G04 ================== begin FILE IDENTIFICATION RECORD ==================*
G04 Layout Name:  12004-1.brd*
G04 Film Name:    12004-1_X_Y*
G04 File Format:  Gerber RS274X*
G04 File Origin:  Cadence Allegro 16.2-S033*
G04 Origin Date:  Tue Oct 16 16:56:28 2012*
G04 *
G04 Layer:  BOARD GEOMETRY/PANEL_DRAWING*
G04 *
G04 Offset:    (0.00 0.00)*
G04 Mirror:    No*
G04 Mode:      Positive*
G04 Rotation:  0*
G04 FullContactRelief:  No*
G04 UndefLineWidth:     6.00*
G04 ================== end FILE IDENTIFICATION RECORD ====================*
%FSLAX35Y35*MOIN*%
%IR0*IPPOS*OFA0.00000B0.00000*MIA0B0*SFA1.00000B1.00000*%
%ADD10C,.006*%
G75*
%LPD*%
G75*
G36*
G01X-1348882Y-1155732D02*
X-1350851Y-1165968D01*
X-1346914D01*
X-1348882Y-1155732D01*
G37*
G36*
G01Y-1143921D02*
X-1346914Y-1133684D01*
X-1350851D01*
X-1348882Y-1143921D01*
G37*
G36*
G01X-1330141Y-1112621D02*
X-1332110Y-1122858D01*
X-1328173D01*
X-1330141Y-1112621D01*
G37*
G36*
G01Y-1104354D02*
X-1328173Y-1094117D01*
X-1332110D01*
X-1330141Y-1104354D01*
G37*
G36*
G01X-1080366Y-1419211D02*
X-1070130Y-1421179D01*
Y-1417242D01*
X-1080366Y-1419211D01*
G37*
G36*
G01X-1047295Y-1022070D02*
X-1057531Y-1020102D01*
Y-1024039D01*
X-1047295Y-1022070D01*
G37*
G36*
G01Y-982700D02*
X-1057531Y-980732D01*
Y-984669D01*
X-1047295Y-982700D01*
G37*
G36*
G01X-981153Y-1419211D02*
X-991390Y-1417242D01*
Y-1421179D01*
X-981153Y-1419211D01*
G37*
G36*
G01X-1047295Y-1061440D02*
X-1037059Y-1063409D01*
Y-1059472D01*
X-1047295Y-1061440D01*
G37*
G36*
G01X-1009500D02*
X-1019736Y-1059472D01*
Y-1063409D01*
X-1009500Y-1061440D01*
G37*
G36*
G01X-997689Y-1022070D02*
X-987453Y-1024039D01*
Y-1020102D01*
X-997689Y-1022070D01*
G37*
G36*
G01X-981153Y-982700D02*
X-970917Y-984669D01*
Y-980732D01*
X-981153Y-982700D01*
G37*
G36*
G01X-1006358Y945315D02*
X-997139Y950181D01*
X-999601Y953253D01*
X-1006358Y945315D01*
G37*
G36*
G01X-917853Y-1208291D02*
X-919822Y-1218527D01*
X-915885D01*
X-917853Y-1208291D01*
G37*
G36*
G01Y-1185850D02*
X-915885Y-1175613D01*
X-919822D01*
X-917853Y-1185850D01*
G37*
G36*
G01X-917453Y-1106716D02*
X-919421Y-1116952D01*
X-915484D01*
X-917453Y-1106716D01*
G37*
G36*
G01Y-1100810D02*
X-915484Y-1090574D01*
X-919421D01*
X-917453Y-1100810D01*
G37*
G36*
G01X-169295Y-428912D02*
X-171263Y-439148D01*
X-167326D01*
X-169295Y-428912D01*
G37*
G36*
G01Y-422612D02*
X-167326Y-412376D01*
X-171263D01*
X-169295Y-422612D01*
G37*
G36*
G01X762840Y-450986D02*
X756406Y-442785D01*
X759339Y-452788D01*
X762840Y-450986D01*
G37*
G36*
G01X753295Y-418509D02*
X753960Y-428912D01*
X757201Y-419004D01*
X753295Y-418509D01*
G37*
G36*
G01X800034Y-399239D02*
X810270Y-401208D01*
Y-397271D01*
X800034Y-399239D01*
G37*
G36*
G01X794522D02*
X784286Y-397271D01*
Y-401208D01*
X794522Y-399239D01*
G37*
G36*
G01X794332Y959250D02*
X803394Y964401D01*
X800838Y967395D01*
X794332Y959250D01*
G37*
G54D10*
G01X-1051232Y-1143921D02*
X-1352819D01*
G01X-1051232Y-1155732D02*
X-1352819D01*
G01X-1348882Y-1143921D02*
Y-1094826D01*
G01D02*
Y-1149826D01*
G01Y-1155732D02*
Y-1175417D01*
G01D02*
Y-1149826D01*
G01X-1051232Y-1104354D02*
X-1334078D01*
G01X-1051232Y-1112621D02*
X-1334078D01*
G01X-1330141Y-1104354D02*
Y-951768D01*
G01D02*
Y-1108487D01*
G01Y-1112621D02*
Y-1132306D01*
G01D02*
Y-1108487D01*
G01X-1351047Y-1122169D02*
X-1361283D01*
X-1359236Y-1123704D01*
G01X-1351047D02*
Y-1120633D01*
G01X-1350706Y-1111933D02*
X-1350876Y-1112188D01*
X-1351218D01*
X-1351388Y-1111933D01*
X-1351218Y-1111677D01*
X-1350876D01*
X-1350706Y-1111933D01*
G01X-1361283Y-1101697D02*
X-1360942Y-1102720D01*
X-1360089Y-1103488D01*
X-1359065Y-1104000D01*
X-1357700Y-1104383D01*
X-1356165Y-1104511D01*
X-1354629Y-1104383D01*
X-1353265Y-1104000D01*
X-1352241Y-1103488D01*
X-1351388Y-1102720D01*
X-1351047Y-1101697D01*
X-1351388Y-1100673D01*
X-1352241Y-1099905D01*
X-1353265Y-1099393D01*
X-1354629Y-1099010D01*
X-1356165Y-1098882D01*
X-1357700Y-1099010D01*
X-1359065Y-1099393D01*
X-1360089Y-1099905D01*
X-1360942Y-1100673D01*
X-1361283Y-1101697D01*
G01Y-1091461D02*
X-1360942Y-1092484D01*
X-1360089Y-1093252D01*
X-1359065Y-1093764D01*
X-1357700Y-1094147D01*
X-1356165Y-1094275D01*
X-1354629Y-1094147D01*
X-1353265Y-1093764D01*
X-1352241Y-1093252D01*
X-1351388Y-1092484D01*
X-1351047Y-1091461D01*
X-1351388Y-1090437D01*
X-1352241Y-1089669D01*
X-1353265Y-1089157D01*
X-1354629Y-1088774D01*
X-1356165Y-1088646D01*
X-1357700Y-1088774D01*
X-1359065Y-1089157D01*
X-1360089Y-1089669D01*
X-1360942Y-1090437D01*
X-1361283Y-1091461D01*
G01X-1342543Y-1020397D02*
X-1342202Y-1021420D01*
X-1341349Y-1022188D01*
X-1340325Y-1022700D01*
X-1338960Y-1023083D01*
X-1337425Y-1023211D01*
X-1335889Y-1023083D01*
X-1334525Y-1022700D01*
X-1333501Y-1022188D01*
X-1332648Y-1021420D01*
X-1332307Y-1020397D01*
X-1332648Y-1019373D01*
X-1333501Y-1018605D01*
X-1334525Y-1018093D01*
X-1335889Y-1017710D01*
X-1337425Y-1017582D01*
X-1338960Y-1017710D01*
X-1340325Y-1018093D01*
X-1341349Y-1018605D01*
X-1342202Y-1019373D01*
X-1342543Y-1020397D01*
G01X-1331966Y-1010161D02*
X-1332136Y-1010416D01*
X-1332478D01*
X-1332648Y-1010161D01*
X-1332478Y-1009905D01*
X-1332136D01*
X-1331966Y-1010161D01*
G01X-1332307Y-1000180D02*
X-1334525Y-999925D01*
X-1336401Y-999541D01*
X-1338107Y-999029D01*
X-1339984Y-998389D01*
X-1342543Y-997365D01*
Y-1002484D01*
G01Y-989689D02*
X-1342202Y-990712D01*
X-1341349Y-991480D01*
X-1340325Y-991992D01*
X-1338960Y-992375D01*
X-1337425Y-992503D01*
X-1335889Y-992375D01*
X-1334525Y-991992D01*
X-1333501Y-991480D01*
X-1332648Y-990712D01*
X-1332307Y-989689D01*
X-1332648Y-988665D01*
X-1333501Y-987897D01*
X-1334525Y-987385D01*
X-1335889Y-987002D01*
X-1337425Y-986874D01*
X-1338960Y-987002D01*
X-1340325Y-987385D01*
X-1341349Y-987897D01*
X-1342202Y-988665D01*
X-1342543Y-989689D01*
G01X-1339131Y-989215D02*
X-1341263Y-990495D01*
X-1342543D01*
Y-989535D01*
X-1341263D01*
Y-990495D01*
G01X-1342543Y-979111D02*
X-1342202Y-980134D01*
X-1341349Y-980902D01*
X-1340325Y-981414D01*
X-1338960Y-981797D01*
X-1337425Y-981925D01*
X-1335889Y-981797D01*
X-1334525Y-981414D01*
X-1333501Y-980902D01*
X-1332648Y-980134D01*
X-1332307Y-979111D01*
X-1332648Y-978087D01*
X-1333501Y-977319D01*
X-1334525Y-976807D01*
X-1335889Y-976424D01*
X-1337425Y-976296D01*
X-1338960Y-976424D01*
X-1340325Y-976807D01*
X-1341349Y-977319D01*
X-1342202Y-978087D01*
X-1342543Y-979111D01*
G01X-1331966Y-968875D02*
X-1332136Y-969130D01*
X-1332478D01*
X-1332648Y-968875D01*
X-1332478Y-968619D01*
X-1332136D01*
X-1331966Y-968875D01*
G01X-1342543Y-958639D02*
X-1342202Y-959662D01*
X-1341349Y-960430D01*
X-1340325Y-960942D01*
X-1338960Y-961325D01*
X-1337425Y-961453D01*
X-1335889Y-961325D01*
X-1334525Y-960942D01*
X-1333501Y-960430D01*
X-1332648Y-959662D01*
X-1332307Y-958639D01*
X-1332648Y-957615D01*
X-1333501Y-956847D01*
X-1334525Y-956335D01*
X-1335889Y-955952D01*
X-1337425Y-955824D01*
X-1338960Y-955952D01*
X-1340325Y-956335D01*
X-1341349Y-956847D01*
X-1342202Y-957615D01*
X-1342543Y-958639D01*
G01X-1333842Y-951217D02*
X-1332989Y-950450D01*
X-1332478Y-949554D01*
X-1332307Y-948403D01*
X-1332648Y-947251D01*
X-1333330Y-946355D01*
X-1334525Y-945716D01*
X-1335889Y-945588D01*
X-1337254Y-945843D01*
X-1338107Y-946483D01*
X-1338790Y-947379D01*
X-1338960Y-948274D01*
X-1338790Y-949170D01*
X-1338107Y-950322D01*
X-1342543Y-949938D01*
Y-946483D01*
G01X-1310240Y-1220348D02*
X-1255750Y-1407924D01*
G01X-1296305Y-1050765D02*
X-1310240Y-1220348D01*
G01X-1216244Y-1008471D02*
X-1296305Y-1050765D01*
G01X-1211325Y-1575443D02*
Y-1565207D01*
X-1208766D01*
X-1207743Y-1565719D01*
X-1206975Y-1566401D01*
X-1206335Y-1567425D01*
X-1205824Y-1568619D01*
X-1205696Y-1570325D01*
X-1205824Y-1572031D01*
X-1206335Y-1573225D01*
X-1206975Y-1574249D01*
X-1207743Y-1574931D01*
X-1208766Y-1575443D01*
X-1211325D01*
G01X-1195715D02*
X-1200834D01*
Y-1565207D01*
X-1195715D01*
G01X-1197763Y-1570154D02*
X-1200834D01*
G01X-1188039Y-1565207D02*
Y-1575443D01*
G01X-1190981Y-1565207D02*
X-1185096D01*
G01X-1181001Y-1575443D02*
X-1177803Y-1565207D01*
X-1174604Y-1575443D01*
G01X-1175755Y-1571861D02*
X-1179850D01*
G01X-1169102Y-1565207D02*
X-1166031D01*
G01X-1167567D02*
Y-1575443D01*
G01X-1169102D02*
X-1166031D01*
G01X-1159890Y-1565207D02*
Y-1575443D01*
X-1154771D01*
G01X-1232142Y-1587070D02*
X-1231119Y-1587923D01*
X-1229967Y-1588435D01*
X-1228944D01*
X-1227920Y-1587923D01*
X-1227152Y-1587070D01*
X-1226769Y-1585876D01*
X-1227024Y-1584682D01*
X-1227664Y-1583658D01*
X-1228816Y-1582976D01*
X-1230351Y-1582635D01*
X-1231247Y-1581952D01*
X-1231631Y-1580758D01*
X-1231375Y-1579564D01*
X-1230735Y-1578711D01*
X-1229839Y-1578199D01*
X-1228944D01*
X-1228048Y-1578540D01*
X-1227280Y-1579393D01*
G01X-1216405Y-1579052D02*
X-1217172Y-1578540D01*
X-1218068Y-1578199D01*
X-1219091D01*
X-1220243Y-1578711D01*
X-1221139Y-1579564D01*
X-1221779Y-1580588D01*
X-1222290Y-1582293D01*
X-1222418Y-1583829D01*
X-1222162Y-1585364D01*
X-1221779Y-1586388D01*
X-1221011Y-1587412D01*
X-1220115Y-1588094D01*
X-1219220Y-1588435D01*
X-1218324D01*
X-1217428Y-1588094D01*
X-1216660Y-1587582D01*
X-1216021Y-1586900D01*
G01X-1212182Y-1588435D02*
X-1208984Y-1578199D01*
X-1205785Y-1588435D01*
G01X-1206936Y-1584853D02*
X-1211031D01*
G01X-1201307Y-1578199D02*
Y-1588435D01*
X-1196188D01*
G01X-1185952D02*
X-1191071D01*
Y-1578199D01*
X-1185952D01*
G01X-1188000Y-1583146D02*
X-1191071D01*
G01X-1193294Y-1586388D02*
X-1192527Y-1587582D01*
X-1191503Y-1588264D01*
X-1190351Y-1588435D01*
X-1189328Y-1588264D01*
X-1188304Y-1587412D01*
X-1187665Y-1586388D01*
X-1187537Y-1585364D01*
X-1187793Y-1584170D01*
X-1188688Y-1583317D01*
X-1189584Y-1582976D01*
X-1190735D01*
G01X-1189584D02*
X-1188816Y-1582464D01*
X-1188176Y-1581611D01*
X-1187920Y-1580588D01*
X-1188176Y-1579564D01*
X-1188816Y-1578711D01*
X-1189968Y-1578199D01*
X-1191119Y-1578370D01*
X-1192271Y-1579052D01*
G01X-1180244Y-1588776D02*
X-1180499Y-1588606D01*
Y-1588264D01*
X-1180244Y-1588094D01*
X-1179988Y-1588264D01*
Y-1588606D01*
X-1180244Y-1588776D01*
G01X-1170008Y-1578199D02*
X-1171031Y-1578540D01*
X-1171799Y-1579393D01*
X-1172311Y-1580417D01*
X-1172694Y-1581782D01*
X-1172822Y-1583317D01*
X-1172694Y-1584853D01*
X-1172311Y-1586217D01*
X-1171799Y-1587241D01*
X-1171031Y-1588094D01*
X-1170008Y-1588435D01*
X-1168984Y-1588094D01*
X-1168216Y-1587241D01*
X-1167704Y-1586217D01*
X-1167321Y-1584853D01*
X-1167193Y-1583317D01*
X-1167321Y-1581782D01*
X-1167704Y-1580417D01*
X-1168216Y-1579393D01*
X-1168984Y-1578540D01*
X-1170008Y-1578199D01*
G01X-1159772D02*
X-1160795Y-1578540D01*
X-1161563Y-1579393D01*
X-1162075Y-1580417D01*
X-1162458Y-1581782D01*
X-1162586Y-1583317D01*
X-1162458Y-1584853D01*
X-1162075Y-1586217D01*
X-1161563Y-1587241D01*
X-1160795Y-1588094D01*
X-1159772Y-1588435D01*
X-1158748Y-1588094D01*
X-1157980Y-1587241D01*
X-1157468Y-1586217D01*
X-1157085Y-1584853D01*
X-1156957Y-1583317D01*
X-1157085Y-1581782D01*
X-1157468Y-1580417D01*
X-1157980Y-1579393D01*
X-1158748Y-1578540D01*
X-1159772Y-1578199D01*
G01X-1149536D02*
X-1150559Y-1578540D01*
X-1151327Y-1579393D01*
X-1151839Y-1580417D01*
X-1152222Y-1581782D01*
X-1152350Y-1583317D01*
X-1152222Y-1584853D01*
X-1151839Y-1586217D01*
X-1151327Y-1587241D01*
X-1150559Y-1588094D01*
X-1149536Y-1588435D01*
X-1148512Y-1588094D01*
X-1147744Y-1587241D01*
X-1147232Y-1586217D01*
X-1146849Y-1584853D01*
X-1146721Y-1583317D01*
X-1146849Y-1581782D01*
X-1147232Y-1580417D01*
X-1147744Y-1579393D01*
X-1148512Y-1578540D01*
X-1149536Y-1578199D01*
G01X-1255750Y-1407924D02*
X-1124984Y-1529477D01*
G01X-1211230Y-1011213D02*
X-1216244Y-1008471D01*
G01X-1200880Y-1017250D02*
X-1206105Y-1014208D01*
G01D02*
X-1211230Y-1011213D01*
G01X-1087453Y-1046053D02*
X-1200880Y-1017250D01*
G01X-1152734Y-1575443D02*
X-1149536Y-1565207D01*
X-1146337Y-1575443D01*
G01X-1147488Y-1571861D02*
X-1151583D01*
G01X-1124984Y-1529477D02*
X-1087453Y-1534176D01*
G01X-1122915Y-32073D02*
X-1122019Y-32926D01*
X-1120995Y-33267D01*
X-1119972Y-32926D01*
X-1119076Y-31902D01*
X-1118436Y-30367D01*
X-1118180Y-28831D01*
Y-26955D01*
X-1118436Y-25420D01*
X-1119076Y-24055D01*
X-1119844Y-23372D01*
X-1120740Y-23031D01*
X-1121763Y-23372D01*
X-1122531Y-24055D01*
X-1123043Y-25078D01*
X-1123299Y-26443D01*
X-1123043Y-27637D01*
X-1122403Y-28831D01*
X-1121635Y-29514D01*
X-1120740Y-29685D01*
X-1119716Y-29343D01*
X-1118948Y-28490D01*
X-1118180Y-26955D01*
G01X-1110504Y-33608D02*
X-1110759Y-33438D01*
Y-33096D01*
X-1110504Y-32926D01*
X-1110248Y-33096D01*
Y-33438D01*
X-1110504Y-33608D01*
G01X-1100268Y-23031D02*
X-1101291Y-23372D01*
X-1102059Y-24225D01*
X-1102571Y-25249D01*
X-1102954Y-26614D01*
X-1103082Y-28149D01*
X-1102954Y-29685D01*
X-1102571Y-31049D01*
X-1102059Y-32073D01*
X-1101291Y-32926D01*
X-1100268Y-33267D01*
X-1099244Y-32926D01*
X-1098476Y-32073D01*
X-1097964Y-31049D01*
X-1097581Y-29685D01*
X-1097453Y-28149D01*
X-1097581Y-26614D01*
X-1097964Y-25249D01*
X-1098476Y-24225D01*
X-1099244Y-23372D01*
X-1100268Y-23031D01*
G01X-1090032D02*
X-1091055Y-23372D01*
X-1091823Y-24225D01*
X-1092335Y-25249D01*
X-1092718Y-26614D01*
X-1092846Y-28149D01*
X-1092718Y-29685D01*
X-1092335Y-31049D01*
X-1091823Y-32073D01*
X-1091055Y-32926D01*
X-1090032Y-33267D01*
X-1089008Y-32926D01*
X-1088240Y-32073D01*
X-1087728Y-31049D01*
X-1087345Y-29685D01*
X-1087217Y-28149D01*
X-1087345Y-26614D01*
X-1087728Y-25249D01*
X-1088240Y-24225D01*
X-1089008Y-23372D01*
X-1090032Y-23031D01*
G01X-1119204Y-13582D02*
Y-3346D01*
X-1123938Y-10682D01*
X-1117541D01*
G01X-1110504Y-13923D02*
X-1110759Y-13753D01*
Y-13411D01*
X-1110504Y-13241D01*
X-1110248Y-13411D01*
Y-13753D01*
X-1110504Y-13923D01*
G01X-1100268Y-3346D02*
X-1101291Y-3687D01*
X-1102059Y-4540D01*
X-1102571Y-5564D01*
X-1102954Y-6929D01*
X-1103082Y-8464D01*
X-1102954Y-10000D01*
X-1102571Y-11364D01*
X-1102059Y-12388D01*
X-1101291Y-13241D01*
X-1100268Y-13582D01*
X-1099244Y-13241D01*
X-1098476Y-12388D01*
X-1097964Y-11364D01*
X-1097581Y-10000D01*
X-1097453Y-8464D01*
X-1097581Y-6929D01*
X-1097964Y-5564D01*
X-1098476Y-4540D01*
X-1099244Y-3687D01*
X-1100268Y-3346D01*
G01X-1090032D02*
X-1091055Y-3687D01*
X-1091823Y-4540D01*
X-1092335Y-5564D01*
X-1092718Y-6929D01*
X-1092846Y-8464D01*
X-1092718Y-10000D01*
X-1092335Y-11364D01*
X-1091823Y-12388D01*
X-1091055Y-13241D01*
X-1090032Y-13582D01*
X-1089008Y-13241D01*
X-1088240Y-12388D01*
X-1087728Y-11364D01*
X-1087345Y-10000D01*
X-1087217Y-8464D01*
X-1087345Y-6929D01*
X-1087728Y-5564D01*
X-1088240Y-4540D01*
X-1089008Y-3687D01*
X-1090032Y-3346D01*
G01X-1120740Y12402D02*
X-1121763Y12061D01*
X-1122531Y11208D01*
X-1123043Y10184D01*
X-1123426Y8819D01*
X-1123554Y7284D01*
X-1123426Y5748D01*
X-1123043Y4384D01*
X-1122531Y3360D01*
X-1121763Y2507D01*
X-1120740Y2166D01*
X-1119716Y2507D01*
X-1118948Y3360D01*
X-1118436Y4384D01*
X-1118053Y5748D01*
X-1117925Y7284D01*
X-1118053Y8819D01*
X-1118436Y10184D01*
X-1118948Y11208D01*
X-1119716Y12061D01*
X-1120740Y12402D01*
G01X-1110504Y1825D02*
X-1110759Y1995D01*
Y2337D01*
X-1110504Y2507D01*
X-1110248Y2337D01*
Y1995D01*
X-1110504Y1825D01*
G01X-1100268Y12402D02*
X-1101291Y12061D01*
X-1102059Y11208D01*
X-1102571Y10184D01*
X-1102954Y8819D01*
X-1103082Y7284D01*
X-1102954Y5748D01*
X-1102571Y4384D01*
X-1102059Y3360D01*
X-1101291Y2507D01*
X-1100268Y2166D01*
X-1099244Y2507D01*
X-1098476Y3360D01*
X-1097964Y4384D01*
X-1097581Y5748D01*
X-1097453Y7284D01*
X-1097581Y8819D01*
X-1097964Y10184D01*
X-1098476Y11208D01*
X-1099244Y12061D01*
X-1100268Y12402D01*
G01X-1090032D02*
X-1091055Y12061D01*
X-1091823Y11208D01*
X-1092335Y10184D01*
X-1092718Y8819D01*
X-1092846Y7284D01*
X-1092718Y5748D01*
X-1092335Y4384D01*
X-1091823Y3360D01*
X-1091055Y2507D01*
X-1090032Y2166D01*
X-1089008Y2507D01*
X-1088240Y3360D01*
X-1087728Y4384D01*
X-1087345Y5748D01*
X-1087217Y7284D01*
X-1087345Y8819D01*
X-1087728Y10184D01*
X-1088240Y11208D01*
X-1089008Y12061D01*
X-1090032Y12402D01*
G01X-1133407Y110499D02*
X-1132639Y111522D01*
X-1131743Y112034D01*
X-1130720Y112205D01*
X-1129440Y111864D01*
X-1128544Y111011D01*
X-1128289Y109987D01*
X-1128416Y108963D01*
X-1128928Y108111D01*
X-1131487Y106405D01*
X-1132639Y105210D01*
X-1133407Y103504D01*
X-1133662Y101969D01*
X-1128289D01*
G01X-1123554Y103504D02*
X-1122787Y102651D01*
X-1121891Y102140D01*
X-1120740Y101969D01*
X-1119588Y102310D01*
X-1118692Y102992D01*
X-1118053Y104187D01*
X-1117925Y105551D01*
X-1118180Y106916D01*
X-1118820Y107769D01*
X-1119716Y108452D01*
X-1120611Y108622D01*
X-1121507Y108452D01*
X-1122659Y107769D01*
X-1122275Y112205D01*
X-1118820D01*
G01X-1110504Y101628D02*
X-1110759Y101798D01*
Y102140D01*
X-1110504Y102310D01*
X-1110248Y102140D01*
Y101798D01*
X-1110504Y101628D01*
G01X-1103082Y104016D02*
X-1102315Y102822D01*
X-1101291Y102140D01*
X-1100139Y101969D01*
X-1099116Y102140D01*
X-1098092Y102992D01*
X-1097453Y104016D01*
X-1097325Y105040D01*
X-1097581Y106234D01*
X-1098476Y107087D01*
X-1099372Y107428D01*
X-1100523D01*
G01X-1099372D02*
X-1098604Y107940D01*
X-1097964Y108793D01*
X-1097708Y109816D01*
X-1097964Y110840D01*
X-1098604Y111693D01*
X-1099756Y112205D01*
X-1100907Y112034D01*
X-1102059Y111352D01*
G01X-1092846Y103504D02*
X-1092079Y102651D01*
X-1091183Y102140D01*
X-1090032Y101969D01*
X-1088880Y102310D01*
X-1087984Y102992D01*
X-1087345Y104187D01*
X-1087217Y105551D01*
X-1087472Y106916D01*
X-1088112Y107769D01*
X-1089008Y108452D01*
X-1089903Y108622D01*
X-1090799Y108452D01*
X-1091951Y107769D01*
X-1091567Y112205D01*
X-1088112D01*
G01X-1141212Y607087D02*
Y617323D01*
X-1142747Y615276D01*
G01Y607087D02*
X-1139676D01*
G01X-1133790Y608622D02*
X-1133023Y607769D01*
X-1132127Y607258D01*
X-1130976Y607087D01*
X-1129824Y607428D01*
X-1128928Y608110D01*
X-1128289Y609305D01*
X-1128161Y610669D01*
X-1128416Y612034D01*
X-1129056Y612887D01*
X-1129952Y613570D01*
X-1130847Y613740D01*
X-1131743Y613570D01*
X-1132895Y612887D01*
X-1132511Y617323D01*
X-1129056D01*
G01X-1123554Y609134D02*
X-1122787Y607940D01*
X-1121763Y607258D01*
X-1120611Y607087D01*
X-1119588Y607258D01*
X-1118564Y608110D01*
X-1117925Y609134D01*
X-1117797Y610158D01*
X-1118053Y611352D01*
X-1118948Y612205D01*
X-1119844Y612546D01*
X-1120995D01*
G01X-1119844D02*
X-1119076Y613058D01*
X-1118436Y613911D01*
X-1118180Y614934D01*
X-1118436Y615958D01*
X-1119076Y616811D01*
X-1120228Y617323D01*
X-1121379Y617152D01*
X-1122531Y616470D01*
G01X-1110504Y606746D02*
X-1110759Y606916D01*
Y607258D01*
X-1110504Y607428D01*
X-1110248Y607258D01*
Y606916D01*
X-1110504Y606746D01*
G01X-1102699Y611352D02*
X-1101803Y612546D01*
X-1101035Y613229D01*
X-1100012Y613570D01*
X-1099116Y613229D01*
X-1098476Y612546D01*
X-1097964Y611523D01*
X-1097836Y610328D01*
X-1097964Y609305D01*
X-1098476Y608281D01*
X-1099244Y607428D01*
X-1100139Y607087D01*
X-1101163Y607428D01*
X-1102059Y608452D01*
X-1102571Y609987D01*
X-1102699Y611693D01*
X-1102443Y613911D01*
X-1102059Y615105D01*
X-1101419Y616299D01*
X-1100523Y617152D01*
X-1099628Y617323D01*
X-1098732Y616982D01*
X-1098092Y616129D01*
G01X-1092846Y608622D02*
X-1092079Y607769D01*
X-1091183Y607258D01*
X-1090032Y607087D01*
X-1088880Y607428D01*
X-1087984Y608110D01*
X-1087345Y609305D01*
X-1087217Y610669D01*
X-1087472Y612034D01*
X-1088112Y612887D01*
X-1089008Y613570D01*
X-1089903Y613740D01*
X-1090799Y613570D01*
X-1091951Y612887D01*
X-1091567Y617323D01*
X-1088112D01*
G01X-1143643Y971326D02*
X-1142875Y972349D01*
X-1141979Y972861D01*
X-1140956Y973032D01*
X-1139676Y972691D01*
X-1138780Y971838D01*
X-1138525Y970814D01*
X-1138652Y969790D01*
X-1139164Y968938D01*
X-1141723Y967232D01*
X-1142875Y966037D01*
X-1143643Y964331D01*
X-1143898Y962796D01*
X-1138525D01*
G01X-1129440D02*
Y973032D01*
X-1134174Y965696D01*
X-1127777D01*
G01X-1119204Y962796D02*
Y973032D01*
X-1123938Y965696D01*
X-1117541D01*
G01X-1110504Y962455D02*
X-1110759Y962625D01*
Y962967D01*
X-1110504Y963137D01*
X-1110248Y962967D01*
Y962625D01*
X-1110504Y962455D01*
G01X-1100268Y973032D02*
X-1101291Y972691D01*
X-1102059Y971838D01*
X-1102571Y970814D01*
X-1102954Y969449D01*
X-1103082Y967914D01*
X-1102954Y966378D01*
X-1102571Y965014D01*
X-1102059Y963990D01*
X-1101291Y963137D01*
X-1100268Y962796D01*
X-1099244Y963137D01*
X-1098476Y963990D01*
X-1097964Y965014D01*
X-1097581Y966378D01*
X-1097453Y967914D01*
X-1097581Y969449D01*
X-1097964Y970814D01*
X-1098476Y971838D01*
X-1099244Y972691D01*
X-1100268Y973032D01*
G01X-1090032D02*
X-1091055Y972691D01*
X-1091823Y971838D01*
X-1092335Y970814D01*
X-1092718Y969449D01*
X-1092846Y967914D01*
X-1092718Y966378D01*
X-1092335Y965014D01*
X-1091823Y963990D01*
X-1091055Y963137D01*
X-1090032Y962796D01*
X-1089008Y963137D01*
X-1088240Y963990D01*
X-1087728Y965014D01*
X-1087345Y966378D01*
X-1087217Y967914D01*
X-1087345Y969449D01*
X-1087728Y970814D01*
X-1088240Y971838D01*
X-1089008Y972691D01*
X-1090032Y973032D01*
G01X-1143643Y951641D02*
X-1142875Y952664D01*
X-1141979Y953176D01*
X-1140956Y953347D01*
X-1139676Y953006D01*
X-1138780Y952153D01*
X-1138525Y951129D01*
X-1138652Y950105D01*
X-1139164Y949253D01*
X-1141723Y947547D01*
X-1142875Y946352D01*
X-1143643Y944646D01*
X-1143898Y943111D01*
X-1138525D01*
G01X-1133790Y945158D02*
X-1133023Y943964D01*
X-1131999Y943282D01*
X-1130847Y943111D01*
X-1129824Y943282D01*
X-1128800Y944134D01*
X-1128161Y945158D01*
X-1128033Y946182D01*
X-1128289Y947376D01*
X-1129184Y948229D01*
X-1130080Y948570D01*
X-1131231D01*
G01X-1130080D02*
X-1129312Y949082D01*
X-1128672Y949935D01*
X-1128416Y950958D01*
X-1128672Y951982D01*
X-1129312Y952835D01*
X-1130464Y953347D01*
X-1131615Y953176D01*
X-1132767Y952494D01*
G01X-1122915Y944305D02*
X-1122019Y943452D01*
X-1120995Y943111D01*
X-1119972Y943452D01*
X-1119076Y944476D01*
X-1118436Y946011D01*
X-1118180Y947547D01*
Y949423D01*
X-1118436Y950958D01*
X-1119076Y952323D01*
X-1119844Y953006D01*
X-1120740Y953347D01*
X-1121763Y953006D01*
X-1122531Y952323D01*
X-1123043Y951300D01*
X-1123299Y949935D01*
X-1123043Y948741D01*
X-1122403Y947547D01*
X-1121635Y946864D01*
X-1120740Y946693D01*
X-1119716Y947035D01*
X-1118948Y947888D01*
X-1118180Y949423D01*
G01X-1110504Y942770D02*
X-1110759Y942940D01*
Y943282D01*
X-1110504Y943452D01*
X-1110248Y943282D01*
Y942940D01*
X-1110504Y942770D01*
G01X-1100268Y953347D02*
X-1101291Y953006D01*
X-1102059Y952153D01*
X-1102571Y951129D01*
X-1102954Y949764D01*
X-1103082Y948229D01*
X-1102954Y946693D01*
X-1102571Y945329D01*
X-1102059Y944305D01*
X-1101291Y943452D01*
X-1100268Y943111D01*
X-1099244Y943452D01*
X-1098476Y944305D01*
X-1097964Y945329D01*
X-1097581Y946693D01*
X-1097453Y948229D01*
X-1097581Y949764D01*
X-1097964Y951129D01*
X-1098476Y952153D01*
X-1099244Y953006D01*
X-1100268Y953347D01*
G01X-1090032D02*
X-1091055Y953006D01*
X-1091823Y952153D01*
X-1092335Y951129D01*
X-1092718Y949764D01*
X-1092846Y948229D01*
X-1092718Y946693D01*
X-1092335Y945329D01*
X-1091823Y944305D01*
X-1091055Y943452D01*
X-1090032Y943111D01*
X-1089008Y943452D01*
X-1088240Y944305D01*
X-1087728Y945329D01*
X-1087345Y946693D01*
X-1087217Y948229D01*
X-1087345Y949764D01*
X-1087728Y951129D01*
X-1088240Y952153D01*
X-1089008Y953006D01*
X-1090032Y953347D01*
G01X-1143643Y935893D02*
X-1142875Y936916D01*
X-1141979Y937428D01*
X-1140956Y937599D01*
X-1139676Y937258D01*
X-1138780Y936405D01*
X-1138525Y935381D01*
X-1138652Y934357D01*
X-1139164Y933505D01*
X-1141723Y931799D01*
X-1142875Y930604D01*
X-1143643Y928898D01*
X-1143898Y927363D01*
X-1138525D01*
G01X-1133790Y929410D02*
X-1133023Y928216D01*
X-1131999Y927534D01*
X-1130847Y927363D01*
X-1129824Y927534D01*
X-1128800Y928386D01*
X-1128161Y929410D01*
X-1128033Y930434D01*
X-1128289Y931628D01*
X-1129184Y932481D01*
X-1130080Y932822D01*
X-1131231D01*
G01X-1130080D02*
X-1129312Y933334D01*
X-1128672Y934187D01*
X-1128416Y935210D01*
X-1128672Y936234D01*
X-1129312Y937087D01*
X-1130464Y937599D01*
X-1131615Y937428D01*
X-1132767Y936746D01*
G01X-1123554Y928898D02*
X-1122787Y928045D01*
X-1121891Y927534D01*
X-1120740Y927363D01*
X-1119588Y927704D01*
X-1118692Y928386D01*
X-1118053Y929581D01*
X-1117925Y930945D01*
X-1118180Y932310D01*
X-1118820Y933163D01*
X-1119716Y933846D01*
X-1120611Y934016D01*
X-1121507Y933846D01*
X-1122659Y933163D01*
X-1122275Y937599D01*
X-1118820D01*
G01X-1110504Y927022D02*
X-1110759Y927192D01*
Y927534D01*
X-1110504Y927704D01*
X-1110248Y927534D01*
Y927192D01*
X-1110504Y927022D01*
G01X-1100268Y937599D02*
X-1101291Y937258D01*
X-1102059Y936405D01*
X-1102571Y935381D01*
X-1102954Y934016D01*
X-1103082Y932481D01*
X-1102954Y930945D01*
X-1102571Y929581D01*
X-1102059Y928557D01*
X-1101291Y927704D01*
X-1100268Y927363D01*
X-1099244Y927704D01*
X-1098476Y928557D01*
X-1097964Y929581D01*
X-1097581Y930945D01*
X-1097453Y932481D01*
X-1097581Y934016D01*
X-1097964Y935381D01*
X-1098476Y936405D01*
X-1099244Y937258D01*
X-1100268Y937599D01*
G01X-1090032D02*
X-1091055Y937258D01*
X-1091823Y936405D01*
X-1092335Y935381D01*
X-1092718Y934016D01*
X-1092846Y932481D01*
X-1092718Y930945D01*
X-1092335Y929581D01*
X-1091823Y928557D01*
X-1091055Y927704D01*
X-1090032Y927363D01*
X-1089008Y927704D01*
X-1088240Y928557D01*
X-1087728Y929581D01*
X-1087345Y930945D01*
X-1087217Y932481D01*
X-1087345Y934016D01*
X-1087728Y935381D01*
X-1088240Y936405D01*
X-1089008Y937258D01*
X-1090032Y937599D01*
G01X-1087453Y-1534176D02*
Y-1046053D01*
G01X-1080366Y-1201007D02*
Y-1423148D01*
G01Y-1419211D02*
X-1030760D01*
G01X-1046115Y-1417045D02*
X-1045219Y-1416874D01*
X-1044195Y-1416363D01*
X-1043555Y-1415510D01*
X-1043300Y-1414315D01*
X-1043555Y-1413121D01*
X-1044323Y-1412098D01*
X-1045475Y-1411586D01*
X-1046754D01*
X-1047522Y-1411245D01*
X-1048162Y-1410392D01*
X-1048418Y-1409198D01*
X-1048034Y-1408003D01*
X-1047138Y-1407150D01*
X-1046115Y-1406809D01*
X-1045091Y-1407150D01*
X-1044195Y-1408003D01*
X-1043811Y-1409198D01*
X-1044067Y-1410392D01*
X-1044707Y-1411245D01*
X-1045475Y-1411586D01*
X-1046754D01*
X-1047906Y-1412098D01*
X-1048674Y-1413121D01*
X-1048929Y-1414315D01*
X-1048674Y-1415510D01*
X-1048034Y-1416363D01*
X-1047010Y-1416874D01*
X-1046115Y-1417045D01*
G01X-1035879Y-1417386D02*
X-1036134Y-1417216D01*
Y-1416874D01*
X-1035879Y-1416704D01*
X-1035623Y-1416874D01*
Y-1417216D01*
X-1035879Y-1417386D01*
G01X-1024107Y-1417045D02*
Y-1406809D01*
X-1028841Y-1414145D01*
X-1022444D01*
G01X-1015407Y-1406809D02*
X-1016430Y-1407150D01*
X-1017198Y-1408003D01*
X-1017710Y-1409027D01*
X-1018093Y-1410392D01*
X-1018221Y-1411927D01*
X-1018093Y-1413463D01*
X-1017710Y-1414827D01*
X-1017198Y-1415851D01*
X-1016430Y-1416704D01*
X-1015407Y-1417045D01*
X-1014383Y-1416704D01*
X-1013615Y-1415851D01*
X-1013103Y-1414827D01*
X-1012720Y-1413463D01*
X-1012592Y-1411927D01*
X-1012720Y-1410392D01*
X-1013103Y-1409027D01*
X-1013615Y-1408003D01*
X-1014383Y-1407150D01*
X-1015407Y-1406809D01*
G01X-1075642Y-1340574D02*
G03X-1087453Y-1352385I0J-11811D01*
G01X-987059Y-1340574D02*
X-1075642D01*
G01X-987059Y-1208291D02*
X-1069146D01*
G01Y-1185850D02*
G03Y-1208291I0J-11221D01*
G01X-987059Y-1185850D02*
X-1069146D01*
G01X-987059Y-1100810D02*
X-1075642D01*
G01X-1087453Y-1088999D02*
G03X-1075642Y-1100810I11811J0D01*
G01X-1047295Y-1022070D02*
X-1066980D01*
G01D02*
X-1022492D01*
G01X-1047295Y-982700D02*
X-1066980D01*
G01D02*
X-1014224D01*
G01X-1031496Y-35433D02*
X-1081862D01*
G01X-1015748Y-15748D02*
X-1081862D01*
G01X0Y0D02*
X-1081862D01*
G01X-1031496Y99803D02*
X-1081862D01*
G01X-1031496Y604922D02*
X-1081862D01*
G01X-1031496Y960630D02*
X-1081862D01*
G01X-1015748Y940945D02*
X-1081862D01*
G01X-996063Y925197D02*
X-1081862D01*
G01X-981153Y-1338606D02*
Y-1423148D01*
G01Y-1419211D02*
X-1030760D01*
G01X-997689Y-1337031D02*
X-1047295D01*
G01Y-1328763D02*
X-997689D01*
G01Y-1325220D02*
X-1047295D01*
G01Y-1316952D02*
X-997689D01*
G01Y-1313409D02*
X-1047295D01*
G01Y-1305141D02*
X-997689D01*
G01Y-1301598D02*
X-1047295D01*
G01Y-1293330D02*
X-997689D01*
G01Y-1289787D02*
X-1047295D01*
G01Y-1281519D02*
X-997689D01*
G01Y-1277976D02*
X-1047295D01*
G01Y-1337031D02*
Y-1328763D01*
G01Y-1325220D02*
Y-1316952D01*
G01Y-1313409D02*
Y-1305141D01*
G01Y-1301598D02*
Y-1293330D01*
G01Y-1289787D02*
Y-1281519D01*
G01Y-1277976D02*
Y-1269708D01*
G01X-997689Y-1277976D02*
Y-1281519D01*
G01Y-1289787D02*
Y-1293330D01*
G01Y-1301598D02*
Y-1305141D01*
G01Y-1313409D02*
Y-1316952D01*
G01Y-1325220D02*
Y-1328763D01*
G01Y-1337031D02*
Y-1340574D01*
G01Y-1269708D02*
Y-1277976D01*
G01Y-1281519D02*
Y-1289787D01*
G01Y-1293330D02*
Y-1301598D01*
G01Y-1305141D02*
Y-1313409D01*
G01Y-1316952D02*
Y-1325220D01*
G01Y-1328763D02*
Y-1337031D01*
G01X-981153Y-1214196D02*
Y-1334669D01*
G01X-987059Y-1340574D02*
X-981153Y-1334669D01*
G01X-1047295Y-1269708D02*
X-997689D01*
G01Y-1266165D02*
X-1047295D01*
G01Y-1257897D02*
X-997689D01*
G01Y-1254354D02*
X-1047295D01*
G01Y-1246086D02*
X-997689D01*
G01Y-1242543D02*
X-1047295D01*
G01Y-1234275D02*
X-997689D01*
G01Y-1230732D02*
X-1047295D01*
G01Y-1222464D02*
X-997689D01*
G01Y-1218921D02*
X-1047295D01*
G01Y-1210653D02*
X-997689D01*
G01X-1047295Y-1266165D02*
Y-1257897D01*
G01Y-1254354D02*
Y-1246086D01*
G01Y-1242543D02*
Y-1234275D01*
G01Y-1230732D02*
Y-1222464D01*
G01Y-1218921D02*
Y-1210653D01*
G01X-997689Y-1208291D02*
Y-1210653D01*
G01Y-1218921D02*
Y-1222464D01*
G01Y-1230732D02*
Y-1234275D01*
G01Y-1242543D02*
Y-1246086D01*
G01Y-1254354D02*
Y-1257897D01*
G01Y-1266165D02*
Y-1269708D01*
G01Y-1210653D02*
Y-1218921D01*
G01Y-1222464D02*
Y-1230732D01*
G01Y-1234275D02*
Y-1242543D01*
G01Y-1246086D02*
Y-1254354D01*
G01Y-1257897D02*
Y-1266165D01*
G01X-981153Y-1214196D02*
X-987059Y-1208291D01*
G01X-993752D02*
X-913916D01*
G01X-987059Y-1185850D02*
X-981153Y-1179944D01*
G01X-1047295Y-1183487D02*
Y-1175220D01*
G01Y-1171676D02*
Y-1163409D01*
G01Y-1159865D02*
Y-1151598D01*
G01Y-1148054D02*
Y-1139787D01*
G01Y-1136243D02*
Y-1127976D01*
G01X-997689Y-1183487D02*
X-1047295D01*
G01Y-1175220D02*
X-997689D01*
G01Y-1171676D02*
X-1047295D01*
G01Y-1163409D02*
X-997689D01*
G01Y-1159865D02*
X-1047295D01*
G01Y-1151598D02*
X-997689D01*
G01Y-1136243D02*
Y-1139787D01*
G01Y-1148054D02*
Y-1151598D01*
G01Y-1159865D02*
Y-1163409D01*
G01Y-1171676D02*
Y-1175220D01*
G01Y-1183487D02*
Y-1185850D01*
G01Y-1127976D02*
Y-1136243D01*
G01Y-1139787D02*
Y-1148054D01*
G01Y-1151598D02*
Y-1159865D01*
G01Y-1163409D02*
Y-1171676D01*
G01Y-1175220D02*
Y-1183487D01*
G01Y-1148054D02*
X-1047295D01*
G01Y-1139787D02*
X-997689D01*
G01Y-1136243D02*
X-1047295D01*
G01X-981153Y-1106716D02*
Y-1179944D01*
G01X-993752Y-1185850D02*
X-913916D01*
G01X-1047295Y-1124432D02*
Y-1116165D01*
G01Y-1112621D02*
Y-1104354D01*
G01X-1009500Y-1116165D02*
Y-1124432D01*
G01X-997689Y-1100810D02*
Y-1104354D01*
G01Y-1112621D02*
Y-1127976D01*
G01Y-1104354D02*
Y-1112621D01*
G01X-1047295Y-1127976D02*
X-997689D01*
G01X-1009500Y-1124432D02*
X-1047295D01*
G01Y-1116165D02*
X-1009500D01*
G01X-997689Y-1112621D02*
X-1047295D01*
G01Y-1104354D02*
X-997689D01*
G01X-981153Y-1106716D02*
X-987059Y-1100810D01*
G01X-997689Y-1096873D02*
Y-1018133D01*
G01X-1047295Y-1100417D02*
Y-1018133D01*
G01X-1009500Y-1112228D02*
Y-1057503D01*
G01X-1047295Y-1112228D02*
Y-1057503D01*
G01X-981153Y-1102779D02*
Y-978763D01*
G01X-1047295Y-1100417D02*
Y-978763D01*
G01X-983122Y-1100810D02*
X-913516D01*
G01X-997689Y-1022070D02*
X-978004D01*
G01D02*
X-1022492D01*
G01X-1009500Y-1061440D02*
X-1028397D01*
G01D02*
X-943436D01*
G01X-1047295D02*
X-1028397D01*
G01X-1036311Y-1019905D02*
Y-1009669D01*
X-1041045Y-1017005D01*
X-1034648D01*
G01X-1027611Y-1020246D02*
X-1027866Y-1020076D01*
Y-1019734D01*
X-1027611Y-1019564D01*
X-1027355Y-1019734D01*
Y-1020076D01*
X-1027611Y-1020246D01*
G01X-1019806Y-1011375D02*
X-1019038Y-1010352D01*
X-1018142Y-1009840D01*
X-1017119Y-1009669D01*
X-1015839Y-1010010D01*
X-1014943Y-1010863D01*
X-1014688Y-1011887D01*
X-1014815Y-1012911D01*
X-1015327Y-1013763D01*
X-1017886Y-1015469D01*
X-1019038Y-1016664D01*
X-1019806Y-1018370D01*
X-1020061Y-1019905D01*
X-1014688D01*
G01X-1007139Y-1009669D02*
X-1008162Y-1010010D01*
X-1008930Y-1010863D01*
X-1009442Y-1011887D01*
X-1009825Y-1013252D01*
X-1009953Y-1014787D01*
X-1009825Y-1016323D01*
X-1009442Y-1017687D01*
X-1008930Y-1018711D01*
X-1008162Y-1019564D01*
X-1007139Y-1019905D01*
X-1006115Y-1019564D01*
X-1005347Y-1018711D01*
X-1004835Y-1017687D01*
X-1004452Y-1016323D01*
X-1004324Y-1014787D01*
X-1004452Y-1013252D01*
X-1004835Y-1011887D01*
X-1005347Y-1010863D01*
X-1006115Y-1010010D01*
X-1007139Y-1009669D01*
G01X-981153Y-982700D02*
X-961468D01*
G01D02*
X-1014224D01*
G01X-1032393Y-979000D02*
X-1031626Y-979853D01*
X-1030730Y-980364D01*
X-1029579Y-980535D01*
X-1028427Y-980194D01*
X-1027531Y-979512D01*
X-1026892Y-978317D01*
X-1026764Y-976953D01*
X-1027019Y-975588D01*
X-1027659Y-974735D01*
X-1028555Y-974052D01*
X-1029450Y-973882D01*
X-1030346Y-974052D01*
X-1031498Y-974735D01*
X-1031114Y-970299D01*
X-1027659D01*
G01X-1019343Y-980876D02*
X-1019598Y-980706D01*
Y-980364D01*
X-1019343Y-980194D01*
X-1019087Y-980364D01*
Y-980706D01*
X-1019343Y-980876D01*
G01X-1011538Y-976270D02*
X-1010642Y-975076D01*
X-1009874Y-974393D01*
X-1008851Y-974052D01*
X-1007955Y-974393D01*
X-1007315Y-975076D01*
X-1006803Y-976099D01*
X-1006675Y-977294D01*
X-1006803Y-978317D01*
X-1007315Y-979341D01*
X-1008083Y-980194D01*
X-1008978Y-980535D01*
X-1010002Y-980194D01*
X-1010898Y-979170D01*
X-1011410Y-977635D01*
X-1011538Y-975929D01*
X-1011282Y-973711D01*
X-1010898Y-972517D01*
X-1010258Y-971323D01*
X-1009362Y-970470D01*
X-1008467Y-970299D01*
X-1007571Y-970640D01*
X-1006931Y-971493D01*
G01X-998871Y-970299D02*
X-999894Y-970640D01*
X-1000662Y-971493D01*
X-1001174Y-972517D01*
X-1001557Y-973882D01*
X-1001685Y-975417D01*
X-1001557Y-976953D01*
X-1001174Y-978317D01*
X-1000662Y-979341D01*
X-999894Y-980194D01*
X-998871Y-980535D01*
X-997847Y-980194D01*
X-997079Y-979341D01*
X-996567Y-978317D01*
X-996184Y-976953D01*
X-996056Y-975417D01*
X-996184Y-973882D01*
X-996567Y-972517D01*
X-997079Y-971493D01*
X-997847Y-970640D01*
X-998871Y-970299D01*
G01X-1006759Y-214280D02*
X-1007782Y-213512D01*
X-1008294Y-212616D01*
X-1008465Y-211593D01*
X-1008124Y-210313D01*
X-1007271Y-209417D01*
X-1006247Y-209162D01*
X-1005223Y-209289D01*
X-1004371Y-209801D01*
X-1002665Y-212360D01*
X-1001470Y-213512D01*
X-999764Y-214280D01*
X-998229Y-214535D01*
Y-209162D01*
G01X-999764Y-204427D02*
X-998911Y-203660D01*
X-998400Y-202764D01*
X-998229Y-201613D01*
X-998570Y-200461D01*
X-999252Y-199565D01*
X-1000447Y-198926D01*
X-1001811Y-198798D01*
X-1003176Y-199053D01*
X-1004029Y-199693D01*
X-1004712Y-200589D01*
X-1004882Y-201484D01*
X-1004712Y-202380D01*
X-1004029Y-203532D01*
X-1008465Y-203148D01*
Y-199693D01*
G01X-1000276Y-194191D02*
X-999082Y-193424D01*
X-998400Y-192400D01*
X-998229Y-191248D01*
X-998400Y-190225D01*
X-999252Y-189201D01*
X-1000276Y-188562D01*
X-1001300Y-188434D01*
X-1002494Y-188690D01*
X-1003347Y-189585D01*
X-1003688Y-190481D01*
Y-191632D01*
G01Y-190481D02*
X-1004200Y-189713D01*
X-1005053Y-189073D01*
X-1006076Y-188817D01*
X-1007100Y-189073D01*
X-1007953Y-189713D01*
X-1008465Y-190865D01*
X-1008294Y-192016D01*
X-1007612Y-193168D01*
G01X-997888Y-181141D02*
X-998058Y-181396D01*
X-998400D01*
X-998570Y-181141D01*
X-998400Y-180885D01*
X-998058D01*
X-997888Y-181141D01*
G01X-1008465Y-170905D02*
X-1008124Y-171928D01*
X-1007271Y-172696D01*
X-1006247Y-173208D01*
X-1004882Y-173591D01*
X-1003347Y-173719D01*
X-1001811Y-173591D01*
X-1000447Y-173208D01*
X-999423Y-172696D01*
X-998570Y-171928D01*
X-998229Y-170905D01*
X-998570Y-169881D01*
X-999423Y-169113D01*
X-1000447Y-168601D01*
X-1001811Y-168218D01*
X-1003347Y-168090D01*
X-1004882Y-168218D01*
X-1006247Y-168601D01*
X-1007271Y-169113D01*
X-1008124Y-169881D01*
X-1008465Y-170905D01*
G01Y-160669D02*
X-1008124Y-161692D01*
X-1007271Y-162460D01*
X-1006247Y-162972D01*
X-1004882Y-163355D01*
X-1003347Y-163483D01*
X-1001811Y-163355D01*
X-1000447Y-162972D01*
X-999423Y-162460D01*
X-998570Y-161692D01*
X-998229Y-160669D01*
X-998570Y-159645D01*
X-999423Y-158877D01*
X-1000447Y-158365D01*
X-1001811Y-157982D01*
X-1003347Y-157854D01*
X-1004882Y-157982D01*
X-1006247Y-158365D01*
X-1007271Y-158877D01*
X-1008124Y-159645D01*
X-1008465Y-160669D01*
G01X-1022507Y-214280D02*
X-1023530Y-213512D01*
X-1024042Y-212616D01*
X-1024213Y-211593D01*
X-1023872Y-210313D01*
X-1023019Y-209417D01*
X-1021995Y-209162D01*
X-1020971Y-209289D01*
X-1020119Y-209801D01*
X-1018413Y-212360D01*
X-1017218Y-213512D01*
X-1015512Y-214280D01*
X-1013977Y-214535D01*
Y-209162D01*
G01X-1015512Y-204427D02*
X-1014659Y-203660D01*
X-1014148Y-202764D01*
X-1013977Y-201613D01*
X-1014318Y-200461D01*
X-1015000Y-199565D01*
X-1016195Y-198926D01*
X-1017559Y-198798D01*
X-1018924Y-199053D01*
X-1019777Y-199693D01*
X-1020460Y-200589D01*
X-1020630Y-201484D01*
X-1020460Y-202380D01*
X-1019777Y-203532D01*
X-1024213Y-203148D01*
Y-199693D01*
G01X-1013977Y-191632D02*
X-1016195Y-191377D01*
X-1018071Y-190993D01*
X-1019777Y-190481D01*
X-1021654Y-189841D01*
X-1024213Y-188817D01*
Y-193936D01*
G01X-1013636Y-181141D02*
X-1013806Y-181396D01*
X-1014148D01*
X-1014318Y-181141D01*
X-1014148Y-180885D01*
X-1013806D01*
X-1013636Y-181141D01*
G01X-1024213Y-170905D02*
X-1023872Y-171928D01*
X-1023019Y-172696D01*
X-1021995Y-173208D01*
X-1020630Y-173591D01*
X-1019095Y-173719D01*
X-1017559Y-173591D01*
X-1016195Y-173208D01*
X-1015171Y-172696D01*
X-1014318Y-171928D01*
X-1013977Y-170905D01*
X-1014318Y-169881D01*
X-1015171Y-169113D01*
X-1016195Y-168601D01*
X-1017559Y-168218D01*
X-1019095Y-168090D01*
X-1020630Y-168218D01*
X-1021995Y-168601D01*
X-1023019Y-169113D01*
X-1023872Y-169881D01*
X-1024213Y-170905D01*
G01Y-160669D02*
X-1023872Y-161692D01*
X-1023019Y-162460D01*
X-1021995Y-162972D01*
X-1020630Y-163355D01*
X-1019095Y-163483D01*
X-1017559Y-163355D01*
X-1016195Y-162972D01*
X-1015171Y-162460D01*
X-1014318Y-161692D01*
X-1013977Y-160669D01*
X-1014318Y-159645D01*
X-1015171Y-158877D01*
X-1016195Y-158365D01*
X-1017559Y-157982D01*
X-1019095Y-157854D01*
X-1020630Y-157982D01*
X-1021995Y-158365D01*
X-1023019Y-158877D01*
X-1023872Y-159645D01*
X-1024213Y-160669D01*
G01X-1042192Y-214280D02*
X-1043215Y-213512D01*
X-1043727Y-212616D01*
X-1043898Y-211593D01*
X-1043557Y-210313D01*
X-1042704Y-209417D01*
X-1041680Y-209162D01*
X-1040656Y-209289D01*
X-1039804Y-209801D01*
X-1038098Y-212360D01*
X-1036903Y-213512D01*
X-1035197Y-214280D01*
X-1033662Y-214535D01*
Y-209162D01*
G01X-1037927Y-204044D02*
X-1039121Y-203148D01*
X-1039804Y-202380D01*
X-1040145Y-201357D01*
X-1039804Y-200461D01*
X-1039121Y-199821D01*
X-1038098Y-199309D01*
X-1036903Y-199181D01*
X-1035880Y-199309D01*
X-1034856Y-199821D01*
X-1034003Y-200589D01*
X-1033662Y-201484D01*
X-1034003Y-202508D01*
X-1035027Y-203404D01*
X-1036562Y-203916D01*
X-1038268Y-204044D01*
X-1040486Y-203788D01*
X-1041680Y-203404D01*
X-1042874Y-202764D01*
X-1043727Y-201868D01*
X-1043898Y-200973D01*
X-1043557Y-200077D01*
X-1042704Y-199437D01*
G01X-1042192Y-193808D02*
X-1043215Y-193040D01*
X-1043727Y-192144D01*
X-1043898Y-191121D01*
X-1043557Y-189841D01*
X-1042704Y-188945D01*
X-1041680Y-188690D01*
X-1040656Y-188817D01*
X-1039804Y-189329D01*
X-1038098Y-191888D01*
X-1036903Y-193040D01*
X-1035197Y-193808D01*
X-1033662Y-194063D01*
Y-188690D01*
G01X-1033321Y-181141D02*
X-1033491Y-181396D01*
X-1033833D01*
X-1034003Y-181141D01*
X-1033833Y-180885D01*
X-1033491D01*
X-1033321Y-181141D01*
G01X-1043898Y-170905D02*
X-1043557Y-171928D01*
X-1042704Y-172696D01*
X-1041680Y-173208D01*
X-1040315Y-173591D01*
X-1038780Y-173719D01*
X-1037244Y-173591D01*
X-1035880Y-173208D01*
X-1034856Y-172696D01*
X-1034003Y-171928D01*
X-1033662Y-170905D01*
X-1034003Y-169881D01*
X-1034856Y-169113D01*
X-1035880Y-168601D01*
X-1037244Y-168218D01*
X-1038780Y-168090D01*
X-1040315Y-168218D01*
X-1041680Y-168601D01*
X-1042704Y-169113D01*
X-1043557Y-169881D01*
X-1043898Y-170905D01*
G01Y-160669D02*
X-1043557Y-161692D01*
X-1042704Y-162460D01*
X-1041680Y-162972D01*
X-1040315Y-163355D01*
X-1038780Y-163483D01*
X-1037244Y-163355D01*
X-1035880Y-162972D01*
X-1034856Y-162460D01*
X-1034003Y-161692D01*
X-1033662Y-160669D01*
X-1034003Y-159645D01*
X-1034856Y-158877D01*
X-1035880Y-158365D01*
X-1037244Y-157982D01*
X-1038780Y-157854D01*
X-1040315Y-157982D01*
X-1041680Y-158365D01*
X-1042704Y-158877D01*
X-1043557Y-159645D01*
X-1043898Y-160669D01*
G01X-996063Y597048D02*
Y-152499D01*
G01X-1011811Y-19685D02*
Y-152499D01*
G01X-1031496Y-35433D02*
Y-152499D01*
G01X-1003937Y-3937D02*
G03X-1000000Y-7874I3937J0D01*
G01X-1031496Y-31496D02*
G03X-1027559Y-35433I3937J0D01*
G01X-986221Y-7874D02*
G03Y0I0J3937D01*
G01X-1004823Y-15748D02*
G03I-6988J0D01*
G01X-986221Y-7874D02*
X-1000000D01*
G01X-1027559Y-35433D02*
X791338D01*
G01X-1031496Y95866D02*
Y-31496D01*
G01X-996063Y3937D02*
G03X-992126Y0I3937J0D01*
G01X-996063Y39370D02*
G03X-1003937I-3937J0D01*
G01X-996063Y3937D02*
G03X-992126Y0I3937J0D01*
G01X-996063Y9843D02*
X-437008D01*
G01X-992126Y0D02*
X-318898D01*
G01D02*
X-992126D01*
G01X-955512D02*
X-986221D01*
G01X-996063Y3937D02*
Y103740D01*
G01Y39370D02*
Y70079D01*
G01Y3937D02*
Y921260D01*
G01X-1003937Y-3937D02*
Y39370D01*
G01X-1027559Y99803D02*
G03X-1031496Y95866I0J-3937D01*
G01X-1003937D02*
G03X-1007874Y99803I-3937J0D01*
G01X-996063Y103740D02*
G03X-1000000Y107677I-3937J0D01*
G01X-1003937Y70079D02*
G03X-996063I3937J0D01*
G01X-1009449Y132481D02*
X-1025985D01*
G01Y131300D02*
X-1009449D01*
G01Y128544D02*
X-1025985D01*
G01Y127363D02*
X-1009449D01*
G01Y124607D02*
X-1025985D01*
G01Y123426D02*
X-1009449D01*
G01Y120670D02*
X-1025985D01*
G01Y119489D02*
X-1009449D01*
G01Y116733D02*
X-1025985D01*
G01X-1022047Y115552D02*
X-1009449D01*
G01Y112796D02*
X-1022047D01*
G01X-1025985Y111615D02*
X-1009449D01*
G01Y108859D02*
X-1025985D01*
G01X-1029528Y107677D02*
X-1000000D01*
G01X-1007874Y99803D02*
X-1027559D01*
G01X-1003937Y70079D02*
Y95866D01*
G01X-1009449Y111615D02*
Y108859D01*
G01Y115552D02*
Y112796D01*
G01Y119489D02*
Y116733D01*
G01Y123426D02*
Y120670D01*
G01Y127363D02*
Y124607D01*
G01Y131300D02*
Y128544D01*
G01Y135237D02*
Y132481D01*
G01X-1031496Y109646D02*
X-1029528Y107677D01*
G01X-1022047Y112796D02*
Y115552D01*
G01X-1025985Y132481D02*
Y135237D01*
G01Y107677D02*
Y136024D01*
G01Y128544D02*
Y131300D01*
G01Y124607D02*
Y127363D01*
G01Y116733D02*
Y119489D01*
G01Y120670D02*
Y123426D01*
G01Y108859D02*
Y111615D01*
G01X-1031496Y109646D02*
Y134055D01*
G01X-1002166Y136024D02*
G03Y143504I0J3740D01*
G01X-1000000Y187599D02*
G03X-996063Y191536I0J3937D01*
G01X-1029528Y187599D02*
X-1000000D01*
G01X-1025985Y186418D02*
X-1009449D01*
G01Y183662D02*
X-1025985D01*
G01Y182481D02*
X-1009449D01*
G01Y179725D02*
X-1025985D01*
G01Y178544D02*
X-1009449D01*
G01Y175788D02*
X-1025985D01*
G01Y174607D02*
X-1009449D01*
G01Y171851D02*
X-1025985D01*
G01Y170670D02*
X-1009449D01*
G01Y167914D02*
X-1025985D01*
G01Y166733D02*
X-1009449D01*
G01Y163977D02*
X-1025985D01*
G01Y162796D02*
X-1009449D01*
G01Y160040D02*
X-1025985D01*
G01Y158859D02*
X-1009449D01*
G01Y156103D02*
X-1025985D01*
G01Y154922D02*
X-1009449D01*
G01Y152166D02*
X-1025985D01*
G01Y150985D02*
X-1009449D01*
G01Y148229D02*
X-1025985D01*
G01Y147048D02*
X-1009449D01*
G01Y144292D02*
X-1025985D01*
G01X-1029528Y143504D02*
X-1002166D01*
G01X-1029528Y136024D02*
X-1002166D01*
G01X-1025985Y135237D02*
X-1009449D01*
G01X-1029528Y136024D02*
X-1031496Y134055D01*
G01X-1029528Y187599D02*
X-1031496Y185630D01*
G01Y145473D02*
X-1029528Y143504D01*
G01X-996063Y261221D02*
Y191536D01*
G01X-1009449Y147048D02*
Y144292D01*
G01Y150985D02*
Y148229D01*
G01Y154922D02*
Y152166D01*
G01Y158859D02*
Y156103D01*
G01Y162796D02*
Y160040D01*
G01Y166733D02*
Y163977D01*
G01Y170670D02*
Y167914D01*
G01Y174607D02*
Y171851D01*
G01Y178544D02*
Y175788D01*
G01Y182481D02*
Y179725D01*
G01Y186418D02*
Y183662D01*
G01X-1025985D02*
Y186418D01*
G01Y143504D02*
Y187599D01*
G01Y179725D02*
Y182481D01*
G01Y175788D02*
Y178544D01*
G01Y167914D02*
Y170670D01*
G01Y171851D02*
Y174607D01*
G01Y163977D02*
Y166733D01*
G01Y160040D02*
Y162796D01*
G01Y156103D02*
Y158859D01*
G01Y152166D02*
Y154922D01*
G01Y144292D02*
Y147048D01*
G01Y148229D02*
Y150985D01*
G01X-1031496Y145473D02*
Y185630D01*
G01X-996063Y261221D02*
G03X-1000000Y265158I-3937J0D01*
G01X-1009449Y274213D02*
X-1025985D01*
G01X-1022047Y273032D02*
X-1009449D01*
G01Y270276D02*
X-1022047D01*
G01X-1025985Y269095D02*
X-1009449D01*
G01Y266339D02*
X-1025985D01*
G01X-1029528Y265158D02*
X-1000000D01*
G01X-1031496Y267126D02*
X-1029528Y265158D01*
G01X-1009449Y273032D02*
Y270276D01*
G01Y269095D02*
Y266339D01*
G01Y276969D02*
Y274213D01*
G01X-1022047Y270276D02*
Y273032D01*
G01X-1025985Y265158D02*
Y545473D01*
G01Y274213D02*
Y276969D01*
G01Y266339D02*
Y269095D01*
G01X-1031496Y267126D02*
Y543504D01*
G01X-1025985Y343898D02*
X-1009449D01*
G01Y341142D02*
X-1025985D01*
G01Y339961D02*
X-1009449D01*
G01Y337205D02*
X-1025985D01*
G01Y336024D02*
X-1009449D01*
G01Y333268D02*
X-1025985D01*
G01Y332087D02*
X-1009449D01*
G01Y329331D02*
X-1025985D01*
G01Y328150D02*
X-1009449D01*
G01Y325394D02*
X-1025985D01*
G01Y324213D02*
X-1009449D01*
G01Y321457D02*
X-1025985D01*
G01Y320276D02*
X-1009449D01*
G01Y317520D02*
X-1025985D01*
G01Y316339D02*
X-1009449D01*
G01Y313583D02*
X-1025985D01*
G01Y312402D02*
X-1009449D01*
G01Y309646D02*
X-1025985D01*
G01Y308465D02*
X-1009449D01*
G01Y305709D02*
X-1025985D01*
G01Y304528D02*
X-1009449D01*
G01Y301772D02*
X-1025985D01*
G01Y300591D02*
X-1009449D01*
G01Y297835D02*
X-1025985D01*
G01Y296654D02*
X-1009449D01*
G01Y293898D02*
X-1025985D01*
G01Y292717D02*
X-1009449D01*
G01Y289961D02*
X-1025985D01*
G01Y288780D02*
X-1009449D01*
G01Y286024D02*
X-1025985D01*
G01Y284843D02*
X-1009449D01*
G01Y282087D02*
X-1025985D01*
G01Y280906D02*
X-1009449D01*
G01Y278150D02*
X-1025985D01*
G01Y276969D02*
X-1009449D01*
G01Y280906D02*
Y278150D01*
G01Y284843D02*
Y282087D01*
G01Y288780D02*
Y286024D01*
G01Y292717D02*
Y289961D01*
G01Y296654D02*
Y293898D01*
G01Y300591D02*
Y297835D01*
G01Y304528D02*
Y301772D01*
G01Y308465D02*
Y305709D01*
G01Y312402D02*
Y309646D01*
G01Y316339D02*
Y313583D01*
G01Y320276D02*
Y317520D01*
G01Y324213D02*
Y321457D01*
G01Y328150D02*
Y325394D01*
G01Y332087D02*
Y329331D01*
G01Y336024D02*
Y333268D01*
G01Y339961D02*
Y337205D01*
G01Y343898D02*
Y341142D01*
G01X-1025985D02*
Y343898D01*
G01Y337205D02*
Y339961D01*
G01Y333268D02*
Y336024D01*
G01Y329331D02*
Y332087D01*
G01Y325394D02*
Y328150D01*
G01Y317520D02*
Y320276D01*
G01Y321457D02*
Y324213D01*
G01Y313583D02*
Y316339D01*
G01Y309646D02*
Y312402D01*
G01Y305709D02*
Y308465D01*
G01Y301772D02*
Y304528D01*
G01Y297835D02*
Y300591D01*
G01Y289961D02*
Y292717D01*
G01Y293898D02*
Y296654D01*
G01Y286024D02*
Y288780D01*
G01Y282087D02*
Y284843D01*
G01Y278150D02*
Y280906D01*
G01Y414764D02*
X-1009449D01*
G01Y412008D02*
X-1025985D01*
G01Y410827D02*
X-1009449D01*
G01Y408071D02*
X-1025985D01*
G01Y406890D02*
X-1009449D01*
G01Y404134D02*
X-1025985D01*
G01Y402953D02*
X-1009449D01*
G01Y400197D02*
X-1025985D01*
G01Y399016D02*
X-1009449D01*
G01Y396260D02*
X-1025985D01*
G01Y395079D02*
X-1009449D01*
G01Y392323D02*
X-1025985D01*
G01Y391142D02*
X-1009449D01*
G01Y388386D02*
X-1025985D01*
G01Y387205D02*
X-1009449D01*
G01Y384449D02*
X-1025985D01*
G01Y383268D02*
X-1009449D01*
G01Y380512D02*
X-1025985D01*
G01Y379331D02*
X-1009449D01*
G01Y376575D02*
X-1025985D01*
G01Y375394D02*
X-1009449D01*
G01Y372638D02*
X-1025985D01*
G01Y371457D02*
X-1009449D01*
G01Y368701D02*
X-1025985D01*
G01Y367520D02*
X-1009449D01*
G01Y364764D02*
X-1025985D01*
G01Y363583D02*
X-1009449D01*
G01Y360827D02*
X-1025985D01*
G01Y359646D02*
X-1009449D01*
G01Y356890D02*
X-1025985D01*
G01Y355709D02*
X-1009449D01*
G01Y352953D02*
X-1025985D01*
G01Y351772D02*
X-1009449D01*
G01Y349016D02*
X-1025985D01*
G01Y347835D02*
X-1009449D01*
G01Y345079D02*
X-1025985D01*
G01X-1009449Y347835D02*
Y345079D01*
G01Y351772D02*
Y349016D01*
G01Y355709D02*
Y352953D01*
G01Y359646D02*
Y356890D01*
G01Y363583D02*
Y360827D01*
G01Y367520D02*
Y364764D01*
G01Y371457D02*
Y368701D01*
G01Y375394D02*
Y372638D01*
G01Y379331D02*
Y376575D01*
G01Y383268D02*
Y380512D01*
G01Y387205D02*
Y384449D01*
G01Y391142D02*
Y388386D01*
G01Y395079D02*
Y392323D01*
G01Y399016D02*
Y396260D01*
G01Y402953D02*
Y400197D01*
G01Y406890D02*
Y404134D01*
G01Y410827D02*
Y408071D01*
G01Y414764D02*
Y412008D01*
G01X-1025985D02*
Y414764D01*
G01Y408071D02*
Y410827D01*
G01Y404134D02*
Y406890D01*
G01Y400197D02*
Y402953D01*
G01Y396260D02*
Y399016D01*
G01Y388386D02*
Y391142D01*
G01Y392323D02*
Y395079D01*
G01Y384449D02*
Y387205D01*
G01Y380512D02*
Y383268D01*
G01Y376575D02*
Y379331D01*
G01Y372638D02*
Y375394D01*
G01Y364764D02*
Y367520D01*
G01Y368701D02*
Y371457D01*
G01Y360827D02*
Y363583D01*
G01Y356890D02*
Y359646D01*
G01Y352953D02*
Y355709D01*
G01Y349016D02*
Y351772D01*
G01Y345079D02*
Y347835D01*
G01Y485630D02*
X-1009449D01*
G01Y482874D02*
X-1025985D01*
G01Y481693D02*
X-1009449D01*
G01Y478937D02*
X-1025985D01*
G01Y477756D02*
X-1009449D01*
G01Y475000D02*
X-1025985D01*
G01Y473819D02*
X-1009449D01*
G01Y471063D02*
X-1025985D01*
G01Y469882D02*
X-1009449D01*
G01Y467126D02*
X-1025985D01*
G01Y465945D02*
X-1009449D01*
G01Y463189D02*
X-1025985D01*
G01Y462008D02*
X-1009449D01*
G01Y459252D02*
X-1025985D01*
G01Y458071D02*
X-1009449D01*
G01Y455315D02*
X-1025985D01*
G01Y454134D02*
X-1009449D01*
G01Y451378D02*
X-1025985D01*
G01Y450197D02*
X-1009449D01*
G01Y447441D02*
X-1025985D01*
G01Y446260D02*
X-1009449D01*
G01Y443504D02*
X-1025985D01*
G01Y442323D02*
X-1009449D01*
G01Y439567D02*
X-1025985D01*
G01Y438386D02*
X-1009449D01*
G01Y435630D02*
X-1025985D01*
G01Y434449D02*
X-1009449D01*
G01Y431693D02*
X-1025985D01*
G01Y430512D02*
X-1009449D01*
G01Y427756D02*
X-1025985D01*
G01Y426575D02*
X-1009449D01*
G01Y423819D02*
X-1025985D01*
G01Y422638D02*
X-1009449D01*
G01Y419882D02*
X-1025985D01*
G01Y418701D02*
X-1009449D01*
G01Y415945D02*
X-1025985D01*
G01X-1009449Y418701D02*
Y415945D01*
G01Y422638D02*
Y419882D01*
G01Y426575D02*
Y423819D01*
G01Y430512D02*
Y427756D01*
G01Y434449D02*
Y431693D01*
G01Y438386D02*
Y435630D01*
G01Y442323D02*
Y439567D01*
G01Y446260D02*
Y443504D01*
G01Y450197D02*
Y447441D01*
G01Y454134D02*
Y451378D01*
G01Y458071D02*
Y455315D01*
G01Y462008D02*
Y459252D01*
G01Y465945D02*
Y463189D01*
G01Y469882D02*
Y467126D01*
G01Y473819D02*
Y471063D01*
G01Y477756D02*
Y475000D01*
G01Y481693D02*
Y478937D01*
G01Y485630D02*
Y482874D01*
G01X-1025985D02*
Y485630D01*
G01Y478937D02*
Y481693D01*
G01Y475000D02*
Y477756D01*
G01Y471063D02*
Y473819D01*
G01Y463189D02*
Y465945D01*
G01Y467126D02*
Y469882D01*
G01Y459252D02*
Y462008D01*
G01Y455315D02*
Y458071D01*
G01Y451378D02*
Y454134D01*
G01Y447441D02*
Y450197D01*
G01Y439567D02*
Y442323D01*
G01Y443504D02*
Y446260D01*
G01Y435630D02*
Y438386D01*
G01Y431693D02*
Y434449D01*
G01Y427756D02*
Y430512D01*
G01Y423819D02*
Y426575D01*
G01Y415945D02*
Y418701D01*
G01Y419882D02*
Y422638D01*
G01X-1002166Y545473D02*
G03Y552953I0J3740D01*
G01X-1009449Y553740D02*
X-1025985D01*
G01X-1029528Y552953D02*
X-1002166D01*
G01X-1029528Y545473D02*
X-1002166D01*
G01X-1025985Y544685D02*
X-1009449D01*
G01Y541929D02*
X-1025985D01*
G01Y540748D02*
X-1009449D01*
G01Y537992D02*
X-1025985D01*
G01Y536811D02*
X-1009449D01*
G01Y534055D02*
X-1025985D01*
G01Y532874D02*
X-1009449D01*
G01Y530118D02*
X-1025985D01*
G01Y528937D02*
X-1009449D01*
G01Y526181D02*
X-1025985D01*
G01Y525000D02*
X-1009449D01*
G01Y522244D02*
X-1025985D01*
G01Y521063D02*
X-1009449D01*
G01Y518307D02*
X-1025985D01*
G01Y517126D02*
X-1009449D01*
G01Y514370D02*
X-1025985D01*
G01Y513189D02*
X-1009449D01*
G01Y510433D02*
X-1025985D01*
G01Y509252D02*
X-1009449D01*
G01Y506496D02*
X-1025985D01*
G01Y505315D02*
X-1009449D01*
G01Y502559D02*
X-1025985D01*
G01Y501378D02*
X-1009449D01*
G01Y498622D02*
X-1025985D01*
G01Y497441D02*
X-1009449D01*
G01Y494685D02*
X-1025985D01*
G01Y493504D02*
X-1009449D01*
G01Y490748D02*
X-1025985D01*
G01Y489567D02*
X-1009449D01*
G01Y486811D02*
X-1025985D01*
G01X-1031496Y554922D02*
X-1029528Y552953D01*
G01Y545473D02*
X-1031496Y543504D01*
G01X-1009449Y489567D02*
Y486811D01*
G01Y493504D02*
Y490748D01*
G01Y497441D02*
Y494685D01*
G01Y501378D02*
Y498622D01*
G01Y505315D02*
Y502559D01*
G01Y509252D02*
Y506496D01*
G01Y513189D02*
Y510433D01*
G01Y517126D02*
Y514370D01*
G01Y521063D02*
Y518307D01*
G01Y525000D02*
Y522244D01*
G01Y528937D02*
Y526181D01*
G01Y532874D02*
Y530118D01*
G01Y536811D02*
Y534055D01*
G01Y540748D02*
Y537992D01*
G01Y544685D02*
Y541929D01*
G01Y556496D02*
Y553740D01*
G01X-1025985Y552953D02*
Y597048D01*
G01Y553740D02*
Y556496D01*
G01Y537992D02*
Y540748D01*
G01Y541929D02*
Y544685D01*
G01Y534055D02*
Y536811D01*
G01Y530118D02*
Y532874D01*
G01Y526181D02*
Y528937D01*
G01Y522244D02*
Y525000D01*
G01Y514370D02*
Y517126D01*
G01Y518307D02*
Y521063D01*
G01Y510433D02*
Y513189D01*
G01Y506496D02*
Y509252D01*
G01Y502559D02*
Y505315D01*
G01Y498622D02*
Y501378D01*
G01Y490748D02*
Y493504D01*
G01Y494685D02*
Y497441D01*
G01Y486811D02*
Y489567D01*
G01X-1031496Y554922D02*
Y595079D01*
G01X-1007874Y604922D02*
G03X-1003937Y608859I0J3937D01*
G01X-1031496D02*
G03X-1027559Y604922I3937J0D01*
G01X-1000000Y597048D02*
G03X-996063Y600985I0J3937D01*
G01X-1027559Y604922D02*
X-1007874D01*
G01X-1029528Y597048D02*
X-1000000D01*
G01X-1025985Y595866D02*
X-1009449D01*
G01Y593111D02*
X-1025985D01*
G01Y591929D02*
X-1009449D01*
G01Y589174D02*
X-1025985D01*
G01Y587992D02*
X-1009449D01*
G01Y585237D02*
X-1025985D01*
G01Y584055D02*
X-1009449D01*
G01Y581300D02*
X-1025985D01*
G01Y580118D02*
X-1009449D01*
G01Y577363D02*
X-1025985D01*
G01Y576181D02*
X-1009449D01*
G01Y573426D02*
X-1025985D01*
G01Y572244D02*
X-1009449D01*
G01Y569489D02*
X-1025985D01*
G01Y568307D02*
X-1009449D01*
G01Y565552D02*
X-1025985D01*
G01Y564370D02*
X-1009449D01*
G01Y561615D02*
X-1025985D01*
G01Y560433D02*
X-1009449D01*
G01Y557677D02*
X-1025985D01*
G01Y556496D02*
X-1009449D01*
G01X-1029528Y597048D02*
X-1031496Y595079D01*
G01X-996063Y921260D02*
Y600985D01*
G01X-1003937Y608859D02*
Y708662D01*
G01X-1009449Y560433D02*
Y557677D01*
G01Y564370D02*
Y561615D01*
G01Y568307D02*
Y565552D01*
G01Y572244D02*
Y569489D01*
G01Y576181D02*
Y573426D01*
G01Y580118D02*
Y577363D01*
G01Y584055D02*
Y581300D01*
G01Y587992D02*
Y585237D01*
G01Y591929D02*
Y589174D01*
G01Y595866D02*
Y593111D01*
G01X-1025985Y589174D02*
Y591929D01*
G01Y593111D02*
Y595866D01*
G01Y585237D02*
Y587992D01*
G01Y581300D02*
Y584055D01*
G01Y577363D02*
Y580118D01*
G01Y573426D02*
Y576181D01*
G01Y569489D02*
Y572244D01*
G01Y561615D02*
Y564370D01*
G01Y565552D02*
Y568307D01*
G01Y557677D02*
Y560433D01*
G01X-1031496Y956693D02*
Y608859D01*
G01X-1003937Y739370D02*
G03X-996063I3937J0D01*
G01Y708662D02*
G03X-1003937I-3937J0D01*
G01X-996063D02*
Y739370D01*
G01X-1003937D02*
Y929134D01*
G01X-1006358Y945315D02*
X-932041Y1004873D01*
G01X-1011811Y944882D02*
Y1015079D01*
G01X-992126Y925197D02*
G03X-996063Y921260I0J-3937D01*
G01X-1000000Y933071D02*
G03X-1003937Y929134I0J-3937D01*
G01X-986221Y925197D02*
G03Y933071I0J3937D01*
G01X-1027559Y960630D02*
G03X-1031496Y956693I0J-3937D01*
G01X-992126Y925197D02*
G03X-996063Y921260I0J-3937D01*
G01X-1004823Y940945D02*
G03I-6988J0D01*
G01X791338Y960630D02*
X-1027559D01*
G01X-1000000Y933071D02*
X-986221D01*
G01X-992126Y925197D02*
X-240158D01*
G01X-986221D02*
X-955512D01*
G01X-992126D02*
X-240158D01*
G01X-996063Y915355D02*
X-437008D01*
G01X-1022507Y1020817D02*
X-1023530Y1021585D01*
X-1024042Y1022481D01*
X-1024213Y1023504D01*
X-1023872Y1024784D01*
X-1023019Y1025680D01*
X-1021995Y1025935D01*
X-1020971Y1025808D01*
X-1020119Y1025296D01*
X-1018413Y1022737D01*
X-1017218Y1021585D01*
X-1015512Y1020817D01*
X-1013977Y1020562D01*
Y1025935D01*
G01X-1015512Y1030670D02*
X-1014659Y1031437D01*
X-1014148Y1032333D01*
X-1013977Y1033484D01*
X-1014318Y1034636D01*
X-1015000Y1035532D01*
X-1016195Y1036171D01*
X-1017559Y1036299D01*
X-1018924Y1036044D01*
X-1019777Y1035404D01*
X-1020460Y1034508D01*
X-1020630Y1033613D01*
X-1020460Y1032717D01*
X-1019777Y1031565D01*
X-1024213Y1031949D01*
Y1035404D01*
G01X-1013977Y1043465D02*
X-1016195Y1043720D01*
X-1018071Y1044104D01*
X-1019777Y1044616D01*
X-1021654Y1045256D01*
X-1024213Y1046280D01*
Y1041161D01*
G01X-1013636Y1053956D02*
X-1013806Y1053701D01*
X-1014148D01*
X-1014318Y1053956D01*
X-1014148Y1054212D01*
X-1013806D01*
X-1013636Y1053956D01*
G01X-1024213Y1064192D02*
X-1023872Y1063169D01*
X-1023019Y1062401D01*
X-1021995Y1061889D01*
X-1020630Y1061506D01*
X-1019095Y1061378D01*
X-1017559Y1061506D01*
X-1016195Y1061889D01*
X-1015171Y1062401D01*
X-1014318Y1063169D01*
X-1013977Y1064192D01*
X-1014318Y1065216D01*
X-1015171Y1065984D01*
X-1016195Y1066496D01*
X-1017559Y1066879D01*
X-1019095Y1067007D01*
X-1020630Y1066879D01*
X-1021995Y1066496D01*
X-1023019Y1065984D01*
X-1023872Y1065216D01*
X-1024213Y1064192D01*
G01Y1074428D02*
X-1023872Y1073405D01*
X-1023019Y1072637D01*
X-1021995Y1072125D01*
X-1020630Y1071742D01*
X-1019095Y1071614D01*
X-1017559Y1071742D01*
X-1016195Y1072125D01*
X-1015171Y1072637D01*
X-1014318Y1073405D01*
X-1013977Y1074428D01*
X-1014318Y1075452D01*
X-1015171Y1076220D01*
X-1016195Y1076732D01*
X-1017559Y1077115D01*
X-1019095Y1077243D01*
X-1020630Y1077115D01*
X-1021995Y1076732D01*
X-1023019Y1076220D01*
X-1023872Y1075452D01*
X-1024213Y1074428D01*
G01X-917853Y-1208291D02*
Y-1298672D01*
G01D02*
Y-1197070D01*
G01X-920019Y-1302038D02*
X-930255D01*
X-928208Y-1303573D01*
G01X-920019D02*
Y-1300502D01*
G01X-919678Y-1291802D02*
X-919848Y-1292057D01*
X-920190D01*
X-920360Y-1291802D01*
X-920190Y-1291546D01*
X-919848D01*
X-919678Y-1291802D01*
G01X-921213Y-1283741D02*
X-920360Y-1282845D01*
X-920019Y-1281821D01*
X-920360Y-1280798D01*
X-921384Y-1279902D01*
X-922919Y-1279262D01*
X-924455Y-1279006D01*
X-926331D01*
X-927866Y-1279262D01*
X-929231Y-1279902D01*
X-929914Y-1280670D01*
X-930255Y-1281566D01*
X-929914Y-1282589D01*
X-929231Y-1283357D01*
X-928208Y-1283869D01*
X-926843Y-1284125D01*
X-925649Y-1283869D01*
X-924455Y-1283229D01*
X-923772Y-1282461D01*
X-923601Y-1281566D01*
X-923943Y-1280542D01*
X-924796Y-1279774D01*
X-926331Y-1279006D01*
G01X-930255Y-1271330D02*
X-929914Y-1272353D01*
X-929061Y-1273121D01*
X-928037Y-1273633D01*
X-926672Y-1274016D01*
X-925137Y-1274144D01*
X-923601Y-1274016D01*
X-922237Y-1273633D01*
X-921213Y-1273121D01*
X-920360Y-1272353D01*
X-920019Y-1271330D01*
X-920360Y-1270306D01*
X-921213Y-1269538D01*
X-922237Y-1269026D01*
X-923601Y-1268643D01*
X-925137Y-1268515D01*
X-926672Y-1268643D01*
X-928037Y-1269026D01*
X-929061Y-1269538D01*
X-929914Y-1270306D01*
X-930255Y-1271330D01*
G01X-926843Y-1261223D02*
X-928975Y-1262503D01*
X-930255D01*
Y-1261543D01*
X-928975D01*
Y-1262503D01*
G01X-930255Y-1260751D02*
X-929914Y-1261774D01*
X-929061Y-1262542D01*
X-928037Y-1263054D01*
X-926672Y-1263437D01*
X-925137Y-1263565D01*
X-923601Y-1263437D01*
X-922237Y-1263054D01*
X-921213Y-1262542D01*
X-920360Y-1261774D01*
X-920019Y-1260751D01*
X-920360Y-1259727D01*
X-921213Y-1258959D01*
X-922237Y-1258447D01*
X-923601Y-1258064D01*
X-925137Y-1257936D01*
X-926672Y-1258064D01*
X-928037Y-1258447D01*
X-929061Y-1258959D01*
X-929914Y-1259727D01*
X-930255Y-1260751D01*
G01X-919678Y-1250515D02*
X-919848Y-1250770D01*
X-920190D01*
X-920360Y-1250515D01*
X-920190Y-1250259D01*
X-919848D01*
X-919678Y-1250515D01*
G01X-930255Y-1240279D02*
X-929914Y-1241302D01*
X-929061Y-1242070D01*
X-928037Y-1242582D01*
X-926672Y-1242965D01*
X-925137Y-1243093D01*
X-923601Y-1242965D01*
X-922237Y-1242582D01*
X-921213Y-1242070D01*
X-920360Y-1241302D01*
X-920019Y-1240279D01*
X-920360Y-1239255D01*
X-921213Y-1238487D01*
X-922237Y-1237975D01*
X-923601Y-1237592D01*
X-925137Y-1237464D01*
X-926672Y-1237592D01*
X-928037Y-1237975D01*
X-929061Y-1238487D01*
X-929914Y-1239255D01*
X-930255Y-1240279D01*
G01X-924284Y-1232474D02*
X-925478Y-1231578D01*
X-926161Y-1230810D01*
X-926502Y-1229787D01*
X-926161Y-1228891D01*
X-925478Y-1228251D01*
X-924455Y-1227739D01*
X-923260Y-1227611D01*
X-922237Y-1227739D01*
X-921213Y-1228251D01*
X-920360Y-1229019D01*
X-920019Y-1229914D01*
X-920360Y-1230938D01*
X-921384Y-1231834D01*
X-922919Y-1232346D01*
X-924625Y-1232474D01*
X-926843Y-1232218D01*
X-928037Y-1231834D01*
X-929231Y-1231194D01*
X-930084Y-1230298D01*
X-930255Y-1229403D01*
X-929914Y-1228507D01*
X-929061Y-1227867D01*
G01X-917853Y-1185850D02*
Y-1166165D01*
G01D02*
Y-1197070D01*
G01X-977216Y-1106716D02*
X-913516D01*
G01X-917453Y-1100810D02*
Y-1051715D01*
G01D02*
Y-1103763D01*
G01Y-1106716D02*
Y-1126401D01*
G01D02*
Y-1103763D01*
G01X-929854Y-1079059D02*
X-929513Y-1080082D01*
X-928660Y-1080850D01*
X-927636Y-1081362D01*
X-926271Y-1081745D01*
X-924736Y-1081873D01*
X-923200Y-1081745D01*
X-921836Y-1081362D01*
X-920812Y-1080850D01*
X-919959Y-1080082D01*
X-919618Y-1079059D01*
X-919959Y-1078035D01*
X-920812Y-1077267D01*
X-921836Y-1076755D01*
X-923200Y-1076372D01*
X-924736Y-1076244D01*
X-926271Y-1076372D01*
X-927636Y-1076755D01*
X-928660Y-1077267D01*
X-929513Y-1078035D01*
X-929854Y-1079059D01*
G01X-919277Y-1068823D02*
X-919447Y-1069078D01*
X-919789D01*
X-919959Y-1068823D01*
X-919789Y-1068567D01*
X-919447D01*
X-919277Y-1068823D01*
G01X-921153Y-1061401D02*
X-920300Y-1060634D01*
X-919789Y-1059738D01*
X-919618Y-1058587D01*
X-919959Y-1057435D01*
X-920641Y-1056539D01*
X-921836Y-1055900D01*
X-923200Y-1055772D01*
X-924565Y-1056027D01*
X-925418Y-1056667D01*
X-926101Y-1057563D01*
X-926271Y-1058458D01*
X-926101Y-1059354D01*
X-925418Y-1060506D01*
X-929854Y-1060122D01*
Y-1056667D01*
G01Y-1048351D02*
X-929513Y-1049374D01*
X-928660Y-1050142D01*
X-927636Y-1050654D01*
X-926271Y-1051037D01*
X-924736Y-1051165D01*
X-923200Y-1051037D01*
X-921836Y-1050654D01*
X-920812Y-1050142D01*
X-919959Y-1049374D01*
X-919618Y-1048351D01*
X-919959Y-1047327D01*
X-920812Y-1046559D01*
X-921836Y-1046047D01*
X-923200Y-1045664D01*
X-924736Y-1045536D01*
X-926271Y-1045664D01*
X-927636Y-1046047D01*
X-928660Y-1046559D01*
X-929513Y-1047327D01*
X-929854Y-1048351D01*
G01X-973594Y-1057228D02*
X-972827Y-1058422D01*
X-971803Y-1059104D01*
X-970651Y-1059275D01*
X-969628Y-1059104D01*
X-968604Y-1058252D01*
X-967965Y-1057228D01*
X-967837Y-1056204D01*
X-968093Y-1055010D01*
X-968988Y-1054157D01*
X-969884Y-1053816D01*
X-971035D01*
G01X-969884D02*
X-969116Y-1053304D01*
X-968476Y-1052451D01*
X-968220Y-1051428D01*
X-968476Y-1050404D01*
X-969116Y-1049551D01*
X-970268Y-1049039D01*
X-971419Y-1049210D01*
X-972571Y-1049892D01*
G01X-960544Y-1059616D02*
X-960799Y-1059446D01*
Y-1059104D01*
X-960544Y-1058934D01*
X-960288Y-1059104D01*
Y-1059446D01*
X-960544Y-1059616D01*
G01X-952739Y-1050745D02*
X-951971Y-1049722D01*
X-951075Y-1049210D01*
X-950052Y-1049039D01*
X-948772Y-1049380D01*
X-947876Y-1050233D01*
X-947621Y-1051257D01*
X-947748Y-1052281D01*
X-948260Y-1053133D01*
X-950819Y-1054839D01*
X-951971Y-1056034D01*
X-952739Y-1057740D01*
X-952994Y-1059275D01*
X-947621D01*
G01X-940072Y-1049039D02*
X-941095Y-1049380D01*
X-941863Y-1050233D01*
X-942375Y-1051257D01*
X-942758Y-1052622D01*
X-942886Y-1054157D01*
X-942758Y-1055693D01*
X-942375Y-1057057D01*
X-941863Y-1058081D01*
X-941095Y-1058934D01*
X-940072Y-1059275D01*
X-939048Y-1058934D01*
X-938280Y-1058081D01*
X-937768Y-1057057D01*
X-937385Y-1055693D01*
X-937257Y-1054157D01*
X-937385Y-1052622D01*
X-937768Y-1051257D01*
X-938280Y-1050233D01*
X-939048Y-1049380D01*
X-940072Y-1049039D01*
G01X-955512Y0D02*
G03Y-7874I0J-3937D01*
G01X-769685D02*
X-955512D01*
G01X-953006Y-9185D02*
X-936758D01*
G01X-947382Y-14685D02*
X-942382D01*
G01X-944882Y-17185D02*
X-942382D01*
G01Y-19685D02*
X-947382D01*
G01X-936758Y-25185D02*
X-953006D01*
G01X-936758Y-9185D02*
Y-25185D01*
G01X-942382Y-14685D02*
Y-19685D01*
G01X-944882Y-14685D02*
Y-17185D01*
G01X-947382Y-19685D02*
Y-14685D01*
G01X-953006Y-25185D02*
Y-9185D01*
G01X-942914Y885827D02*
G03I-9842J0D01*
G01X-955512Y933071D02*
G03Y925197I0J-3937D01*
G01X-953006Y950382D02*
X-936758D01*
G01X-947382Y944882D02*
X-942382D01*
G01X-944882Y942382D02*
X-942382D01*
G01Y939882D02*
X-947382D01*
G01X-936758Y934382D02*
X-953006D01*
G01X-955512Y933071D02*
X-750000D01*
G01X-936758Y950382D02*
Y934382D01*
G01X-942382Y944882D02*
Y939882D01*
G01X-944882Y944882D02*
Y942382D01*
G01X-947382Y939882D02*
Y944882D01*
G01X-953006Y934382D02*
Y950382D01*
G01X-916392Y1004282D02*
Y994046D01*
G01X-919334Y1004282D02*
X-913449D01*
G01X-906156Y994046D02*
X-906923Y994217D01*
X-907691Y994899D01*
X-908203Y996093D01*
X-908459Y997458D01*
X-908203Y998823D01*
X-907691Y1000017D01*
X-906923Y1000699D01*
X-906156Y1000870D01*
X-905388Y1000699D01*
X-904620Y1000017D01*
X-904108Y998823D01*
X-903980Y997458D01*
X-904108Y996093D01*
X-904620Y994899D01*
X-905388Y994217D01*
X-906156Y994046D01*
G01X-895920D02*
X-896687Y994217D01*
X-897455Y994899D01*
X-897967Y996093D01*
X-898223Y997458D01*
X-897967Y998823D01*
X-897455Y1000017D01*
X-896687Y1000699D01*
X-895920Y1000870D01*
X-895152Y1000699D01*
X-894384Y1000017D01*
X-893872Y998823D01*
X-893744Y997458D01*
X-893872Y996093D01*
X-894384Y994899D01*
X-895152Y994217D01*
X-895920Y994046D01*
G01X-885684D02*
Y1004282D01*
G01X-875448Y1000870D02*
Y994046D01*
G01Y1003599D02*
X-875703Y1003770D01*
Y1004111D01*
X-875448Y1004282D01*
X-875192Y1004111D01*
Y1003770D01*
X-875448Y1003599D01*
G01X-867387Y994046D02*
Y1000870D01*
G01Y999164D02*
X-866875Y1000017D01*
X-866107Y1000699D01*
X-865083Y1000870D01*
X-864188Y1000699D01*
X-863420Y1000017D01*
X-863036Y998823D01*
Y994046D01*
G01X-856767Y991487D02*
X-855871Y990805D01*
X-854847Y990634D01*
X-853952Y990805D01*
X-853184Y991657D01*
X-852672Y992852D01*
Y1000870D01*
G01Y999505D02*
X-853184Y1000188D01*
X-853952Y1000699D01*
X-854847Y1000870D01*
X-855871Y1000529D01*
X-856511Y999846D01*
X-857023Y998652D01*
X-857279Y997458D01*
X-857151Y996434D01*
X-856639Y995240D01*
X-855871Y994387D01*
X-854847Y994046D01*
X-854080Y994217D01*
X-853184Y994899D01*
X-852672Y995581D01*
G01X-836679Y994046D02*
Y1004282D01*
G01Y999335D02*
X-836039Y1000188D01*
X-835399Y1000699D01*
X-834375Y1000870D01*
X-833608Y1000699D01*
X-832712Y1000017D01*
X-832328Y998993D01*
Y994046D01*
G01X-824268D02*
X-825035Y994217D01*
X-825803Y994899D01*
X-826315Y996093D01*
X-826571Y997458D01*
X-826315Y998823D01*
X-825803Y1000017D01*
X-825035Y1000699D01*
X-824268Y1000870D01*
X-823500Y1000699D01*
X-822732Y1000017D01*
X-822220Y998823D01*
X-822092Y997458D01*
X-822220Y996093D01*
X-822732Y994899D01*
X-823500Y994217D01*
X-824268Y994046D01*
G01X-814032D02*
Y1004282D01*
G01X-805715Y998652D02*
X-801620D01*
X-802004Y999846D01*
X-802644Y1000529D01*
X-803540Y1000870D01*
X-804435Y1000699D01*
X-805203Y1000188D01*
X-805715Y998993D01*
X-805971Y997970D01*
Y996946D01*
X-805715Y995923D01*
X-805075Y994899D01*
X-804307Y994217D01*
X-803412Y994046D01*
X-802516Y994387D01*
X-801620Y995411D01*
G01X-795479Y995240D02*
X-794839Y994558D01*
X-793943Y994046D01*
X-793176D01*
X-792408Y994387D01*
X-791896Y994899D01*
X-791640Y995581D01*
X-791768Y996605D01*
X-792280Y997117D01*
X-794583Y998140D01*
X-795095Y999335D01*
X-794839Y1000188D01*
X-794327Y1000699D01*
X-793560Y1000870D01*
X-792792Y1000699D01*
X-792024Y1000188D01*
G01X-914856Y1007038D02*
Y1017274D01*
X-919590Y1009938D01*
X-913193D01*
G01X-907819Y1010450D02*
X-904492D01*
G01X-928892Y1004873D02*
X-798682D01*
G01X-932041D02*
X-928892D01*
G01X-848475Y1003626D02*
X-849755Y1005332D01*
X-850395Y1007038D01*
Y1013862D01*
X-849755Y1015568D01*
X-848475Y1017274D01*
G01X-840542Y1007038D02*
Y1017274D01*
X-834657Y1007038D01*
Y1017274D01*
G01X-829923Y1007038D02*
Y1017274D01*
X-826852D01*
X-825828Y1016762D01*
X-825060Y1015568D01*
X-824804Y1014203D01*
X-825060Y1012838D01*
X-825700Y1011815D01*
X-826852Y1011303D01*
X-829923D01*
G01X-817128Y1017274D02*
Y1007038D01*
G01X-820070Y1017274D02*
X-814185D01*
G01X-809578Y1007038D02*
Y1017274D01*
G01X-804205D02*
Y1007038D01*
G01Y1012156D02*
X-809578D01*
G01X-796016Y1003626D02*
X-794736Y1005332D01*
X-794096Y1007038D01*
Y1013862D01*
X-794736Y1015568D01*
X-796016Y1017274D01*
G01X-892067Y1009085D02*
X-891300Y1007891D01*
X-890276Y1007209D01*
X-889124Y1007038D01*
X-888101Y1007209D01*
X-887077Y1008061D01*
X-886438Y1009085D01*
X-886310Y1010109D01*
X-886566Y1011303D01*
X-887461Y1012156D01*
X-888357Y1012497D01*
X-889508D01*
G01X-888357D02*
X-887589Y1013009D01*
X-886949Y1013862D01*
X-886693Y1014885D01*
X-886949Y1015909D01*
X-887589Y1016762D01*
X-888741Y1017274D01*
X-889892Y1017103D01*
X-891044Y1016421D01*
G01X-879017Y1006697D02*
X-879272Y1006867D01*
Y1007209D01*
X-879017Y1007379D01*
X-878761Y1007209D01*
Y1006867D01*
X-879017Y1006697D01*
G01X-871595Y1008573D02*
X-870828Y1007720D01*
X-869932Y1007209D01*
X-868781Y1007038D01*
X-867629Y1007379D01*
X-866733Y1008061D01*
X-866094Y1009256D01*
X-865966Y1010620D01*
X-866221Y1011985D01*
X-866861Y1012838D01*
X-867757Y1013521D01*
X-868652Y1013691D01*
X-869548Y1013521D01*
X-870700Y1012838D01*
X-870316Y1017274D01*
X-866861D01*
G01X-861359Y1008573D02*
X-860592Y1007720D01*
X-859696Y1007209D01*
X-858545Y1007038D01*
X-857393Y1007379D01*
X-856497Y1008061D01*
X-855858Y1009256D01*
X-855730Y1010620D01*
X-855985Y1011985D01*
X-856625Y1012838D01*
X-857521Y1013521D01*
X-858416Y1013691D01*
X-859312Y1013521D01*
X-860464Y1012838D01*
X-860080Y1017274D01*
X-856625D01*
G01X-902977Y1007038D02*
Y1013862D01*
G01Y1012156D02*
X-902465Y1013009D01*
X-901697Y1013691D01*
X-900673Y1013862D01*
X-899778Y1013691D01*
X-899010Y1013009D01*
X-898626Y1011815D01*
Y1007038D01*
G01X-769685Y-7874D02*
G03Y0I0J3937D01*
G01X-738977D02*
X-769685D01*
G01X-738977D02*
G03Y-7874I0J-3937D01*
G01X-522835D02*
X-738977D01*
G01X-704462Y544380D02*
X-702822D01*
G01X-717585D02*
X-715125D01*
G01X-715945Y541030D02*
X-719226D01*
G01X-702822D02*
X-706103D01*
G01X-694620D02*
X-698721D01*
G01X-706103D02*
X-708563Y541867D01*
G01X-719226Y541030D02*
X-721686Y541867D01*
G01X-706103Y545218D02*
X-704462Y544380D01*
G01X-719226Y545218D02*
X-717585Y544380D01*
G01X-700361Y541867D02*
X-702822Y541030D01*
G01Y544380D02*
X-700361Y545218D01*
G01X-713485Y541867D02*
X-715945Y541030D01*
G01X-706923Y546056D02*
X-706103Y545218D01*
G01X-708563Y541867D02*
X-711024Y544380D01*
G01X-720046Y546056D02*
X-719226Y545218D01*
G01X-721686Y541867D02*
X-723327Y543543D01*
G01X-715125Y544380D02*
X-713485Y545218D01*
G01X-698721Y543543D02*
X-700361Y541867D01*
G01Y545218D02*
X-698721Y546893D01*
G01X-723327Y543543D02*
X-724967Y547731D01*
G01X-707743D02*
X-706923Y546056D01*
G01X-720866Y547731D02*
X-720046Y546056D01*
G01X-711024Y544380D02*
X-713485Y541867D01*
G01Y545218D02*
X-712664Y546056D01*
G01D02*
X-711844Y547731D01*
G01X-698721Y546893D02*
Y567835D01*
G01Y541030D02*
Y543543D01*
G01X-707743Y567835D02*
Y547731D01*
G01X-711844D02*
Y567835D01*
G01X-720866D02*
Y547731D01*
G01X-724967D02*
Y567835D01*
G01X-698721D02*
X-694620D01*
G01X-711844D02*
X-707743D01*
G01X-724967D02*
X-720866D01*
G01X-719292Y933071D02*
G03Y925197I0J-3937D01*
G01X-750000D02*
G03Y933071I0J3937D01*
G01X-719292D02*
X-512992D01*
G01X-750000Y925197D02*
X-719292D01*
G01X-634744Y532653D02*
X-630643Y533491D01*
G01X-667553Y544380D02*
X-665912D01*
G01X-680676D02*
X-678215D01*
G01X-629823Y529303D02*
X-635564Y528465D01*
G01X-679036Y541030D02*
X-682316D01*
G01X-665912D02*
X-669193D01*
G01X-657710D02*
X-661811D01*
G01X-626542Y537679D02*
X-622441D01*
G01X-638025Y532653D02*
X-634744D01*
G01X-635564Y528465D02*
X-638845D01*
G01X-642126Y533491D02*
X-638025Y532653D01*
G01X-638845Y528465D02*
X-643766Y529303D01*
G01X-669193Y541030D02*
X-671654Y541867D01*
G01X-682316Y541030D02*
X-684777Y541867D01*
G01X-669193Y545218D02*
X-667553Y544380D01*
G01X-643766Y529303D02*
X-647047Y530978D01*
G01X-682316Y545218D02*
X-680676Y544380D01*
G01X-644587Y535166D02*
X-642126Y533491D01*
G01X-663451Y541867D02*
X-665912Y541030D01*
G01Y544380D02*
X-663451Y545218D01*
G01X-676575Y541867D02*
X-679036Y541030D01*
G01X-647047Y530978D02*
X-650328Y534329D01*
G01X-670013Y546056D02*
X-669193Y545218D01*
G01X-626542Y530978D02*
X-629823Y529303D01*
G01X-678215Y544380D02*
X-676575Y545218D01*
G01X-646227Y537679D02*
X-644587Y535166D01*
G01X-671654Y541867D02*
X-674114Y544380D01*
G01X-683136Y546056D02*
X-682316Y545218D01*
G01X-684777Y541867D02*
X-686418Y543543D01*
G01X-630643Y533491D02*
X-628183Y535166D01*
G01X-670833Y547731D02*
X-670013Y546056D01*
G01X-683957Y547731D02*
X-683136Y546056D01*
G01X-648688Y545218D02*
X-628183Y563647D01*
G01X-621621D02*
X-644587Y542705D01*
G01X-623261Y534329D02*
X-626542Y530978D01*
G01X-661811Y543543D02*
X-663451Y541867D01*
G01Y545218D02*
X-661811Y546893D01*
G01X-674114Y544380D02*
X-676575Y541867D01*
G01Y545218D02*
X-675755Y546056D01*
G01X-628183Y535166D02*
X-626542Y537679D01*
G01X-650328Y534329D02*
X-651148Y537679D01*
G01X-686418Y543543D02*
X-688058Y547731D01*
G01X-650328Y542705D02*
X-648688Y545218D01*
G01X-644587Y542705D02*
X-646227Y539355D01*
G01X-675755Y546056D02*
X-674935Y547731D01*
G01X-651148Y539355D02*
X-650328Y542705D01*
G01X-646227Y539355D02*
Y537679D01*
G01X-651148D02*
Y539355D01*
G01X-657710Y567835D02*
Y541030D01*
G01X-661811Y546893D02*
Y567835D01*
G01Y541030D02*
Y543543D01*
G01X-670833Y567835D02*
Y547731D01*
G01X-674935D02*
Y567835D01*
G01X-683957D02*
Y547731D01*
G01X-688058D02*
Y567835D01*
G01X-694620D02*
Y541030D01*
G01X-651148Y567835D02*
X-621621D01*
G01X-661811D02*
X-657710D01*
G01X-674935D02*
X-670833D01*
G01X-688058D02*
X-683957D01*
G01X-628183Y563647D02*
X-651148D01*
G01D02*
Y567835D01*
G01X-606312Y5238D02*
X-606559Y5154D01*
G01Y5489D02*
X-606312Y5573D01*
G01X-607625Y5238D02*
X-607871Y5154D01*
G01X-610003Y5238D02*
X-610249Y5154D01*
G01Y5489D02*
X-610003Y5573D01*
G01X-611316Y5238D02*
X-611562Y5154D01*
G01X-599833Y5238D02*
X-598685Y5825D01*
G01X-607789Y5489D02*
X-607625Y5573D01*
G01X-611480Y5489D02*
X-611316Y5573D01*
G01X-598110Y5825D02*
X-599669Y4987D01*
G01X-603114Y3982D02*
X-602703Y4233D01*
G01X-604098Y7751D02*
X-604508Y7500D01*
G01X-603196Y4401D02*
X-602949Y4568D01*
G01X-604016Y7332D02*
X-604262Y7165D01*
G01X-602703Y4233D02*
X-602457Y4484D01*
G01X-606148Y5406D02*
X-606312Y5238D01*
G01Y5573D02*
X-606148Y5741D01*
G01X-604508Y7500D02*
X-604754Y7249D01*
G01X-607379Y5489D02*
X-607625Y5238D01*
G01Y5573D02*
X-607543Y5657D01*
G01X-609839Y5406D02*
X-610003Y5238D01*
G01Y5573D02*
X-609839Y5741D01*
G01X-611070Y5489D02*
X-611316Y5238D01*
G01Y5573D02*
X-611234Y5657D01*
G01X-600489Y4484D02*
X-600981Y3898D01*
G01Y4568D02*
X-600489Y5154D01*
G01X-599833Y6411D02*
X-599669Y6662D01*
G01X-602949Y4568D02*
X-602622Y5071D01*
G01X-604262Y7165D02*
X-604590Y6662D01*
G01X-602457Y4484D02*
X-602294Y4819D01*
G01X-604754Y7249D02*
X-604918Y6913D01*
G01X-607543Y5657D02*
X-607461Y5825D01*
G01X-611234Y5657D02*
X-611152Y5825D01*
G01X-602294Y4819D02*
X-602211Y5071D01*
G01X-604918Y6913D02*
X-605000Y6662D01*
G01X-603606Y7835D02*
X-604098Y7751D01*
G01X-603606Y3898D02*
X-603114Y3982D01*
G01X-603606Y7416D02*
X-604016Y7332D01*
G01X-603606Y4317D02*
X-603196Y4401D01*
G01X-602211Y5071D02*
X-602129Y5489D01*
G01X-605000Y6662D02*
X-605082Y6243D01*
G01X-602622Y5071D02*
X-602540Y5573D01*
G01X-604590Y6662D02*
X-604672Y6160D01*
G01X-594666Y7835D02*
X-594173D01*
G01X-597454D02*
X-596962D01*
G01X-601473D02*
X-600981D01*
G01X-606148D02*
X-605738D01*
G01X-609839D02*
X-609429D01*
G01X-611152D02*
X-610742D01*
G01X-608773D02*
X-608363D01*
G01X-607461D02*
X-607051D01*
G01X-612464D02*
X-612054D01*
G01X-596962Y5992D02*
X-594666D01*
G01X-606723Y5489D02*
X-606559D01*
G01X-611726D02*
X-611480D01*
G01X-610414D02*
X-610249D01*
G01X-608035D02*
X-607789D01*
G01X-594666D02*
X-596962D01*
G01X-611562Y5154D02*
X-611890D01*
G01X-609429D02*
X-609839D01*
G01X-610249D02*
X-610577D01*
G01X-607871D02*
X-608199D01*
G01X-605738D02*
X-606148D01*
G01X-606559D02*
X-606886D01*
G01X-600981Y3898D02*
X-601473D01*
G01X-594173D02*
X-594666D01*
G01X-596962D02*
X-597454D01*
G01X-594173Y7835D02*
Y3898D01*
G01X-603196Y7332D02*
X-603606Y7416D01*
G01X-603114Y7751D02*
X-603606Y7835D01*
G01X-604098Y3982D02*
X-603606Y3898D01*
G01X-594666Y5992D02*
Y7835D01*
G01Y3898D02*
Y5489D01*
G01X-596962D02*
Y3898D01*
G01Y7835D02*
Y5992D01*
G01X-597454Y3898D02*
Y7835D01*
G01X-600489Y5154D02*
Y4484D01*
G01X-600981Y7835D02*
Y4568D01*
G01X-601473Y3898D02*
Y7835D01*
G01X-602129Y5489D02*
Y6243D01*
G01X-602540Y5573D02*
Y6160D01*
G01X-604672D02*
Y5573D01*
G01X-605082Y6243D02*
Y5489D01*
G01X-605738Y7835D02*
Y5154D01*
G01X-606148Y5741D02*
Y7835D01*
G01Y5154D02*
Y5406D01*
G01X-607051Y7835D02*
Y5825D01*
G01X-607461D02*
Y7835D01*
G01X-608363D02*
Y5825D01*
G01X-608773D02*
Y7835D01*
G01X-609429D02*
Y5154D01*
G01X-609839Y5741D02*
Y7835D01*
G01Y5154D02*
Y5406D01*
G01X-610742Y7835D02*
Y5825D01*
G01X-611152D02*
Y7835D01*
G01X-612054D02*
Y5825D01*
G01X-612464D02*
Y7835D01*
G01X-602540Y6160D02*
X-602622Y6662D01*
G01X-604672Y5573D02*
X-604590Y5071D01*
G01X-602129Y6243D02*
X-602211Y6662D01*
G01X-605082Y5489D02*
X-605000Y5071D01*
G01X-602211Y6662D02*
X-602294Y6913D01*
G01X-605000Y5071D02*
X-604918Y4819D01*
G01X-606886Y5154D02*
X-607133Y5238D01*
G01X-608199Y5154D02*
X-608445Y5238D01*
G01X-610577Y5154D02*
X-610823Y5238D01*
G01X-611890Y5154D02*
X-612136Y5238D01*
G01X-604016Y4401D02*
X-603606Y4317D01*
G01X-608609Y5406D02*
X-608773Y5825D01*
G01X-612300Y5406D02*
X-612464Y5825D01*
G01X-602294Y6913D02*
X-602457Y7249D01*
G01X-604918Y4819D02*
X-604754Y4484D01*
G01X-607051Y5825D02*
X-606969Y5657D01*
G01X-608363Y5825D02*
X-608281Y5657D01*
G01X-610742Y5825D02*
X-610660Y5657D01*
G01X-612054Y5825D02*
X-611972Y5657D01*
G01X-599669Y4987D02*
X-599833Y5238D01*
G01X-602622Y6662D02*
X-602949Y7165D01*
G01X-604590Y5071D02*
X-604262Y4568D01*
G01X-602457Y7249D02*
X-602703Y7500D01*
G01X-604754Y4484D02*
X-604508Y4233D01*
G01X-606969Y5657D02*
X-606886Y5573D01*
G01X-607133Y5238D02*
X-607379Y5489D01*
G01X-608281Y5657D02*
X-608199Y5573D01*
G01X-608445Y5238D02*
X-608609Y5406D01*
G01X-610660Y5657D02*
X-610577Y5573D01*
G01X-610823Y5238D02*
X-611070Y5489D01*
G01X-611972Y5657D02*
X-611890Y5573D01*
G01X-612136Y5238D02*
X-612300Y5406D01*
G01X-602949Y7165D02*
X-603196Y7332D01*
G01X-604262Y4568D02*
X-604016Y4401D01*
G01X-602703Y7500D02*
X-603114Y7751D01*
G01X-604508Y4233D02*
X-604098Y3982D01*
G01X-599669Y6662D02*
X-598110Y5825D01*
G01X-598685D02*
X-599833Y6411D01*
G01X-606886Y5573D02*
X-606723Y5489D01*
G01X-608199Y5573D02*
X-608035Y5489D01*
G01X-610577Y5573D02*
X-610414Y5489D01*
G01X-611890Y5573D02*
X-611726Y5489D01*
G01X-580959Y106862D02*
G03I-2244J0D01*
G01X-570959D02*
G03I-2244J0D01*
G01X-560959D02*
G03I-2244J0D01*
G01X-580959Y96862D02*
G03I-2244J0D01*
G01X-570959D02*
G03I-2244J0D01*
G01X-560959D02*
G03I-2244J0D01*
G01X-600959Y106862D02*
G03I-2244J0D01*
G01Y96862D02*
G03I-2244J0D01*
G01X-590959Y106862D02*
G03I-2244J0D01*
G01Y96862D02*
G03I-2244J0D01*
G01X-562453Y97612D02*
X-561953Y98112D01*
G01X-563953Y96112D02*
X-564453Y95612D01*
G01X-562453Y107612D02*
X-561953Y108112D01*
G01X-572453Y97612D02*
X-571953Y98112D01*
G01X-573953Y96112D02*
X-574453Y95612D01*
G01X-563953Y106112D02*
X-564453Y105612D01*
G01X-572453Y107612D02*
X-571953Y108112D01*
G01X-582453Y97612D02*
X-581953Y98112D01*
G01X-583953Y96112D02*
X-584453Y95612D01*
G01X-573953Y106112D02*
X-574453Y105612D01*
G01X-582453Y107612D02*
X-581953Y108112D01*
G01X-592453Y97612D02*
X-591953Y98112D01*
G01X-593953Y96112D02*
X-594453Y95612D01*
G01X-583953Y106112D02*
X-584453Y105612D01*
G01X-592453Y107612D02*
X-591953Y108112D01*
G01X-602453Y97612D02*
X-601953Y98112D01*
G01X-603953Y96112D02*
X-604453Y95612D01*
G01X-593953Y106112D02*
X-594453Y105612D01*
G01X-618990Y88575D02*
X-618203Y89362D01*
G01X-602453Y107612D02*
X-601953Y108112D01*
G01X-603953Y106112D02*
X-604453Y105612D01*
G01X-566303Y119362D02*
X-623203D01*
G01X-617199Y117362D02*
X-606699D01*
G01X-618990Y115150D02*
X-566303D01*
G01X-498203Y114362D02*
X-618203D01*
G01X-617199Y113362D02*
X-611199D01*
G01X-509707D02*
X-606699D01*
G01X-601953Y108112D02*
X-604453D01*
G01X-591953D02*
X-594453D01*
G01X-581953D02*
X-584453D01*
G01X-571953D02*
X-574453D01*
G01X-561953D02*
X-564453D01*
G01X-602453Y107612D02*
X-603953D01*
G01X-592453D02*
X-593953D01*
G01X-582453D02*
X-583953D01*
G01X-572453D02*
X-573953D01*
G01X-562453D02*
X-563953D01*
G01Y106112D02*
X-562453D01*
G01X-573953D02*
X-572453D01*
G01X-583953D02*
X-582453D01*
G01X-593953D02*
X-592453D01*
G01X-603953D02*
X-602453D01*
G01X-564453Y105612D02*
X-561953D01*
G01X-574453D02*
X-571953D01*
G01X-584453D02*
X-581953D01*
G01X-594453D02*
X-591953D01*
G01X-604453D02*
X-601953D01*
G01X-606699Y103362D02*
X-509707D01*
G01X-606699Y100362D02*
X-509707D01*
G01X-601953Y98112D02*
X-604453D01*
G01X-591953D02*
X-594453D01*
G01X-581953D02*
X-584453D01*
G01X-571953D02*
X-574453D01*
G01X-561953D02*
X-564453D01*
G01X-602453Y97612D02*
X-603953D01*
G01X-592453D02*
X-593953D01*
G01X-582453D02*
X-583953D01*
G01X-572453D02*
X-573953D01*
G01X-562453D02*
X-563953D01*
G01Y96112D02*
X-562453D01*
G01X-573953D02*
X-572453D01*
G01X-583953D02*
X-582453D01*
G01X-593953D02*
X-592453D01*
G01X-603953D02*
X-602453D01*
G01X-564453Y95612D02*
X-561953D01*
G01X-574453D02*
X-571953D01*
G01X-584453D02*
X-581953D01*
G01X-594453D02*
X-591953D01*
G01X-604453D02*
X-601953D01*
G01X-499207Y90362D02*
X-617199D01*
G01X-618203Y89362D02*
X-498203D01*
G01X-618990Y88575D02*
X-497415D01*
G01X-493203Y84362D02*
X-623203D01*
G01X-556703Y113362D02*
Y90362D01*
G01X-559703D02*
Y113362D01*
G01X-561953Y105612D02*
Y108112D01*
G01Y95612D02*
Y98112D01*
G01X-562453Y106112D02*
Y107612D01*
G01Y96112D02*
Y97612D01*
G01X-563953D02*
Y96112D01*
G01Y107612D02*
Y106112D01*
G01X-564453Y98112D02*
Y95612D01*
G01Y108112D02*
Y105612D01*
G01X-566303Y119362D02*
Y114362D01*
G01X-566703Y113362D02*
Y90362D01*
G01X-569703D02*
Y113362D01*
G01X-571953Y105612D02*
Y108112D01*
G01Y95612D02*
Y98112D01*
G01X-572453Y106112D02*
Y107612D01*
G01Y96112D02*
Y97612D01*
G01X-573953D02*
Y96112D01*
G01Y107612D02*
Y106112D01*
G01X-574453Y98112D02*
Y95612D01*
G01Y108112D02*
Y105612D01*
G01X-576703Y113362D02*
Y90362D01*
G01X-579703D02*
Y113362D01*
G01X-581953Y105612D02*
Y108112D01*
G01Y95612D02*
Y98112D01*
G01X-582453Y106112D02*
Y107612D01*
G01Y96112D02*
Y97612D01*
G01X-583953D02*
Y96112D01*
G01Y107612D02*
Y106112D01*
G01X-584453Y98112D02*
Y95612D01*
G01Y108112D02*
Y105612D01*
G01X-586703Y113362D02*
Y90362D01*
G01X-589703D02*
Y113362D01*
G01X-591953Y105612D02*
Y108112D01*
G01Y95612D02*
Y98112D01*
G01X-592453Y106112D02*
Y107612D01*
G01Y96112D02*
Y97612D01*
G01X-593953D02*
Y96112D01*
G01Y107612D02*
Y106112D01*
G01X-594453Y98112D02*
Y95612D01*
G01Y108112D02*
Y105612D01*
G01X-596703Y113362D02*
Y90362D01*
G01X-599703D02*
Y113362D01*
G01X-601953Y105612D02*
Y108112D01*
G01Y95612D02*
Y98112D01*
G01X-602453Y106112D02*
Y107612D01*
G01Y96112D02*
Y97612D01*
G01X-603953D02*
Y96112D01*
G01Y107612D02*
Y106112D01*
G01X-604453Y98112D02*
Y95612D01*
G01Y108112D02*
Y105612D01*
G01X-606699Y117362D02*
Y90362D01*
G01X-611199Y113362D02*
Y90362D01*
G01X-617199D02*
Y117362D01*
G01X-618203Y114362D02*
Y89362D01*
G01X-618990Y115150D02*
Y88575D01*
G01X-623203Y84362D02*
Y119362D01*
G01X-562453Y106112D02*
X-561953Y105612D01*
G01X-563953Y107612D02*
X-564453Y108112D01*
G01X-562453Y96112D02*
X-561953Y95612D01*
G01X-572453Y106112D02*
X-571953Y105612D01*
G01X-573953Y107612D02*
X-574453Y108112D01*
G01X-563953Y97612D02*
X-564453Y98112D01*
G01X-572453Y96112D02*
X-571953Y95612D01*
G01X-582453Y106112D02*
X-581953Y105612D01*
G01X-583953Y107612D02*
X-584453Y108112D01*
G01X-573953Y97612D02*
X-574453Y98112D01*
G01X-582453Y96112D02*
X-581953Y95612D01*
G01X-592453Y106112D02*
X-591953Y105612D01*
G01X-593953Y107612D02*
X-594453Y108112D01*
G01X-583953Y97612D02*
X-584453Y98112D01*
G01X-592453Y96112D02*
X-591953Y95612D01*
G01X-602453Y106112D02*
X-601953Y105612D01*
G01X-603953Y107612D02*
X-604453Y108112D01*
G01X-593953Y97612D02*
X-594453Y98112D01*
G01X-618990Y115150D02*
X-618203Y114362D01*
G01X-602453Y96112D02*
X-601953Y95612D01*
G01X-603953Y97612D02*
X-604453Y98112D01*
G01X-586352Y549406D02*
X-563386D01*
G01Y544380D02*
X-586352D01*
G01Y528465D02*
X-591273D01*
G01X-558465D02*
X-563386D01*
G01X-613419Y556108D02*
X-597835Y547731D01*
G01X-603576D02*
X-615059Y553595D01*
G01Y541867D02*
X-603576Y547731D01*
G01X-597835D02*
X-613419Y539355D01*
G01D02*
X-615059Y541867D01*
G01Y553595D02*
X-613419Y556108D01*
G01X-558465Y567835D02*
Y528465D01*
G01X-563386Y549406D02*
Y567835D01*
G01Y528465D02*
Y544380D01*
G01X-586352D02*
Y528465D01*
G01Y567835D02*
Y549406D01*
G01X-591273Y528465D02*
Y567835D01*
G01X-622441Y537679D02*
X-623261Y534329D01*
G01X-563386Y567835D02*
X-558465D01*
G01X-591273D02*
X-586352D01*
G01X-621621D02*
Y563647D01*
G01X-604039Y921654D02*
X-604531Y921570D01*
G01X-604039Y917717D02*
X-603547Y917801D01*
G01X-604039Y921235D02*
X-604449Y921151D01*
G01X-604039Y918136D02*
X-603629Y918220D01*
G01X-595099Y921654D02*
X-594607D01*
G01X-601906D02*
X-601414D01*
G01X-597887D02*
X-597395D01*
G01X-606581D02*
X-606172D01*
G01X-610272D02*
X-609862D01*
G01X-611585D02*
X-611175D01*
G01X-609206D02*
X-608796D01*
G01X-607894D02*
X-607484D01*
G01X-612897D02*
X-612487D01*
G01X-597395Y919811D02*
X-595099D01*
G01X-610847Y919308D02*
X-610683D01*
G01X-608468D02*
X-608222D01*
G01X-607156D02*
X-606992D01*
G01X-612159D02*
X-611913D01*
G01X-595099D02*
X-597395D01*
G01X-611995Y918973D02*
X-612323D01*
G01X-609862D02*
X-610272D01*
G01X-610683D02*
X-611010D01*
G01X-606992D02*
X-607320D01*
G01X-608304D02*
X-608632D01*
G01X-606172D02*
X-606581D01*
G01X-601414Y917717D02*
X-601906D01*
G01X-597395D02*
X-597887D01*
G01X-594607D02*
X-595099D01*
G01X-603547Y921570D02*
X-604039Y921654D01*
G01X-604531Y917801D02*
X-604039Y917717D01*
G01X-603629Y921151D02*
X-604039Y921235D01*
G01X-604449Y918220D02*
X-604039Y918136D01*
G01X-607320Y918973D02*
X-607566Y919057D01*
G01X-608632Y918973D02*
X-608878Y919057D01*
G01X-611010Y918973D02*
X-611257Y919057D01*
G01X-612323Y918973D02*
X-612569Y919057D01*
G01X-600102Y920481D02*
X-598544Y919644D01*
G01X-599118D02*
X-600266Y920230D01*
G01X-607320Y919392D02*
X-607156Y919308D01*
G01X-608632Y919392D02*
X-608468Y919308D01*
G01X-611010Y919392D02*
X-610847Y919308D01*
G01X-612323Y919392D02*
X-612159Y919308D01*
G01X-603383Y920984D02*
X-603629Y921151D01*
G01X-604695Y918387D02*
X-604449Y918220D01*
G01X-603136Y921319D02*
X-603547Y921570D01*
G01X-604941Y918052D02*
X-604531Y917801D01*
G01X-602890Y921068D02*
X-603136Y921319D01*
G01X-605187Y918303D02*
X-604941Y918052D01*
G01X-607402Y919476D02*
X-607320Y919392D01*
G01X-607566Y919057D02*
X-607812Y919308D01*
G01X-608714Y919476D02*
X-608632Y919392D01*
G01X-608878Y919057D02*
X-609042Y919225D01*
G01X-611093Y919476D02*
X-611010Y919392D01*
G01X-611257Y919057D02*
X-611503Y919308D01*
G01X-612405Y919476D02*
X-612323Y919392D01*
G01X-612569Y919057D02*
X-612733Y919225D01*
G01X-600102Y918806D02*
X-600266Y919057D01*
G01X-603055Y920481D02*
X-603383Y920984D01*
G01X-605023Y918890D02*
X-604695Y918387D01*
G01X-602727Y920732D02*
X-602890Y921068D01*
G01X-605351Y918638D02*
X-605187Y918303D01*
G01X-607484Y919644D02*
X-607402Y919476D01*
G01X-608796Y919644D02*
X-608714Y919476D01*
G01X-611175Y919644D02*
X-611093Y919476D01*
G01X-612487Y919644D02*
X-612405Y919476D01*
G01X-602644Y920481D02*
X-602727Y920732D01*
G01X-605433Y918890D02*
X-605351Y918638D01*
G01X-609042Y919225D02*
X-609206Y919644D01*
G01X-612733Y919225D02*
X-612897Y919644D01*
G01X-602973Y919979D02*
X-603055Y920481D01*
G01X-602562Y920062D02*
X-602644Y920481D01*
G01X-605515Y919308D02*
X-605433Y918890D01*
G01X-605105Y919392D02*
X-605023Y918890D01*
G01X-594607Y921654D02*
Y917717D01*
G01X-595099Y919811D02*
Y921654D01*
G01Y917717D02*
Y919308D01*
G01X-597395D02*
Y917717D01*
G01Y921654D02*
Y919811D01*
G01X-597887Y917717D02*
Y921654D01*
G01X-600922Y918973D02*
Y918303D01*
G01X-601414Y921654D02*
Y918387D01*
G01X-601906Y917717D02*
Y921654D01*
G01X-602562Y919308D02*
Y920062D01*
G01X-602973Y919392D02*
Y919979D01*
G01X-605105D02*
Y919392D01*
G01X-605515Y920062D02*
Y919308D01*
G01X-606172Y921654D02*
Y918973D01*
G01X-606581Y919560D02*
Y921654D01*
G01Y918973D02*
Y919225D01*
G01X-607484Y921654D02*
Y919644D01*
G01X-607894D02*
Y921654D01*
G01X-608796D02*
Y919644D01*
G01X-609206D02*
Y921654D01*
G01X-609862D02*
Y918973D01*
G01X-610272Y919560D02*
Y921654D01*
G01Y918973D02*
Y919225D01*
G01X-611175Y921654D02*
Y919644D01*
G01X-611585D02*
Y921654D01*
G01X-612487D02*
Y919644D01*
G01X-612897D02*
Y921654D01*
G01X-606746Y919057D02*
X-606992Y918973D01*
G01Y919308D02*
X-606746Y919392D01*
G01X-608058Y919057D02*
X-608304Y918973D01*
G01X-610436Y919057D02*
X-610683Y918973D01*
G01Y919308D02*
X-610436Y919392D01*
G01X-611749Y919057D02*
X-611995Y918973D01*
G01X-602727Y918638D02*
X-602644Y918890D01*
G01X-605351Y920732D02*
X-605433Y920481D01*
G01X-602644Y918890D02*
X-602562Y919308D01*
G01X-605433Y920481D02*
X-605515Y920062D01*
G01X-603055Y918890D02*
X-602973Y919392D01*
G01X-605023Y920481D02*
X-605105Y919979D01*
G01X-600266Y919057D02*
X-599118Y919644D01*
G01X-608222Y919308D02*
X-608058Y919392D01*
G01X-611913Y919308D02*
X-611749Y919392D01*
G01X-598544Y919644D02*
X-600102Y918806D01*
G01X-603547Y917801D02*
X-603136Y918052D01*
G01X-604531Y921570D02*
X-604941Y921319D01*
G01X-603629Y918220D02*
X-603383Y918387D01*
G01X-604449Y921151D02*
X-604695Y920984D01*
G01X-603136Y918052D02*
X-602890Y918303D01*
G01X-606581Y919225D02*
X-606746Y919057D01*
G01Y919392D02*
X-606581Y919560D01*
G01X-604941Y921319D02*
X-605187Y921068D01*
G01X-607812Y919308D02*
X-608058Y919057D01*
G01Y919392D02*
X-607976Y919476D01*
G01X-610272Y919225D02*
X-610436Y919057D01*
G01Y919392D02*
X-610272Y919560D01*
G01X-611503Y919308D02*
X-611749Y919057D01*
G01Y919392D02*
X-611667Y919476D01*
G01X-600922Y918303D02*
X-601414Y917717D01*
G01Y918387D02*
X-600922Y918973D01*
G01X-600266Y920230D02*
X-600102Y920481D01*
G01X-603383Y918387D02*
X-603055Y918890D01*
G01X-604695Y920984D02*
X-605023Y920481D01*
G01X-602890Y918303D02*
X-602727Y918638D01*
G01X-605187Y921068D02*
X-605351Y920732D01*
G01X-607976Y919476D02*
X-607894Y919644D01*
G01X-611667Y919476D02*
X-611585Y919644D01*
G01X-522835Y-7874D02*
G03Y0I0J3937D01*
G01X-492126D02*
G03Y-7874I0J-3937D01*
G01X-365355D02*
X-492126D01*
G01Y0D02*
X-522835D01*
G01X-550959Y106862D02*
G03I-2244J0D01*
G01X-540959D02*
G03I-2244J0D01*
G01X-530959D02*
G03I-2244J0D01*
G01X-520959D02*
G03I-2244J0D01*
G01X-510959D02*
G03I-2244J0D01*
G01X-550959Y96862D02*
G03I-2244J0D01*
G01X-540959D02*
G03I-2244J0D01*
G01X-530959D02*
G03I-2244J0D01*
G01X-520959D02*
G03I-2244J0D01*
G01X-510959D02*
G03I-2244J0D01*
G01X-512795Y111209D02*
X-512918Y111167D01*
G01X-513123Y111292D02*
X-512959Y111418D01*
G01X-512453Y97612D02*
X-511953Y98112D01*
G01X-513953Y96112D02*
X-514453Y95612D01*
G01X-497415Y115150D02*
X-498203Y114362D01*
G01X-512453Y107612D02*
X-511953Y108112D01*
G01X-522453Y97612D02*
X-521953Y98112D01*
G01X-523953Y96112D02*
X-524453Y95612D01*
G01X-513953Y106112D02*
X-514453Y105612D01*
G01X-522453Y107612D02*
X-521953Y108112D01*
G01X-532453Y97612D02*
X-531953Y98112D01*
G01X-533953Y96112D02*
X-534453Y95612D01*
G01X-523953Y106112D02*
X-524453Y105612D01*
G01X-532453Y107612D02*
X-531953Y108112D01*
G01X-542453Y97612D02*
X-541953Y98112D01*
G01X-543953Y96112D02*
X-544453Y95612D01*
G01X-533953Y106112D02*
X-534453Y105612D01*
G01X-542453Y107612D02*
X-541953Y108112D01*
G01X-552453Y97612D02*
X-551953Y98112D01*
G01X-553953Y96112D02*
X-554453Y95612D01*
G01X-543953Y106112D02*
X-544453Y105612D01*
G01X-552453Y107612D02*
X-551953Y108112D01*
G01X-553953Y106112D02*
X-554453Y105612D01*
G01X-512918Y111167D02*
X-513000Y111083D01*
G01X-513615Y110664D02*
X-513861Y110371D01*
G01Y110706D02*
X-513615Y110999D01*
G01X-513246Y111125D02*
X-513123Y111292D01*
G01X-512959Y111418D02*
X-512754Y111460D01*
G01X-513000Y111083D02*
X-513041Y110957D01*
G01X-513287Y110999D02*
X-513246Y111125D01*
G01X-493203Y119362D02*
X-550103D01*
G01X-509707Y117362D02*
X-499207D01*
G01X-550103Y115150D02*
X-497415D01*
G01X-499207Y113362D02*
X-505207D01*
G01X-512016Y112339D02*
X-511770D01*
G01X-514107D02*
X-513861D01*
G01X-512754Y111460D02*
X-512016D01*
G01Y111209D02*
X-512795D01*
G01Y110580D02*
X-512016D01*
G01X-513861Y110371D02*
X-514107D01*
G01X-511770D02*
X-512754D01*
G01X-551953Y108112D02*
X-554453D01*
G01X-541953D02*
X-544453D01*
G01X-531953D02*
X-534453D01*
G01X-521953D02*
X-524453D01*
G01X-511953D02*
X-514453D01*
G01X-552453Y107612D02*
X-553953D01*
G01X-542453D02*
X-543953D01*
G01X-532453D02*
X-533953D01*
G01X-522453D02*
X-523953D01*
G01X-512453D02*
X-513953D01*
G01Y106112D02*
X-512453D01*
G01X-523953D02*
X-522453D01*
G01X-533953D02*
X-532453D01*
G01X-543953D02*
X-542453D01*
G01X-553953D02*
X-552453D01*
G01X-514453Y105612D02*
X-511953D01*
G01X-524453D02*
X-521953D01*
G01X-534453D02*
X-531953D01*
G01X-544453D02*
X-541953D01*
G01X-554453D02*
X-551953D01*
G01Y98112D02*
X-554453D01*
G01X-541953D02*
X-544453D01*
G01X-531953D02*
X-534453D01*
G01X-521953D02*
X-524453D01*
G01X-511953D02*
X-514453D01*
G01X-552453Y97612D02*
X-553953D01*
G01X-542453D02*
X-543953D01*
G01X-532453D02*
X-533953D01*
G01X-522453D02*
X-523953D01*
G01X-512453D02*
X-513953D01*
G01Y96112D02*
X-512453D01*
G01X-523953D02*
X-522453D01*
G01X-533953D02*
X-532453D01*
G01X-543953D02*
X-542453D01*
G01X-553953D02*
X-552453D01*
G01X-514453Y95612D02*
X-511953D01*
G01X-524453D02*
X-521953D01*
G01X-534453D02*
X-531953D01*
G01X-544453D02*
X-541953D01*
G01X-554453D02*
X-551953D01*
G01X-493203Y84362D02*
Y119362D01*
G01X-497415Y88575D02*
Y115150D01*
G01X-498203Y89362D02*
Y114362D01*
G01X-499207Y117362D02*
Y90362D01*
G01X-505207D02*
Y113362D01*
G01X-509707Y90362D02*
Y117362D01*
G01X-511770Y112339D02*
Y110371D01*
G01X-511953Y105612D02*
Y108112D01*
G01Y95612D02*
Y98112D01*
G01X-512016Y110580D02*
Y111209D01*
G01Y111460D02*
Y112339D01*
G01X-512453Y106112D02*
Y107612D01*
G01Y96112D02*
Y97612D01*
G01X-513041Y110957D02*
Y110831D01*
G01X-513287D02*
Y110999D01*
G01X-513615D02*
Y110664D01*
G01X-513861Y112339D02*
Y110706D01*
G01X-513953Y97612D02*
Y96112D01*
G01Y107612D02*
Y106112D01*
G01X-514107Y110371D02*
Y112339D01*
G01X-514453Y98112D02*
Y95612D01*
G01Y108112D02*
Y105612D01*
G01X-516703Y113362D02*
Y90362D01*
G01X-519703D02*
Y113362D01*
G01X-521953Y105612D02*
Y108112D01*
G01Y95612D02*
Y98112D01*
G01X-522453Y106112D02*
Y107612D01*
G01Y96112D02*
Y97612D01*
G01X-523953D02*
Y96112D01*
G01Y107612D02*
Y106112D01*
G01X-524453Y98112D02*
Y95612D01*
G01Y108112D02*
Y105612D01*
G01X-512918Y110622D02*
X-512795Y110580D01*
G01X-512754Y110371D02*
X-512959Y110413D01*
G01X-526703Y113362D02*
Y90362D01*
G01X-529703D02*
Y113362D01*
G01X-531953Y105612D02*
Y108112D01*
G01Y95612D02*
Y98112D01*
G01X-532453Y106112D02*
Y107612D01*
G01Y96112D02*
Y97612D01*
G01X-533953D02*
Y96112D01*
G01Y107612D02*
Y106112D01*
G01X-534453Y98112D02*
Y95612D01*
G01Y108112D02*
Y105612D01*
G01X-536703Y113362D02*
Y90362D01*
G01X-539703D02*
Y113362D01*
G01X-541953Y105612D02*
Y108112D01*
G01Y95612D02*
Y98112D01*
G01X-542453Y106112D02*
Y107612D01*
G01Y96112D02*
Y97612D01*
G01X-543953D02*
Y96112D01*
G01Y107612D02*
Y106112D01*
G01X-544453Y98112D02*
Y95612D01*
G01Y108112D02*
Y105612D01*
G01X-546703Y113362D02*
Y90362D01*
G01X-549703D02*
Y113362D01*
G01X-550103Y119362D02*
Y114362D01*
G01X-551953Y105612D02*
Y108112D01*
G01Y95612D02*
Y98112D01*
G01X-552453Y106112D02*
Y107612D01*
G01Y96112D02*
Y97612D01*
G01X-553953D02*
Y96112D01*
G01Y107612D02*
Y106112D01*
G01X-554453Y98112D02*
Y95612D01*
G01Y108112D02*
Y105612D01*
G01X-513041Y110831D02*
X-513000Y110706D01*
G01X-513246D02*
X-513287Y110831D01*
G01X-513123Y110539D02*
X-513246Y110706D01*
G01X-513000D02*
X-512918Y110622D01*
G01X-512453Y106112D02*
X-511953Y105612D01*
G01X-513953Y107612D02*
X-514453Y108112D01*
G01X-497415Y88575D02*
X-498203Y89362D01*
G01X-512453Y96112D02*
X-511953Y95612D01*
G01X-522453Y106112D02*
X-521953Y105612D01*
G01X-523953Y107612D02*
X-524453Y108112D01*
G01X-513953Y97612D02*
X-514453Y98112D01*
G01X-522453Y96112D02*
X-521953Y95612D01*
G01X-532453Y106112D02*
X-531953Y105612D01*
G01X-533953Y107612D02*
X-534453Y108112D01*
G01X-523953Y97612D02*
X-524453Y98112D01*
G01X-512959Y110413D02*
X-513123Y110539D01*
G01X-532453Y96112D02*
X-531953Y95612D01*
G01X-542453Y106112D02*
X-541953Y105612D01*
G01X-543953Y107612D02*
X-544453Y108112D01*
G01X-533953Y97612D02*
X-534453Y98112D01*
G01X-542453Y96112D02*
X-541953Y95612D01*
G01X-552453Y106112D02*
X-551953Y105612D01*
G01X-553953Y107612D02*
X-554453Y108112D01*
G01X-543953Y97612D02*
X-544453Y98112D01*
G01X-552453Y96112D02*
X-551953Y95612D01*
G01X-553953Y97612D02*
X-554453Y98112D01*
G01X-482284Y933071D02*
G03Y925197I0J-3937D01*
G01X-512992D02*
G03Y933071I0J3937D01*
G01Y925197D02*
X-482284D01*
G01X-414926Y65158D02*
Y62205D01*
G01X-422677Y123504D02*
Y53662D01*
G01X-426614Y70670D02*
Y53662D01*
G01X-430985Y46634D02*
Y54705D01*
G01X-434922Y43406D02*
Y133760D01*
G01X-435315Y54705D02*
Y122461D01*
G01X-435473Y54705D02*
Y122461D01*
G01X-435640D02*
Y54705D01*
G01X-435749Y122461D02*
Y54705D01*
G01X-436064D02*
Y122461D01*
G01X-436299Y54705D02*
Y122461D01*
G01X-436424D02*
Y54705D01*
G01X-436642D02*
Y122461D01*
G01X-437008Y9843D02*
Y0D01*
G01X-437015Y54705D02*
Y122461D01*
G01X-438949Y54705D02*
Y122461D01*
G01X-439292Y54705D02*
Y122461D01*
G01X-439841D02*
Y54705D01*
G01X-440276D02*
Y122461D01*
G01X-442796Y39469D02*
Y137697D01*
G01X-446733Y39351D02*
Y141634D01*
G01X-414926Y62205D02*
X-369633D01*
G01X-430985Y54705D02*
X-440273D01*
G01X-426614Y53662D02*
X-331457D01*
G01X-313780Y51300D02*
X-434922D01*
G01X-316890Y50611D02*
X-430985D01*
G01Y49803D02*
X-434922D01*
G01X-316890D02*
X-430985D01*
G01X-434922Y49016D02*
X-313780D01*
G01X-316890Y48642D02*
X-430985D01*
G01X-313780Y47835D02*
X-434922D01*
G01X-412559Y47776D02*
X-434922D01*
G01X-316890Y47618D02*
X-430985D01*
G01X-316890Y46634D02*
X-430985D01*
G01X-434922Y43406D02*
X-309843D01*
G01X-313780Y39469D02*
X-442796D01*
G01X-314961Y39351D02*
X-446733D01*
G01X-434922Y133760D02*
X-309843D01*
G01X-316890Y130532D02*
X-430985D01*
G01X-316890Y129548D02*
X-430985D01*
G01X-434922Y129390D02*
X-412559D01*
G01X-313780Y129331D02*
X-434922D01*
G01X-316890Y128524D02*
X-430985D01*
G01X-313780Y128150D02*
X-434922D01*
G01X-430985Y127363D02*
X-316890D01*
G01X-434922D02*
X-430985D01*
G01Y126555D02*
X-316890D01*
G01X-434922Y125866D02*
X-313780D01*
G01X-414926Y112008D02*
Y114961D01*
G01X-423465Y76575D02*
Y70670D01*
G01Y86024D02*
Y80118D01*
G01Y95473D02*
Y89567D01*
G01Y104922D02*
Y99016D01*
G01X-426614Y80118D02*
Y76575D01*
G01Y80118D02*
Y76575D01*
G01Y89567D02*
Y86024D01*
G01Y89567D02*
Y86024D01*
G01Y99016D02*
Y95473D01*
G01Y99016D02*
Y95473D01*
G01Y123504D02*
Y104922D01*
G01X-430985Y122461D02*
Y130532D01*
G01X-434922Y95473D02*
Y99016D01*
G01Y86024D02*
Y89567D01*
G01Y76575D02*
Y80118D01*
G01X-331457Y123504D02*
X-426614D01*
G01X-440273Y122461D02*
X-430985D01*
G01X-414926Y114961D02*
X-369633D01*
G01X-414926Y112008D02*
X-401835D01*
G01X-423465Y104922D02*
X-434922D01*
G01X-426614Y99016D02*
X-434922D01*
G01X-423465D02*
X-434922D01*
G01X-426614Y95473D02*
X-434922D01*
G01X-423465D02*
X-434922D01*
G01X-426614Y89567D02*
X-434922D01*
G01X-423465D02*
X-434922D01*
G01Y86024D02*
X-426614D01*
G01X-434922D02*
X-423465D01*
G01X-434922Y80118D02*
X-426614D01*
G01X-434922D02*
X-423465D01*
G01X-434922Y76575D02*
X-426614D01*
G01X-434922D02*
X-423465D01*
G01X-434922Y70670D02*
X-423465D01*
G01X-401835Y65158D02*
X-414926D01*
G01X-456103Y165355D02*
G03I-590J0D01*
G01X-450591Y174705D02*
X-470670D01*
G01X-463977Y170768D02*
X-464961D01*
G01X-461418D02*
X-462402D01*
G01X-458859D02*
X-459843D01*
G01X-456299D02*
X-457284D01*
G01X-463977Y168881D02*
X-464961D01*
G01X-461418D02*
X-462402D01*
G01X-458859D02*
X-459843D01*
G01X-456299D02*
X-457284D01*
G01X-463977Y168800D02*
X-464961D01*
G01X-461418D02*
X-462402D01*
G01X-458859D02*
X-459843D01*
G01X-456299D02*
X-457284D01*
G01X-456228Y168504D02*
X-456161D01*
G01X-456496Y168455D02*
X-456170D01*
G01X-456103Y168406D02*
X-456496D01*
G01X-463977Y167405D02*
X-464961D01*
G01X-461418D02*
X-462402D01*
G01X-458859D02*
X-459843D01*
G01X-456299D02*
X-457284D01*
G01X-463977Y167323D02*
X-464961D01*
G01X-461418D02*
X-462402D01*
G01X-458859D02*
X-459843D01*
G01X-456299D02*
X-457284D01*
G01X-454528Y167126D02*
X-466733D01*
G01Y155709D02*
X-454528D01*
G01X-463977Y155512D02*
X-464961D01*
G01X-461418D02*
X-462402D01*
G01X-458859D02*
X-459843D01*
G01X-456299D02*
X-457284D01*
G01X-463977Y155431D02*
X-464961D01*
G01X-461418D02*
X-462402D01*
G01X-458859D02*
X-459843D01*
G01X-456299D02*
X-457284D01*
G01X-463977Y154036D02*
X-464961D01*
G01X-461418D02*
X-462402D01*
G01X-458859D02*
X-459843D01*
G01X-456299D02*
X-457284D01*
G01X-463977Y153954D02*
X-464961D01*
G01X-461418D02*
X-462402D01*
G01X-458859D02*
X-459843D01*
G01X-456299D02*
X-457284D01*
G01X-463977Y152067D02*
X-464961D01*
G01X-461418D02*
X-462402D01*
G01X-458859D02*
X-459843D01*
G01X-456299D02*
X-457284D01*
G01X-450591Y148130D02*
X-470670D01*
G01X-446733Y141634D02*
X-437008D01*
G01X-442796Y137697D02*
X-313780D01*
G01X-437008Y879922D02*
Y141634D01*
G01X-450591Y148130D02*
Y174705D01*
G01X-454528Y155709D02*
Y167126D01*
G01X-456103Y168455D02*
Y168406D01*
G01X-456299Y155709D02*
Y152067D01*
G01Y170768D02*
Y167126D01*
G01X-456496Y168406D02*
Y168455D01*
G01X-457284Y155709D02*
Y152067D01*
G01Y170768D02*
Y167126D01*
G01X-458859Y155709D02*
Y152067D01*
G01Y170768D02*
Y167126D01*
G01X-459843Y155709D02*
Y152067D01*
G01Y170768D02*
Y167126D01*
G01X-461418Y155709D02*
Y152067D01*
G01Y170768D02*
Y167126D01*
G01X-462402Y155709D02*
Y152067D01*
G01Y170768D02*
Y167126D01*
G01X-463977Y155709D02*
Y152067D01*
G01Y170768D02*
Y167126D01*
G01X-464961Y155709D02*
Y152067D01*
G01Y170768D02*
Y167126D01*
G01X-466733D02*
Y155709D01*
G01X-470670Y174705D02*
Y148130D01*
G01X-456161Y168504D02*
X-456103Y168455D01*
G01X-456170D02*
X-456228Y168504D01*
G01X-417012Y344365D02*
G03I-1890J0D01*
G01X-413902Y340152D02*
X-415266Y339365D01*
G01X-420437Y344798D02*
X-417288D01*
G01Y344404D02*
X-419901D01*
G01X-419432Y344011D02*
X-419968D01*
G01X-415367Y343105D02*
X-420162D01*
G01X-422538Y339365D02*
X-415266D01*
G01X-427839Y335428D02*
X-409965D01*
G01X-418146Y288150D02*
X-416096D01*
G01X-413635Y274747D02*
X-415276D01*
G01X-422538Y339365D02*
X-423902Y340152D01*
G01X-419901Y344404D02*
X-419432Y344011D01*
G01X-419968D02*
X-420437Y344404D01*
G01X-415276Y276842D02*
X-414455Y276423D01*
G01X-415276Y274747D02*
X-416506Y275166D01*
G01X-415367Y345625D02*
Y343105D01*
G01X-416096Y288150D02*
Y278098D01*
G01X-417288Y344798D02*
Y344404D01*
G01X-417642Y365625D02*
Y343105D01*
G01X-418146Y278098D02*
Y288150D01*
G01X-420162Y365625D02*
Y343105D01*
G01X-420437Y344404D02*
Y344798D01*
G01X-423902Y348577D02*
Y340152D01*
G01X-427839Y373302D02*
Y335428D01*
G01X-417326Y276004D02*
X-418146Y278098D01*
G01X-416096D02*
X-415686Y277260D01*
G01D02*
X-415276Y276842D01*
G01X-416506Y275166D02*
X-417326Y276004D01*
G01X-417012Y364365D02*
G03I-1890J0D01*
G01X-419968Y365756D02*
X-419700Y365822D01*
G01X-413902Y350152D02*
X-415266Y349365D01*
G01X-422538D02*
X-423902Y348577D01*
G01X-413902Y360152D02*
X-415266Y359365D01*
G01X-271654Y385158D02*
X-437008D01*
G01X-409965Y373302D02*
X-427839D01*
G01X-415266Y369365D02*
X-422538D01*
G01X-419700Y365822D02*
X-419566D01*
G01X-417623D02*
X-417288D01*
G01X-415367Y365625D02*
X-420162D01*
G01X-419566Y365428D02*
X-419700D01*
G01X-417288Y363459D02*
X-417623D01*
G01X-415367Y363105D02*
X-420162D01*
G01X-415367Y345625D02*
X-420162D01*
G01X-422538Y359365D02*
X-423902Y358577D01*
G01X-422538Y369365D02*
X-423902Y368577D01*
G01X-419700Y365428D02*
X-419901Y365297D01*
G01X-419566Y365822D02*
X-419298Y365756D01*
G01X-419700Y363525D02*
X-419968Y363590D01*
G01X-420236Y365494D02*
X-419968Y365756D01*
G01X-419901Y365297D02*
X-420035Y365100D01*
G01X-419298Y365756D02*
X-419097Y365625D01*
G01X-419901Y363984D02*
X-419700Y363853D01*
G01X-413902Y368577D02*
X-415266Y369365D01*
G01X-413902Y358577D02*
X-415266Y359365D01*
G01X-422538D02*
X-423902Y360152D01*
G01X-413902Y348577D02*
X-415266Y349365D01*
G01X-422538D02*
X-423902Y350152D01*
G01X-419298Y365297D02*
X-419566Y365428D01*
G01X-420370Y365231D02*
X-420236Y365494D01*
G01X-420370Y364116D02*
X-420437Y364575D01*
G01X-420102Y364509D02*
X-420035Y364181D01*
G01X-420236Y363853D02*
X-420370Y364116D01*
G01X-420035Y364181D02*
X-419901Y363984D01*
G01X-419097Y365625D02*
X-417623Y363984D01*
G01Y363459D02*
X-419298Y365297D01*
G01X-419968Y363590D02*
X-420236Y363853D01*
G01X-420035Y365100D02*
X-420102Y364772D01*
G01X-420437Y364837D02*
X-420370Y365231D01*
G01X-415367Y365625D02*
Y363105D01*
G01X-417288Y365822D02*
Y363459D01*
G01X-417623Y363984D02*
Y365822D01*
G01X-419700Y363853D02*
Y363525D01*
G01X-420102Y364772D02*
Y364509D01*
G01X-420437Y364575D02*
Y364837D01*
G01X-423902Y358577D02*
Y350152D01*
G01Y368577D02*
Y360152D01*
G01X-437008Y589882D02*
X-271654D01*
G01X-456103Y732284D02*
G03I-590J0D01*
G01X-450591Y741634D02*
X-470670D01*
G01X-463977Y737697D02*
X-464961D01*
G01X-461418D02*
X-462402D01*
G01X-458859D02*
X-459843D01*
G01X-456299D02*
X-457284D01*
G01X-463977Y735810D02*
X-464961D01*
G01X-461418D02*
X-462402D01*
G01X-458859D02*
X-459843D01*
G01X-456299D02*
X-457284D01*
G01X-463977Y735729D02*
X-464961D01*
G01X-461418D02*
X-462402D01*
G01X-458859D02*
X-459843D01*
G01X-456299D02*
X-457284D01*
G01X-456228Y735433D02*
X-456161D01*
G01X-456496Y735384D02*
X-456170D01*
G01X-456103Y735335D02*
X-456496D01*
G01X-463977Y734334D02*
X-464961D01*
G01X-461418D02*
X-462402D01*
G01X-458859D02*
X-459843D01*
G01X-456299D02*
X-457284D01*
G01X-463977Y734252D02*
X-464961D01*
G01X-461418D02*
X-462402D01*
G01X-458859D02*
X-459843D01*
G01X-456299D02*
X-457284D01*
G01X-454528Y734055D02*
X-466733D01*
G01Y722638D02*
X-454528D01*
G01X-463977Y722441D02*
X-464961D01*
G01X-461418D02*
X-462402D01*
G01X-458859D02*
X-459843D01*
G01X-456299D02*
X-457284D01*
G01X-463977Y722360D02*
X-464961D01*
G01X-461418D02*
X-462402D01*
G01X-458859D02*
X-459843D01*
G01X-456299D02*
X-457284D01*
G01X-463977Y720965D02*
X-464961D01*
G01X-461418D02*
X-462402D01*
G01X-458859D02*
X-459843D01*
G01X-456299D02*
X-457284D01*
G01X-463977Y720883D02*
X-464961D01*
G01X-461418D02*
X-462402D01*
G01X-458859D02*
X-459843D01*
G01X-456299D02*
X-457284D01*
G01X-463977Y718996D02*
X-464961D01*
G01X-461418D02*
X-462402D01*
G01X-458859D02*
X-459843D01*
G01X-456299D02*
X-457284D01*
G01X-450591Y715059D02*
X-470670D01*
G01X-456161Y735433D02*
X-456103Y735384D01*
G01X-456170D02*
X-456228Y735433D01*
G01X-450591Y715059D02*
Y741634D01*
G01X-454528Y722638D02*
Y734055D01*
G01X-456103Y735384D02*
Y735335D01*
G01X-456299Y722638D02*
Y718996D01*
G01Y737697D02*
Y734055D01*
G01X-456496Y735335D02*
Y735384D01*
G01X-457284Y722638D02*
Y718996D01*
G01Y737697D02*
Y734055D01*
G01X-458859Y722638D02*
Y718996D01*
G01Y737697D02*
Y734055D01*
G01X-459843Y722638D02*
Y718996D01*
G01Y737697D02*
Y734055D01*
G01X-461418Y722638D02*
Y718996D01*
G01Y737697D02*
Y734055D01*
G01X-462402Y722638D02*
Y718996D01*
G01Y737697D02*
Y734055D01*
G01X-463977Y722638D02*
Y718996D01*
G01Y737697D02*
Y734055D01*
G01X-464961Y722638D02*
Y718996D01*
G01Y737697D02*
Y734055D01*
G01X-466733D02*
Y722638D01*
G01X-470670Y741634D02*
Y715059D01*
G01X-236221Y879922D02*
X-437008D01*
G01X-482284Y933071D02*
X-316142D01*
G01X-437008Y915355D02*
Y925197D01*
G01X-365355Y-7874D02*
G03Y0I0J3937D01*
G01X-379173Y50748D02*
G03I-1890J0D01*
G01X-382168Y66823D02*
G03X-379958I1105J-1862D01*
G01X-380305Y62311D02*
G03X-379031Y66823I-758J2650D01*
G01X-383095D02*
G03X-381821Y62311I2032J-1862D01*
G01X-378189Y50748D02*
G03I-2874J0D01*
G01X-378012Y64961D02*
G03I-3051J0D01*
G01Y50748D02*
G03I-3051J0D01*
G01X-400748Y48819D02*
G03I-3937J0D01*
G01X-341693D02*
G03I-3937J0D01*
G01X-399764D02*
G03I-4921J0D01*
G01X-340709D02*
G03I-4921J0D01*
G01X-337756D02*
G03I-7874J0D01*
G01X-396811D02*
G03I-7874J0D01*
G01X-381890Y19685D02*
G03I-9843J0D01*
G01X-334646D02*
G03I-9842J0D01*
G01X-373032D02*
G03I-18701J0D01*
G01X-325788D02*
G03I-18700J0D01*
G01X-353504Y47776D02*
Y43406D01*
G01X-369633Y114961D02*
Y62205D01*
G01X-373412Y67467D02*
Y62205D01*
G01X-374790Y67467D02*
Y62205D01*
G01X-384749Y67467D02*
Y62205D01*
G01X-384927D02*
Y67467D01*
G01X-396811Y43406D02*
Y47776D01*
G01X-398707Y114961D02*
Y62205D01*
G01X-401018D02*
Y114961D01*
G01X-407060Y62205D02*
Y114961D01*
G01X-407847Y65158D02*
Y62205D01*
G01X-408241Y65158D02*
Y62205D01*
G01X-408635Y65158D02*
Y62205D01*
G01X-412559Y47776D02*
Y43406D01*
G01X-380305Y62311D02*
X-381821D01*
G01X-369633Y62755D02*
X-373133Y65355D01*
G01X-396811Y47776D02*
X-353504D01*
G01X-334646Y0D02*
X-365355D01*
G01X-379173Y126418D02*
G03I-1890J0D01*
G01X-379958Y110343D02*
G03X-382168I-1105J1862D01*
G01X-381821Y114855D02*
G03X-383095Y110343I758J-2650D01*
G01X-379031D02*
G03X-380305Y114855I-2032J1862D01*
G01X-378189Y126418D02*
G03I-2874J0D01*
G01X-378012Y112205D02*
G03I-3051J0D01*
G01Y126418D02*
G03I-3051J0D01*
G01X-341693Y128347D02*
G03I-3937J0D01*
G01X-400748D02*
G03I-3937J0D01*
G01X-399764D02*
G03I-4921J0D01*
G01X-340709D02*
G03I-4921J0D01*
G01X-396811D02*
G03I-7874J0D01*
G01X-337756D02*
G03I-7874J0D01*
G01X-400601Y71031D02*
X-401732Y70661D01*
G01X-402402Y70456D02*
X-401899Y70620D01*
G01X-410453Y68524D02*
X-410579Y68483D01*
G01X-410621Y68729D02*
X-410495Y68770D01*
G01X-411291Y68524D02*
X-411417Y68483D01*
G01X-411333Y68770D02*
X-411459Y68729D01*
G01X-400433Y70866D02*
X-402402Y70210D01*
G01X-384009Y110118D02*
X-384156Y110068D01*
G01D02*
X-384353Y109970D01*
G01X-410286Y68647D02*
X-410453Y68524D01*
G01X-411123Y68647D02*
X-411291Y68524D01*
G01X-369633Y114411D02*
X-373133Y111811D01*
G01X-410495Y68770D02*
X-410411Y68852D01*
G01X-411249D02*
X-411333Y68770D01*
G01X-403410Y80459D02*
X-402622Y81246D01*
G01X-384353Y109970D02*
X-384501Y109822D01*
G01X-403410Y93057D02*
X-402622Y93845D01*
G01X-410160Y68811D02*
X-410286Y68647D01*
G01X-384501Y109822D02*
X-384648Y109626D01*
G01X-380514Y111397D02*
X-381843Y109478D01*
G01X-378546Y113415D02*
X-379924Y111397D01*
G01X-379186Y113415D02*
X-380219Y111889D01*
G01Y110954D02*
X-381203Y109478D01*
G01X-411081Y68729D02*
X-411123Y68647D01*
G01X-375839Y112627D02*
X-377070Y109478D01*
G01X-376085Y113415D02*
X-377266Y110364D01*
G01X-410411Y68852D02*
X-410370Y68975D01*
G01X-411207D02*
X-411249Y68852D01*
G01X-384648Y109626D02*
X-384697Y109478D01*
G01X-410118Y69016D02*
X-410160Y68811D01*
G01X-353504Y133760D02*
Y129390D01*
G01X-372622Y112191D02*
Y64975D01*
G01X-373412Y114961D02*
Y109699D01*
G01X-373526Y109084D02*
Y113809D01*
G01X-373920Y109478D02*
Y113415D01*
G01X-374412D02*
Y110364D01*
G01X-374790Y109699D02*
Y114961D01*
G01X-376368Y107874D02*
Y108662D01*
G01Y104725D02*
Y105512D01*
G01Y100000D02*
Y100788D01*
G01Y101575D02*
Y102363D01*
G01Y95276D02*
Y96063D01*
G01Y98426D02*
Y99213D01*
G01Y92126D02*
Y92914D01*
G01Y85827D02*
Y86615D01*
G01Y88977D02*
Y89764D01*
G01Y82677D02*
Y83465D01*
G01Y79528D02*
Y80315D01*
G01Y76378D02*
Y77166D01*
G01Y73229D02*
Y74016D01*
G01Y70079D02*
Y70866D01*
G01Y69292D02*
Y68504D01*
G01Y72441D02*
Y71654D01*
G01Y75591D02*
Y74803D01*
G01Y78740D02*
Y77953D01*
G01Y85040D02*
Y84252D01*
G01Y81890D02*
Y81103D01*
G01Y88189D02*
Y87402D01*
G01Y94489D02*
Y93701D01*
G01Y91339D02*
Y90552D01*
G01Y97638D02*
Y96851D01*
G01Y103937D02*
Y103150D01*
G01Y107087D02*
Y106300D01*
G01X-377266Y110364D02*
Y113415D01*
G01X-377759D02*
Y109478D01*
G01X-380131Y107874D02*
Y108662D01*
G01Y104725D02*
Y105512D01*
G01Y101575D02*
Y102363D01*
G01Y95276D02*
Y96063D01*
G01Y98426D02*
Y99213D01*
G01Y92126D02*
Y92914D01*
G01Y85827D02*
Y86615D01*
G01Y88977D02*
Y89764D01*
G01Y82677D02*
Y83465D01*
G01Y79528D02*
Y80315D01*
G01Y76378D02*
Y77166D01*
G01Y73229D02*
Y74016D01*
G01Y70079D02*
Y70866D01*
G01Y69292D02*
Y68504D01*
G01Y72441D02*
Y71654D01*
G01Y75591D02*
Y74803D01*
G01Y78740D02*
Y77953D01*
G01Y85040D02*
Y84252D01*
G01Y81890D02*
Y81103D01*
G01Y88189D02*
Y87402D01*
G01Y94489D02*
Y93701D01*
G01Y91339D02*
Y90552D01*
G01Y97638D02*
Y96851D01*
G01Y100788D02*
Y100000D01*
G01Y103937D02*
Y103150D01*
G01Y107087D02*
Y106300D01*
G01X-381333Y68898D02*
Y108268D01*
G01X-382773Y106300D02*
Y107087D01*
G01Y107874D02*
Y108662D01*
G01Y104725D02*
Y105512D01*
G01Y103150D02*
Y103937D01*
G01Y101575D02*
Y102363D01*
G01Y98426D02*
Y99213D01*
G01Y90552D02*
Y91339D01*
G01Y92126D02*
Y92914D01*
G01Y85827D02*
Y86615D01*
G01Y81103D02*
Y81890D01*
G01Y82677D02*
Y83465D01*
G01Y79528D02*
Y80315D01*
G01Y74803D02*
Y75591D01*
G01Y73229D02*
Y74016D01*
G01Y69292D02*
Y68504D01*
G01Y70866D02*
Y70079D01*
G01Y72441D02*
Y71654D01*
G01Y78740D02*
Y77953D01*
G01Y77166D02*
Y76378D01*
G01Y85040D02*
Y84252D01*
G01Y88189D02*
Y87402D01*
G01Y89764D02*
Y88977D01*
G01Y94489D02*
Y93701D01*
G01Y97638D02*
Y96851D01*
G01Y96063D02*
Y95276D01*
G01Y100788D02*
Y100000D01*
G01X-383664Y110167D02*
Y110561D01*
G01X-383677Y106300D02*
Y107087D01*
G01Y100000D02*
Y100788D01*
G01Y103150D02*
Y103937D01*
G01Y96851D02*
Y97638D01*
G01Y93701D02*
Y94489D01*
G01Y90552D02*
Y91339D01*
G01Y87402D02*
Y88189D01*
G01Y84252D02*
Y85040D01*
G01Y81103D02*
Y81890D01*
G01Y77953D02*
Y78740D01*
G01Y71654D02*
Y72441D01*
G01Y74803D02*
Y75591D01*
G01Y68504D02*
Y69292D01*
G01Y70866D02*
Y70079D01*
G01Y74016D02*
Y73229D01*
G01Y80315D02*
Y79528D01*
G01Y77166D02*
Y76378D01*
G01Y83465D02*
Y82677D01*
G01Y86615D02*
Y85827D01*
G01Y89764D02*
Y88977D01*
G01Y92914D02*
Y92126D01*
G01Y96063D02*
Y95276D01*
G01Y99213D02*
Y98426D01*
G01Y102363D02*
Y101575D01*
G01Y108662D02*
Y107874D01*
G01Y105512D02*
Y104725D01*
G01X-384599Y110561D02*
Y113415D01*
G01X-384644Y106300D02*
Y107087D01*
G01Y100000D02*
Y100788D01*
G01Y103150D02*
Y103937D01*
G01Y96851D02*
Y97638D01*
G01Y93701D02*
Y94489D01*
G01Y90552D02*
Y91339D01*
G01Y87402D02*
Y88189D01*
G01Y84252D02*
Y85040D01*
G01Y81103D02*
Y81890D01*
G01Y77953D02*
Y78740D01*
G01Y71654D02*
Y72441D01*
G01Y74803D02*
Y75591D01*
G01Y68504D02*
Y69292D01*
G01Y70866D02*
Y70079D01*
G01Y74016D02*
Y73229D01*
G01Y80315D02*
Y79528D01*
G01Y77166D02*
Y76378D01*
G01Y83465D02*
Y82677D01*
G01Y86615D02*
Y85827D01*
G01Y89764D02*
Y88977D01*
G01Y92914D02*
Y92126D01*
G01Y96063D02*
Y95276D01*
G01Y99213D02*
Y98426D01*
G01Y102363D02*
Y101575D01*
G01Y108662D02*
Y107874D01*
G01Y105512D02*
Y104725D01*
G01X-384749Y109699D02*
Y114961D01*
G01X-384927Y109699D02*
Y114961D01*
G01X-385091Y113415D02*
Y109478D01*
G01X-385485Y113809D02*
Y109084D01*
G01X-353504Y129390D02*
X-396811D01*
G01X-383762Y110167D02*
X-384009Y110118D01*
G01X-392967Y111811D02*
Y65355D01*
G01X-393755Y111811D02*
Y65355D01*
G01X-396811Y129390D02*
Y133760D01*
G01X-399776Y70866D02*
Y70079D01*
G01Y74016D02*
Y73229D01*
G01Y80315D02*
Y79528D01*
G01Y77166D02*
Y76378D01*
G01Y83465D02*
Y82677D01*
G01Y89764D02*
Y88977D01*
G01Y86615D02*
Y85827D01*
G01Y92914D02*
Y92126D01*
G01Y99213D02*
Y98426D01*
G01Y96063D02*
Y95276D01*
G01Y102363D02*
Y101575D01*
G01Y108662D02*
Y107874D01*
G01Y105512D02*
Y104725D01*
G01X-400376Y107874D02*
Y108662D01*
G01Y104725D02*
Y105512D01*
G01Y101575D02*
Y102363D01*
G01Y98426D02*
Y99213D01*
G01Y95276D02*
Y96063D01*
G01Y92126D02*
Y92914D01*
G01Y88977D02*
Y89764D01*
G01Y85827D02*
Y86615D01*
G01Y82677D02*
Y83465D01*
G01Y79528D02*
Y80315D01*
G01Y76378D02*
Y77166D01*
G01Y73229D02*
Y74016D01*
G01Y70079D02*
Y70866D01*
G01X-400433Y69636D02*
Y69390D01*
G01Y71194D02*
Y70866D01*
G01X-401411D02*
Y70079D01*
G01Y74016D02*
Y73229D01*
G01Y80315D02*
Y79528D01*
G01Y77166D02*
Y76378D01*
G01Y83465D02*
Y82677D01*
G01Y89764D02*
Y88977D01*
G01Y86615D02*
Y85827D01*
G01Y92914D02*
Y92126D01*
G01Y99213D02*
Y98426D01*
G01Y96063D02*
Y95276D01*
G01Y102363D02*
Y101575D01*
G01Y108662D02*
Y107874D01*
G01Y105512D02*
Y104725D01*
G01X-401732Y70661D02*
Y71400D01*
G01X-401835Y112008D02*
Y65158D01*
G01X-401899Y70620D02*
Y71440D01*
G01X-402402Y69390D02*
Y69636D01*
G01Y70210D02*
Y70456D01*
G01Y71605D02*
Y71851D01*
G01X-402622Y81246D02*
Y65158D01*
G01Y93845D02*
Y81746D01*
G01Y112008D02*
Y94345D01*
G01X-402870Y70866D02*
Y70079D01*
G01Y74016D02*
Y73229D01*
G01Y80315D02*
Y79528D01*
G01Y77166D02*
Y76378D01*
G01Y83465D02*
Y82677D01*
G01Y89764D02*
Y88977D01*
G01Y86615D02*
Y85827D01*
G01Y92914D02*
Y92126D01*
G01Y99213D02*
Y98426D01*
G01Y96063D02*
Y95276D01*
G01Y102363D02*
Y101575D01*
G01Y108662D02*
Y107874D01*
G01Y105512D02*
Y104725D01*
G01X-402887Y107874D02*
Y108662D01*
G01Y104725D02*
Y105512D01*
G01Y101575D02*
Y102363D01*
G01Y98426D02*
Y99213D01*
G01Y95276D02*
Y96063D01*
G01Y92126D02*
Y92914D01*
G01Y88977D02*
Y89764D01*
G01Y85827D02*
Y86615D01*
G01Y82677D02*
Y83465D01*
G01Y79528D02*
Y80315D01*
G01Y76378D02*
Y77166D01*
G01Y73229D02*
Y74016D01*
G01Y70079D02*
Y70866D01*
G01X-403165D02*
Y70079D01*
G01Y74016D02*
Y73229D01*
G01Y80315D02*
Y79528D01*
G01Y77166D02*
Y76378D01*
G01Y83465D02*
Y82677D01*
G01Y89764D02*
Y88977D01*
G01Y86615D02*
Y85827D01*
G01Y92914D02*
Y92126D01*
G01Y99213D02*
Y98426D01*
G01Y96063D02*
Y95276D01*
G01Y102363D02*
Y101575D01*
G01Y108662D02*
Y107874D01*
G01Y105512D02*
Y104725D01*
G01X-403410Y80459D02*
Y65158D01*
G01Y93057D02*
Y82534D01*
G01Y112008D02*
Y95132D01*
G01X-403453Y101575D02*
Y102363D01*
G01Y70079D02*
Y70866D01*
G01Y74016D02*
Y73229D01*
G01Y80315D02*
Y79528D01*
G01Y77166D02*
Y76378D01*
G01Y83465D02*
Y82677D01*
G01Y89764D02*
Y88977D01*
G01Y86615D02*
Y85827D01*
G01Y92914D02*
Y92126D01*
G01Y99213D02*
Y98426D01*
G01Y96063D02*
Y95276D01*
G01Y108662D02*
Y107874D01*
G01Y105512D02*
Y104725D01*
G01X-403525Y107874D02*
Y108662D01*
G01Y104725D02*
Y105512D01*
G01Y101575D02*
Y102363D01*
G01Y98426D02*
Y99213D01*
G01Y95276D02*
Y96063D01*
G01Y92126D02*
Y92914D01*
G01Y88977D02*
Y89764D01*
G01Y85827D02*
Y86615D01*
G01Y82677D02*
Y83465D01*
G01Y79528D02*
Y80315D01*
G01Y76378D02*
Y77166D01*
G01Y73229D02*
Y74016D01*
G01Y70079D02*
Y70866D01*
G01X-403803D02*
Y70079D01*
G01Y74016D02*
Y73229D01*
G01Y80315D02*
Y79528D01*
G01Y77166D02*
Y76378D01*
G01Y83465D02*
Y82677D01*
G01Y89764D02*
Y88977D01*
G01Y86615D02*
Y85827D01*
G01Y92914D02*
Y92126D01*
G01Y99213D02*
Y98426D01*
G01Y96063D02*
Y95276D01*
G01Y102363D02*
Y101575D01*
G01Y108662D02*
Y107874D01*
G01Y105512D02*
Y104725D01*
G01X-404004Y68504D02*
Y107087D01*
G01X-404024Y101575D02*
Y102363D01*
G01Y70079D02*
Y70866D01*
G01Y74016D02*
Y73229D01*
G01Y80315D02*
Y79528D01*
G01Y77166D02*
Y76378D01*
G01Y83465D02*
Y82677D01*
G01Y89764D02*
Y88977D01*
G01Y86615D02*
Y85827D01*
G01Y92914D02*
Y92126D01*
G01Y99213D02*
Y98426D01*
G01Y96063D02*
Y95276D01*
G01Y108662D02*
Y107874D01*
G01Y105512D02*
Y104725D01*
G01X-404036Y101575D02*
Y102363D01*
G01Y70079D02*
Y70866D01*
G01Y74016D02*
Y73229D01*
G01Y80315D02*
Y79528D01*
G01Y77166D02*
Y76378D01*
G01Y83465D02*
Y82677D01*
G01Y89764D02*
Y88977D01*
G01Y86615D02*
Y85827D01*
G01Y92914D02*
Y92126D01*
G01Y99213D02*
Y98426D01*
G01Y96063D02*
Y95276D01*
G01Y108662D02*
Y107874D01*
G01Y105512D02*
Y104725D01*
G01X-407847Y112008D02*
Y114961D01*
G01X-408241Y112008D02*
Y114961D01*
G01X-408635Y112008D02*
Y114961D01*
G01X-409225Y69292D02*
Y68504D01*
G01Y72441D02*
Y71654D01*
G01Y75591D02*
Y74803D01*
G01Y78740D02*
Y77953D01*
G01Y81890D02*
Y81103D01*
G01Y85040D02*
Y84252D01*
G01Y88189D02*
Y87402D01*
G01Y91339D02*
Y90552D01*
G01Y94489D02*
Y93701D01*
G01Y97638D02*
Y96851D01*
G01Y100788D02*
Y100000D01*
G01Y103937D02*
Y103150D01*
G01Y107087D02*
Y106300D01*
G01X-409825D02*
Y107087D01*
G01Y100000D02*
Y100788D01*
G01Y103150D02*
Y103937D01*
G01Y96851D02*
Y97638D01*
G01Y90552D02*
Y91339D01*
G01Y93701D02*
Y94489D01*
G01Y87402D02*
Y88189D01*
G01Y81103D02*
Y81890D01*
G01Y84252D02*
Y85040D01*
G01Y77953D02*
Y78740D01*
G01Y71654D02*
Y72441D01*
G01Y74803D02*
Y75591D01*
G01Y68504D02*
Y69292D01*
G01X-410118Y67909D02*
Y67663D01*
G01Y70000D02*
Y69016D01*
G01X-410370Y68975D02*
Y69754D01*
G01X-410836Y106300D02*
Y107087D01*
G01Y100000D02*
Y100788D01*
G01Y103150D02*
Y103937D01*
G01Y96851D02*
Y97638D01*
G01Y90552D02*
Y91339D01*
G01Y93701D02*
Y94489D01*
G01Y87402D02*
Y88189D01*
G01Y81103D02*
Y81890D01*
G01Y84252D02*
Y85040D01*
G01Y77953D02*
Y78740D01*
G01Y71654D02*
Y72441D01*
G01Y74803D02*
Y75591D01*
G01Y68504D02*
Y69292D01*
G01X-410956Y69754D02*
Y68975D01*
G01X-411203Y65158D02*
Y112008D01*
G01X-411207Y69754D02*
Y68975D01*
G01X-411400Y69292D02*
Y68504D01*
G01Y72441D02*
Y71654D01*
G01Y75591D02*
Y74803D01*
G01Y78740D02*
Y77953D01*
G01Y81890D02*
Y81103D01*
G01Y85040D02*
Y84252D01*
G01Y88189D02*
Y87402D01*
G01Y91339D02*
Y90552D01*
G01Y94489D02*
Y93701D01*
G01Y97638D02*
Y96851D01*
G01Y100788D02*
Y100000D01*
G01Y103937D02*
Y103150D01*
G01Y107087D02*
Y106300D01*
G01X-411835Y68975D02*
Y69754D01*
G01X-412087Y67663D02*
Y67909D01*
G01Y69016D02*
Y70000D01*
G01X-412559Y133760D02*
Y129390D01*
G01X-412806Y69292D02*
Y68504D01*
G01Y72441D02*
Y71654D01*
G01Y75591D02*
Y74803D01*
G01Y78740D02*
Y77953D01*
G01Y81890D02*
Y81103D01*
G01Y85040D02*
Y84252D01*
G01Y88189D02*
Y87402D01*
G01Y91339D02*
Y90552D01*
G01Y94489D02*
Y93701D01*
G01Y97638D02*
Y96851D01*
G01Y100788D02*
Y100000D01*
G01Y103937D02*
Y103150D01*
G01Y107087D02*
Y106300D01*
G01X-413406Y69292D02*
Y68504D01*
G01Y72441D02*
Y71654D01*
G01Y75591D02*
Y74803D01*
G01Y78740D02*
Y77953D01*
G01Y81890D02*
Y81103D01*
G01Y85040D02*
Y84252D01*
G01Y88189D02*
Y87402D01*
G01Y91339D02*
Y90552D01*
G01Y94489D02*
Y93701D01*
G01Y97638D02*
Y96851D01*
G01Y100788D02*
Y100000D01*
G01Y103937D02*
Y103150D01*
G01Y107087D02*
Y106300D01*
G01X-412045Y68811D02*
X-412087Y69016D01*
G01X-410956Y68975D02*
X-410914Y68852D01*
G01X-411794D02*
X-411835Y68975D01*
G01X-375593Y113415D02*
X-374412Y110364D01*
G01X-375839Y112627D02*
X-374609Y109478D01*
G01X-381821Y114855D02*
X-380305D01*
G01X-373526Y113809D02*
X-385485D01*
G01X-384599Y113415D02*
X-385091D01*
G01X-381253D02*
X-381892D01*
G01X-378546D02*
X-379186D01*
G01X-377266D02*
X-377759D01*
G01X-375593D02*
X-376085D01*
G01X-373920D02*
X-374412D01*
G01X-373133Y111811D02*
X-393755D01*
G01X-383664Y110561D02*
X-384599D01*
G01X-379031Y110343D02*
X-383095D01*
G01X-383762Y110167D02*
X-383664D01*
G01X-369633Y109699D02*
X-384927D01*
G01X-374609Y109478D02*
X-373920D01*
G01X-379235D02*
X-378595D01*
G01X-381843D02*
X-381203D01*
G01X-377759D02*
X-377070D01*
G01X-385091D02*
X-384697D01*
G01X-385485Y109084D02*
X-373526D01*
G01X-404036Y108662D02*
X-399776D01*
G01X-376368D02*
X-384644D01*
G01X-381333Y108268D02*
X-401018D01*
G01X-404036Y107874D02*
X-399776D01*
G01X-376368D02*
X-384644D01*
G01X-413406Y107087D02*
X-401018D01*
G01X-376368D02*
X-384644D01*
G01X-409225Y106300D02*
X-413406D01*
G01X-376368D02*
X-384644D01*
G01X-404036Y105512D02*
X-399776D01*
G01X-376368D02*
X-384644D01*
G01X-404036Y104725D02*
X-399776D01*
G01X-376368D02*
X-384644D01*
G01X-413406Y103937D02*
X-409225D01*
G01X-376368D02*
X-384644D01*
G01X-409225Y103150D02*
X-413406D01*
G01X-376368D02*
X-384644D01*
G01X-404036Y102363D02*
X-399776D01*
G01X-376368D02*
X-384644D01*
G01X-404036Y101575D02*
X-399776D01*
G01X-376368D02*
X-384644D01*
G01X-413406Y100788D02*
X-409225D01*
G01X-376368D02*
X-384644D01*
G01X-409225Y100000D02*
X-413406D01*
G01X-376368D02*
X-384644D01*
G01X-404036Y99213D02*
X-399776D01*
G01X-376368D02*
X-384644D01*
G01X-404036Y98426D02*
X-399776D01*
G01X-376368D02*
X-384644D01*
G01X-413406Y97638D02*
X-409225D01*
G01X-376368D02*
X-384644D01*
G01X-409225Y96851D02*
X-413406D01*
G01X-376368D02*
X-384644D01*
G01X-404036Y96063D02*
X-399776D01*
G01X-376368D02*
X-384644D01*
G01X-404036Y95276D02*
X-399776D01*
G01X-376368D02*
X-384644D01*
G01X-403410Y95132D02*
X-407060D01*
G01X-413406Y94489D02*
X-409225D01*
G01X-376368D02*
X-384644D01*
G01X-402622Y94345D02*
X-407060D01*
G01Y93845D02*
X-402622D01*
G01X-409225Y93701D02*
X-413406D01*
G01X-376368D02*
X-384644D01*
G01X-407060Y93057D02*
X-403410D01*
G01X-404036Y92914D02*
X-399776D01*
G01X-376368D02*
X-384644D01*
G01X-404036Y92126D02*
X-399776D01*
G01X-376368D02*
X-384644D01*
G01X-413406Y91339D02*
X-409225D01*
G01X-376368D02*
X-384644D01*
G01X-409225Y90552D02*
X-413406D01*
G01X-376368D02*
X-384644D01*
G01X-404036Y89764D02*
X-399776D01*
G01X-376368D02*
X-384644D01*
G01X-404036Y88977D02*
X-399776D01*
G01X-376368D02*
X-384644D01*
G01X-413406Y88189D02*
X-409225D01*
G01X-376368D02*
X-384644D01*
G01X-409225Y87402D02*
X-413406D01*
G01X-376368D02*
X-384644D01*
G01X-404036Y86615D02*
X-399776D01*
G01X-376368D02*
X-384644D01*
G01X-404036Y85827D02*
X-399776D01*
G01X-376368D02*
X-384644D01*
G01X-413406Y85040D02*
X-409225D01*
G01X-376368D02*
X-384644D01*
G01X-409225Y84252D02*
X-413406D01*
G01X-376368D02*
X-384644D01*
G01X-404036Y83465D02*
X-399776D01*
G01X-376368D02*
X-384644D01*
G01X-404036Y82677D02*
X-399776D01*
G01X-376368D02*
X-384644D01*
G01X-403410Y82534D02*
X-407060D01*
G01X-413406Y81890D02*
X-409225D01*
G01X-376368D02*
X-384644D01*
G01X-402622Y81746D02*
X-407060D01*
G01Y81246D02*
X-402622D01*
G01X-409225Y81103D02*
X-413406D01*
G01X-376368D02*
X-384644D01*
G01X-407060Y80459D02*
X-403410D01*
G01X-404036Y80315D02*
X-399776D01*
G01X-376368D02*
X-384644D01*
G01X-404036Y79528D02*
X-399776D01*
G01X-376368D02*
X-384644D01*
G01X-413406Y78740D02*
X-409225D01*
G01X-376368D02*
X-384644D01*
G01X-409225Y77953D02*
X-413406D01*
G01X-376368D02*
X-384644D01*
G01X-404036Y77166D02*
X-399776D01*
G01X-376368D02*
X-384644D01*
G01X-404036Y76378D02*
X-399776D01*
G01X-376368D02*
X-384644D01*
G01X-413406Y75591D02*
X-409225D01*
G01X-376368D02*
X-384644D01*
G01X-409225Y74803D02*
X-413406D01*
G01X-376368D02*
X-384644D01*
G01X-404036Y74016D02*
X-399776D01*
G01X-376368D02*
X-384644D01*
G01X-404036Y73229D02*
X-399776D01*
G01X-376368D02*
X-384644D01*
G01X-413406Y72441D02*
X-409225D01*
G01X-376368D02*
X-384644D01*
G01X-409225Y71654D02*
X-413406D01*
G01X-376368D02*
X-384644D01*
G01X-404036Y70866D02*
X-399776D01*
G01X-376368D02*
X-384644D01*
G01X-404036Y70079D02*
X-399776D01*
G01X-376368D02*
X-384644D01*
G01X-412087Y70000D02*
X-410118D01*
G01X-401061Y69882D02*
X-400726D01*
G01X-411835Y69754D02*
X-411207D01*
G01X-410370D02*
X-410956D01*
G01X-402402Y69636D02*
X-400768D01*
G01X-400433Y69390D02*
X-402402D01*
G01X-413406Y69292D02*
X-409225D01*
G01X-376368D02*
X-384644D01*
G01X-401018Y68898D02*
X-381333D01*
G01X-410705Y68729D02*
X-410621D01*
G01X-411459D02*
X-411584D01*
G01X-401018Y68504D02*
X-413406D01*
G01X-376368D02*
X-384644D01*
G01X-411417Y68483D02*
X-411626D01*
G01X-410579D02*
X-410746D01*
G01Y68155D02*
X-410411D01*
G01X-412087Y67909D02*
X-410453D01*
G01X-410118Y67663D02*
X-412087D01*
G01X-369633Y67467D02*
X-384927D01*
G01X-383095Y66823D02*
X-379031D01*
G01X-373133Y65355D02*
X-393755D01*
G01X-411040Y68647D02*
X-411081Y68729D01*
G01X-380219Y110954D02*
X-379235Y109478D01*
G01X-381253Y113415D02*
X-380219Y111889D01*
G01X-381892Y113415D02*
X-380514Y111397D01*
G01X-379924D02*
X-378595Y109478D01*
G01X-411919Y68647D02*
X-412045Y68811D01*
G01X-403410Y95132D02*
X-402622Y94345D01*
G01X-403410Y82534D02*
X-402622Y81746D01*
G01X-402402Y71851D02*
X-400433Y71194D01*
G01X-401732Y71400D02*
X-400601Y71031D01*
G01X-401899Y71440D02*
X-402402Y71605D01*
G01X-410830Y68770D02*
X-410705Y68729D01*
G01X-410746Y68483D02*
X-410872Y68524D01*
G01X-411584Y68729D02*
X-411710Y68770D01*
G01X-411626Y68483D02*
X-411752Y68524D01*
G01X-410914Y68852D02*
X-410830Y68770D01*
G01X-411710D02*
X-411794Y68852D01*
G01X-400726Y69882D02*
X-400433Y69636D01*
G01X-400768D02*
X-401061Y69882D01*
G01X-410411Y68155D02*
X-410118Y67909D01*
G01X-410453D02*
X-410746Y68155D01*
G01X-410872Y68524D02*
X-411040Y68647D01*
G01X-411752Y68524D02*
X-411919Y68647D01*
G01X-346378Y278098D02*
X-354170Y273910D01*
G01X-371394Y268884D02*
X-369344Y270140D01*
G01X-371805Y270978D02*
X-370574Y271816D01*
G01X-369344Y270140D02*
X-368114Y271397D01*
G01X-358271D02*
X-360732Y268465D01*
G01Y271816D02*
X-358271Y274747D01*
G01X-370574Y271816D02*
X-368934Y274329D01*
G01X-360732Y268465D02*
X-363192D01*
G01X-373855D02*
X-371394Y268884D01*
G01X-373855Y270559D02*
X-371805Y270978D01*
G01X-368114Y271397D02*
X-367294Y273072D01*
G01D02*
X-366883Y274329D01*
G01X-375906Y270978D02*
X-373855Y270559D01*
G01X-376316Y268884D02*
X-373855Y268465D01*
G01X-366883Y274329D02*
X-366473Y276423D01*
G01X-368934Y274329D02*
X-368524Y276842D01*
G01X-358271Y274747D02*
Y271397D01*
G01X-360732Y288150D02*
Y271816D01*
G01X-363192Y268465D02*
Y288150D01*
G01X-379186Y276842D02*
X-378776Y274329D01*
G01X-381237Y276423D02*
X-380827Y274329D01*
G01D02*
X-380417Y273072D01*
G01D02*
X-379597Y271397D01*
G01X-354170Y273910D02*
X-354990Y275166D01*
G01X-378776Y274329D02*
X-377136Y271816D01*
G01X-379597Y271397D02*
X-378366Y270140D01*
G01X-377136Y271816D02*
X-375906Y270978D01*
G01X-378366Y270140D02*
X-376316Y268884D01*
G01X-387388Y275166D02*
X-388619Y274747D01*
G01Y276423D02*
X-387388Y276842D01*
G01X-393950Y275166D02*
X-395181Y274747D01*
G01X-405843Y275166D02*
X-407073Y274747D01*
G01Y276423D02*
X-405843Y276842D01*
G01X-412405Y275166D02*
X-413635Y274747D01*
G01X-354990Y275166D02*
X-349249Y278098D01*
G01X-394770Y276423D02*
X-393950Y276842D01*
G01X-413225Y276423D02*
X-412405Y276842D01*
G01X-376316Y287731D02*
X-378366Y286475D01*
G01X-375906Y285637D02*
X-377136Y284799D01*
G01X-373855Y288150D02*
X-376316Y287731D01*
G01X-373855Y286056D02*
X-375906Y285637D01*
G01X-386568Y276004D02*
X-387388Y275166D01*
G01Y276842D02*
X-386568Y277679D01*
G01X-378366Y286475D02*
X-379597Y285218D01*
G01X-392720Y276423D02*
X-393950Y275166D01*
G01Y276842D02*
X-393540Y277260D01*
G01X-405023Y276004D02*
X-405843Y275166D01*
G01Y276842D02*
X-405023Y277679D01*
G01X-411175Y276423D02*
X-412405Y275166D01*
G01Y276842D02*
X-411995Y277260D01*
G01X-354990Y281030D02*
X-354170Y282286D01*
G01X-377136Y284799D02*
X-378776Y282286D01*
G01X-363192Y288150D02*
X-360732D01*
G01X-386568D02*
X-384518D01*
G01X-393130D02*
X-391079D01*
G01X-399692D02*
X-397641D01*
G01X-405023D02*
X-402973D01*
G01X-411585D02*
X-409534D01*
G01X-389439Y276423D02*
X-388619D01*
G01X-396001D02*
X-394770D01*
G01X-407894D02*
X-407073D01*
G01X-414455D02*
X-413225D01*
G01X-407073Y274747D02*
X-408714D01*
G01X-402973D02*
X-405023D01*
G01X-395181D02*
X-396821D01*
G01X-388619D02*
X-390259D01*
G01X-384518D02*
X-386568D01*
G01X-379597Y285218D02*
X-380417Y283543D01*
G01X-393540Y277260D02*
X-393130Y278098D01*
G01X-411995Y277260D02*
X-411585Y278098D01*
G01X-380417Y283543D02*
X-380827Y282286D01*
G01X-390259Y274747D02*
X-391490Y275166D01*
G01X-396821Y274747D02*
X-398051Y275166D01*
G01X-371805Y285637D02*
X-373855Y286056D01*
G01X-371394Y287731D02*
X-373855Y288150D01*
G01X-380827Y282286D02*
X-381237Y280192D01*
G01X-378776Y282286D02*
X-379186Y279773D01*
G01X-366473Y276423D02*
Y280192D01*
G01X-368524Y276842D02*
Y279773D01*
G01X-379186D02*
Y276842D01*
G01X-381237Y280192D02*
Y276423D01*
G01X-384518Y288150D02*
Y274747D01*
G01X-368524Y279773D02*
X-368934Y282286D01*
G01X-366473Y280192D02*
X-366883Y282286D01*
G01D02*
X-367294Y283543D01*
G01X-398872Y276004D02*
X-399692Y278098D01*
G01X-367294Y283543D02*
X-368114Y285218D01*
G01X-391079Y278098D02*
X-390670Y277260D01*
G01X-397641Y278098D02*
X-397231Y277260D01*
G01X-368934Y282286D02*
X-370574Y284799D01*
G01X-368114Y285218D02*
X-369344Y286475D01*
G01X-390670Y277260D02*
X-390259Y276842D01*
G01X-391490Y275166D02*
X-392720Y276423D01*
G01X-397231Y277260D02*
X-396821Y276842D01*
G01X-398051Y275166D02*
X-398872Y276004D01*
G01X-370574Y284799D02*
X-371805Y285637D01*
G01X-369344Y286475D02*
X-371394Y287731D01*
G01X-354170Y282286D02*
X-346378Y278098D01*
G01X-349249D02*
X-354990Y281030D01*
G01X-390259Y276842D02*
X-389439Y276423D01*
G01X-396821Y276842D02*
X-396001Y276423D01*
G01X-408714Y276842D02*
X-407894Y276423D01*
G01X-408714Y274747D02*
X-409944Y275166D01*
G01X-386568Y277679D02*
Y288150D01*
G01Y274747D02*
Y276004D01*
G01X-391079Y288150D02*
Y278098D01*
G01X-393130D02*
Y288150D01*
G01X-397641D02*
Y278098D01*
G01X-399692D02*
Y288150D01*
G01X-402973D02*
Y274747D01*
G01X-405023Y277679D02*
Y288150D01*
G01Y274747D02*
Y276004D01*
G01X-409534Y288150D02*
Y278098D01*
G01X-409965Y335428D02*
Y373302D01*
G01X-411585Y278098D02*
Y288150D01*
G01X-413902Y340152D02*
Y348577D01*
G01X-409534Y278098D02*
X-409124Y277260D01*
G01D02*
X-408714Y276842D01*
G01X-409944Y275166D02*
X-411175Y276423D01*
G01X-372648Y413314D02*
X-371007Y413733D01*
G01D02*
X-368547D01*
G01X-357064D02*
X-359114D01*
G01X-364856Y410801D02*
X-362395D01*
G01Y407031D02*
X-365266D01*
G01X-368547Y405356D02*
X-371007D01*
G01X-385361Y404100D02*
X-384541D01*
G01X-391923D02*
X-390692D01*
G01X-403816D02*
X-402996D01*
G01X-410377D02*
X-409147D01*
G01X-371007Y403262D02*
X-368547D01*
G01X-371007Y415827D02*
X-373058Y415408D01*
G01X-368547Y403262D02*
X-366496Y403681D01*
G01X-366906Y405775D02*
X-368547Y405356D01*
G01X-383310Y402843D02*
X-384541Y402424D01*
G01Y404100D02*
X-383310Y404519D01*
G01X-389872Y402843D02*
X-391103Y402424D01*
G01X-401765Y402843D02*
X-402996Y402424D01*
G01Y404100D02*
X-401765Y404519D01*
G01X-408327Y402843D02*
X-409557Y402424D01*
G01X-345581Y402843D02*
X-339839Y405775D01*
G01X-336969D02*
X-344760Y401587D01*
G01X-368547Y413733D02*
X-366906Y413314D01*
G01X-371007Y405356D02*
X-372648Y405775D01*
G01X-366496Y415408D02*
X-368547Y415827D01*
G01X-373058Y403681D02*
X-371007Y403262D01*
G01X-409557Y402424D02*
X-411197D01*
G01X-402996D02*
X-404636D01*
G01X-398894D02*
X-400945D01*
G01X-391103D02*
X-392743D01*
G01X-380440D02*
X-382490D01*
G01X-384541D02*
X-386181D01*
G01X-364446Y398236D02*
X-376339D01*
G01Y396142D02*
X-362395D01*
G01X-351322D02*
X-353783D01*
G01X-390692Y404100D02*
X-389872Y404519D01*
G01X-409147Y404100D02*
X-408327Y404519D01*
G01X-366496Y403681D02*
X-364446Y404937D01*
G01X-373058Y415408D02*
X-375109Y414152D01*
G01X-373878Y412476D02*
X-372648Y413314D01*
G01X-365266Y407031D02*
X-366906Y405775D01*
G01Y413314D02*
X-365676Y412476D01*
G01X-372648Y405775D02*
X-373878Y406613D01*
G01X-364446Y414152D02*
X-366496Y415408D01*
G01X-375109Y404937D02*
X-373058Y403681D01*
G01X-344760Y409963D02*
X-336969Y405775D01*
G01X-339839D02*
X-345581Y408707D01*
G01X-386181Y404519D02*
X-385361Y404100D01*
G01X-392743Y404519D02*
X-391923Y404100D01*
G01X-404636Y404519D02*
X-403816Y404100D01*
G01X-411197Y404519D02*
X-410377Y404100D01*
G01X-386181Y402424D02*
X-387412Y402843D01*
G01X-392743Y402424D02*
X-393973Y402843D01*
G01X-404636Y402424D02*
X-405866Y402843D01*
G01X-411197Y402424D02*
X-412428Y402843D01*
G01X-382490Y403681D02*
X-383310Y402843D01*
G01Y404519D02*
X-382490Y405356D01*
G01X-388642Y404100D02*
X-389872Y402843D01*
G01Y404519D02*
X-389462Y404937D01*
G01X-400945Y403681D02*
X-401765Y402843D01*
G01Y404519D02*
X-400945Y405356D01*
G01X-407097Y404100D02*
X-408327Y402843D01*
G01Y404519D02*
X-407917Y404937D01*
G01X-348862Y399074D02*
X-351322Y396142D01*
G01Y399493D02*
X-348862Y402424D01*
G01X-375109Y414152D02*
X-376339Y412476D01*
G01X-345581Y408707D02*
X-344760Y409963D01*
G01X-374698Y411220D02*
X-373878Y412476D01*
G01X-374698Y407869D02*
X-375109Y409126D01*
G01X-377159Y408707D02*
X-376339Y406613D01*
G01X-362395Y410801D02*
X-363215Y412476D01*
G01X-365676D02*
X-364856Y410801D01*
G01X-387001Y405775D02*
X-386591Y404937D01*
G01X-344760Y401587D02*
X-345581Y402843D01*
G01X-373878Y406613D02*
X-374698Y407869D01*
G01X-363215Y412476D02*
X-364446Y414152D01*
G01X-376339Y406613D02*
X-375109Y404937D01*
G01X-386591D02*
X-386181Y404519D01*
G01X-387412Y402843D02*
X-388642Y404100D01*
G01X-393153Y404937D02*
X-392743Y404519D01*
G01X-393973Y402843D02*
X-394794Y403681D01*
G01X-405046Y404937D02*
X-404636Y404519D01*
G01X-405866Y402843D02*
X-407097Y404100D01*
G01X-411608Y404937D02*
X-411197Y404519D01*
G01X-412428Y402843D02*
X-413248Y403681D01*
G01X-389462Y404937D02*
X-389052Y405775D01*
G01X-407917Y404937D02*
X-407507Y405775D01*
G01X-376339Y412476D02*
X-377159Y410382D01*
G01X-375109Y409963D02*
X-374698Y411220D01*
G01X-348862Y402424D02*
Y399074D01*
G01X-351322Y415827D02*
Y399493D01*
G01X-353783Y396142D02*
Y415827D01*
G01X-357064D02*
Y413733D01*
G01X-359114D02*
Y415827D01*
G01X-362395Y396142D02*
Y407031D01*
G01X-364446Y404937D02*
Y398236D01*
G01X-375109Y409126D02*
Y409963D01*
G01X-376339Y398236D02*
Y396142D01*
G01X-377159Y410382D02*
Y408707D01*
G01X-380440Y415827D02*
Y402424D01*
G01X-382490Y405356D02*
Y415827D01*
G01Y402424D02*
Y403681D01*
G01X-394794D02*
X-395614Y405775D01*
G01X-413248Y403681D02*
X-414068Y405775D01*
G01X-393563D02*
X-393153Y404937D01*
G01X-405456Y405775D02*
X-405046Y404937D01*
G01X-412018Y405775D02*
X-411608Y404937D01*
G01X-387001Y415827D02*
Y405775D01*
G01X-389052D02*
Y415827D01*
G01X-393563D02*
Y405775D01*
G01X-395614D02*
Y415827D01*
G01X-398894D02*
Y402424D01*
G01X-400945Y405356D02*
Y415827D01*
G01Y402424D02*
Y403681D01*
G01X-405456Y415827D02*
Y405775D01*
G01X-407507D02*
Y415827D01*
G01X-412018D02*
Y405775D01*
G01X-413902Y360152D02*
Y368577D01*
G01Y350152D02*
Y358577D01*
G01X-414068Y405775D02*
Y415827D01*
G01X-411422Y430389D02*
G03X-407485Y426452I3937J0D01*
G01X-395673Y446137D02*
G03X-391736Y442200I3937J0D01*
G01D02*
X-316933D01*
G01X-407485Y426452D02*
X-301185D01*
G01X-353783Y415827D02*
X-351322D01*
G01X-359114D02*
X-357064D01*
G01X-382490D02*
X-380440D01*
G01X-389052D02*
X-387001D01*
G01X-395614D02*
X-393563D01*
G01X-400945D02*
X-398894D01*
G01X-407507D02*
X-405456D01*
G01X-414068D02*
X-412018D01*
G01X-368547D02*
X-371007D01*
G01X-395673Y520940D02*
Y446137D01*
G01X-411422Y536688D02*
Y430389D01*
G01X-407485Y540625D02*
G03X-411422Y536688I0J-3937D01*
G01X-391736Y524877D02*
G03X-395673Y520940I0J-3937D01*
G01X-301185Y540625D02*
X-407485D01*
G01X-316933Y524877D02*
X-391736D01*
G01X-406864Y696834D02*
X-408504D01*
G01X-400302D02*
X-401942D01*
G01X-396201D02*
X-398251D01*
G01X-388409D02*
X-390049D01*
G01X-381847D02*
X-383488D01*
G01X-377746D02*
X-379797D01*
G01X-353960Y690552D02*
X-356421D01*
G01X-367083D02*
X-364623Y690970D01*
G01X-367083Y692646D02*
X-365033Y693065D01*
G01X-369134D02*
X-367083Y692646D01*
G01X-369544Y690970D02*
X-367083Y690552D01*
G01X-383488Y696834D02*
X-384718Y697253D01*
G01X-390049Y696834D02*
X-391280Y697253D01*
G01X-401942Y696834D02*
X-403173Y697253D01*
G01X-408504Y696834D02*
X-409735Y697253D01*
G01X-370364Y693902D02*
X-369134Y693065D01*
G01X-371595Y692227D02*
X-369544Y690970D01*
G01X-372825Y693483D02*
X-371595Y692227D01*
G01X-373645Y695159D02*
X-372825Y693483D01*
G01X-347398Y695996D02*
X-348219Y697253D01*
G01X-372005Y696415D02*
X-370364Y693902D01*
G01X-374055Y696415D02*
X-373645Y695159D01*
G01X-372415Y698928D02*
X-372005Y696415D01*
G01X-374465Y698509D02*
X-374055Y696415D01*
G01X-351499Y696834D02*
Y693483D01*
G01X-353960Y710237D02*
Y693902D01*
G01X-356421Y690552D02*
Y710237D01*
G01X-377746D02*
Y696834D01*
G01X-379797D02*
Y698090D01*
G01X-380617Y697253D02*
X-381847Y696834D01*
G01X-387179Y697253D02*
X-388409Y696834D01*
G01X-399072Y697253D02*
X-400302Y696834D01*
G01X-405633Y697253D02*
X-406864Y696834D01*
G01X-339607Y700185D02*
X-347398Y695996D01*
G01X-364623Y690970D02*
X-362572Y692227D01*
G01X-365033Y693065D02*
X-363803Y693902D01*
G01X-362572Y692227D02*
X-361342Y693483D01*
G01X-351499D02*
X-353960Y690552D01*
G01Y693902D02*
X-351499Y696834D01*
G01X-363803Y693902D02*
X-362162Y696415D01*
G01X-361342Y693483D02*
X-360522Y695159D01*
G01D02*
X-360112Y696415D01*
G01D02*
X-359701Y698509D01*
G01X-362162Y696415D02*
X-361752Y698928D01*
G01X-396201Y710237D02*
Y696834D01*
G01X-398251D02*
Y698090D01*
G01X-367083Y708142D02*
X-369134Y707724D01*
G01X-356421Y710237D02*
X-353960D01*
G01X-379797D02*
X-377746D01*
G01X-386359D02*
X-384308D01*
G01X-392920D02*
X-390870D01*
G01X-398251D02*
X-396201D01*
G01X-404813D02*
X-402762D01*
G01X-411375D02*
X-409324D01*
G01X-382668Y698509D02*
X-381847D01*
G01X-389229D02*
X-387999D01*
G01X-401122D02*
X-400302D01*
G01X-407684D02*
X-406453D01*
G01X-367083Y710237D02*
X-369544Y709818D01*
G01X-365033Y707724D02*
X-367083Y708142D01*
G01X-364623Y709818D02*
X-367083Y710237D01*
G01X-362572Y708561D02*
X-364623Y709818D01*
G01X-347398Y704373D02*
X-339607Y700185D01*
G01X-342477D02*
X-348219Y703116D01*
G01X-383488Y698928D02*
X-382668Y698509D01*
G01X-390049Y698928D02*
X-389229Y698509D01*
G01X-401942Y698928D02*
X-401122Y698509D01*
G01X-363803Y706886D02*
X-365033Y707724D01*
G01X-408504Y698928D02*
X-407684Y698509D01*
G01X-361342Y707305D02*
X-362572Y708561D01*
G01X-383898Y699347D02*
X-383488Y698928D01*
G01X-384718Y697253D02*
X-385948Y698509D01*
G01X-390459Y699347D02*
X-390049Y698928D01*
G01X-391280Y697253D02*
X-392100Y698090D01*
G01X-402353Y699347D02*
X-401942Y698928D01*
G01X-403173Y697253D02*
X-404403Y698509D01*
G01X-408914Y699347D02*
X-408504Y698928D01*
G01X-409735Y697253D02*
X-410555Y698090D01*
G01X-360522Y705629D02*
X-361342Y707305D01*
G01X-362162Y704373D02*
X-363803Y706886D01*
G01X-359701Y702279D02*
X-360112Y704373D01*
G01D02*
X-360522Y705629D01*
G01X-392100Y698090D02*
X-392920Y700185D01*
G01X-410555Y698090D02*
X-411375Y700185D01*
G01X-384308D02*
X-383898Y699347D01*
G01X-390870Y700185D02*
X-390459Y699347D01*
G01X-402762Y700185D02*
X-402353Y699347D01*
G01X-409324Y700185D02*
X-408914Y699347D01*
G01X-361752Y701860D02*
X-362162Y704373D01*
G01X-359701Y698509D02*
Y702279D01*
G01X-361752Y698928D02*
Y701860D01*
G01X-372415D02*
Y698928D01*
G01X-374465Y702279D02*
Y698509D01*
G01X-379797Y699766D02*
Y710237D01*
G01X-384308D02*
Y700185D01*
G01X-381847Y698509D02*
X-380617Y698928D01*
G01X-400302Y698509D02*
X-399072Y698928D01*
G01X-348219Y697253D02*
X-342477Y700185D01*
G01X-387999Y698509D02*
X-387179Y698928D01*
G01X-348219Y703116D02*
X-347398Y704373D01*
G01X-372825Y707305D02*
X-373645Y705629D01*
G01D02*
X-374055Y704373D01*
G01D02*
X-374465Y702279D01*
G01X-372005Y704373D02*
X-372415Y701860D01*
G01X-386359Y700185D02*
Y710237D01*
G01X-390870D02*
Y700185D01*
G01X-392920D02*
Y710237D01*
G01X-398251Y699766D02*
Y710237D01*
G01X-402762D02*
Y700185D01*
G01X-404813D02*
Y710237D01*
G01X-409324D02*
Y700185D01*
G01X-411375D02*
Y710237D01*
G01X-406453Y698509D02*
X-405633Y698928D01*
G01X-369544Y709818D02*
X-371595Y708561D01*
G01X-369134Y707724D02*
X-370364Y706886D01*
G01X-379797Y698090D02*
X-380617Y697253D01*
G01Y698928D02*
X-379797Y699766D01*
G01X-371595Y708561D02*
X-372825Y707305D01*
G01X-385948Y698509D02*
X-387179Y697253D01*
G01Y698928D02*
X-386768Y699347D01*
G01X-398251Y698090D02*
X-399072Y697253D01*
G01Y698928D02*
X-398251Y699766D01*
G01X-404403Y698509D02*
X-405633Y697253D01*
G01Y698928D02*
X-405223Y699347D01*
G01X-370364Y706886D02*
X-372005Y704373D01*
G01X-386768Y699347D02*
X-386359Y700185D01*
G01X-405223Y699347D02*
X-404813Y700185D01*
G01X-317126Y-201613D02*
X-317297Y-200717D01*
X-317808Y-199693D01*
X-318661Y-199053D01*
X-319856Y-198798D01*
X-321050Y-199053D01*
X-322073Y-199821D01*
X-322585Y-200973D01*
Y-202252D01*
X-322926Y-203020D01*
X-323779Y-203660D01*
X-324973Y-203916D01*
X-326168Y-203532D01*
X-327021Y-202636D01*
X-327362Y-201613D01*
X-327021Y-200589D01*
X-326168Y-199693D01*
X-324973Y-199309D01*
X-323779Y-199565D01*
X-322926Y-200205D01*
X-322585Y-200973D01*
Y-202252D01*
X-322073Y-203404D01*
X-321050Y-204172D01*
X-319856Y-204427D01*
X-318661Y-204172D01*
X-317808Y-203532D01*
X-317297Y-202508D01*
X-317126Y-201613D01*
G01X-327362Y-191377D02*
X-327021Y-192400D01*
X-326168Y-193168D01*
X-325144Y-193680D01*
X-323779Y-194063D01*
X-322244Y-194191D01*
X-320708Y-194063D01*
X-319344Y-193680D01*
X-318320Y-193168D01*
X-317467Y-192400D01*
X-317126Y-191377D01*
X-317467Y-190353D01*
X-318320Y-189585D01*
X-319344Y-189073D01*
X-320708Y-188690D01*
X-322244Y-188562D01*
X-323779Y-188690D01*
X-325144Y-189073D01*
X-326168Y-189585D01*
X-327021Y-190353D01*
X-327362Y-191377D01*
G01X-316785Y-181141D02*
X-316955Y-181396D01*
X-317297D01*
X-317467Y-181141D01*
X-317297Y-180885D01*
X-316955D01*
X-316785Y-181141D01*
G01X-327362Y-170905D02*
X-327021Y-171928D01*
X-326168Y-172696D01*
X-325144Y-173208D01*
X-323779Y-173591D01*
X-322244Y-173719D01*
X-320708Y-173591D01*
X-319344Y-173208D01*
X-318320Y-172696D01*
X-317467Y-171928D01*
X-317126Y-170905D01*
X-317467Y-169881D01*
X-318320Y-169113D01*
X-319344Y-168601D01*
X-320708Y-168218D01*
X-322244Y-168090D01*
X-323779Y-168218D01*
X-325144Y-168601D01*
X-326168Y-169113D01*
X-327021Y-169881D01*
X-327362Y-170905D01*
G01Y-160669D02*
X-327021Y-161692D01*
X-326168Y-162460D01*
X-325144Y-162972D01*
X-323779Y-163355D01*
X-322244Y-163483D01*
X-320708Y-163355D01*
X-319344Y-162972D01*
X-318320Y-162460D01*
X-317467Y-161692D01*
X-317126Y-160669D01*
X-317467Y-159645D01*
X-318320Y-158877D01*
X-319344Y-158365D01*
X-320708Y-157982D01*
X-322244Y-157854D01*
X-323779Y-157982D01*
X-325144Y-158365D01*
X-326168Y-158877D01*
X-327021Y-159645D01*
X-327362Y-160669D01*
G01X-314961Y0D02*
Y-152499D01*
G01X-311024Y-7874D02*
G03X-307087Y-3937I0J3937D01*
G01X-334646Y0D02*
G03Y-7874I0J-3937D01*
G01X-311024D02*
X-334646D01*
G01X-286221Y55237D02*
G03X-287796Y56811I-1575J-1D01*
G01X-318898Y0D02*
G03X-314961Y3937I0J3937D01*
G01X-274410Y31595D02*
G03X-270473Y35532I0J3937D01*
G01X-303150Y31595D02*
G03X-307087Y27658I0J-3937D01*
G01X-318898Y0D02*
G03X-314961Y3937I0J3937D01*
G01X-282284Y51890D02*
X-283464Y50709D01*
G01X-282284Y125276D02*
Y51890D01*
G01X-283464Y126457D02*
Y50709D01*
G01X-286221Y55237D02*
Y53662D01*
G01X-287796Y56811D02*
Y53662D01*
G01X-307087Y27658D02*
Y-3937D01*
G01X-309843Y133760D02*
Y43406D01*
G01X-313780Y39469D02*
Y137697D01*
G01Y133760D02*
Y43406D01*
G01X-314764Y125591D02*
Y51575D01*
G01X-314961Y133859D02*
Y3937D01*
G01Y133859D02*
Y3937D01*
G01X-315748Y125591D02*
Y51575D01*
G01X-316890D02*
Y46634D01*
G01X-320827Y53662D02*
Y123504D01*
G01X-331457Y53662D02*
Y123504D01*
G01X-337756Y43406D02*
Y47776D01*
G01X-287796Y56811D02*
X-320827D01*
G01X-282284Y55630D02*
X-320827D01*
G01Y53662D02*
X-282284D01*
G01X-309843Y51792D02*
X-313780D01*
G01Y51575D02*
X-316890D01*
G01X-309843Y50709D02*
X-283464D01*
G01X-313780Y49803D02*
X-316890D01*
G01X-337756Y47776D02*
X-313780D01*
G01Y46949D02*
X-309843D01*
G01X-274410Y31595D02*
X-303150D01*
G01X-287796Y120355D02*
G03X-286221Y121929I0J1575D01*
G01X-282284Y89370D02*
G03X-283465Y90552I-1181J1D01*
G01Y86615D02*
G03X-282284Y87796I0J1181D01*
G01X-286221Y102756D02*
Y108662D01*
G01Y68504D02*
Y74410D01*
G01Y123504D02*
Y121929D01*
G01X-287796Y123504D02*
Y120355D01*
G01X-294095Y74410D02*
Y68504D01*
G01Y108662D02*
Y102756D01*
G01X-316890Y130532D02*
Y125591D01*
G01X-337756Y129390D02*
Y133760D01*
G01X-309843Y130217D02*
X-313780D01*
G01Y129390D02*
X-337756D01*
G01X-316890Y127363D02*
X-313780D01*
G01X-309843Y126457D02*
X-283464D01*
G01X-316890Y125591D02*
X-313780D01*
G01Y125374D02*
X-309843D01*
G01X-282284Y125276D02*
X-283464Y126457D01*
G01X-320827Y123504D02*
X-282284D01*
G01Y121536D02*
X-320827D01*
G01X-287796Y120355D02*
X-320827D01*
G01X-286221Y108662D02*
X-294095D01*
G01Y102756D02*
X-286221D01*
G01X-320827Y90552D02*
X-283465D01*
G01Y86615D02*
X-320827D01*
G01X-286221Y74410D02*
X-294095D01*
G01Y68504D02*
X-286221D01*
G01X-292043Y189235D02*
X-292105Y189508D01*
G01X-291980Y188974D02*
X-292043Y189235D01*
G01X-291916Y188721D02*
X-291980Y188974D01*
G01X-289911Y188967D02*
X-289974Y188721D01*
G01X-289849Y189229D02*
X-289911Y188967D01*
G01X-289785Y189508D02*
X-289849Y189229D01*
G01X-279395Y185187D02*
G03X-279705Y185237I-310J-935D01*
G01X-280217Y187796D02*
G03X-281398Y188977I-1181J0D01*
G01X-287697D02*
G03X-288878Y187796I0J-1181D01*
G01X-276148Y183073D02*
G03X-275610Y182974I622J1868D01*
G01X-279403Y184152D02*
G03X-280023Y184252I-619J-1868D01*
G01X-291916Y188721D02*
G03X-289974I971J-1713D01*
G01X-292105Y189508D02*
G03X-289785I1160J-2500D01*
G01X-287874Y187008D02*
G03I-3071J0D01*
G01X-311024Y137796D02*
G03X-314961Y133859I0J-3937D01*
G01X-311024Y137796D02*
G03X-314961Y133859I0J-3937D01*
G01X-324038Y191009D02*
X-323976Y191030D01*
G01X-324059Y191132D02*
X-323997Y191153D01*
G01X-324394Y191030D02*
X-324457Y191009D01*
G01X-324478Y191132D02*
X-324416Y191153D01*
G01X-324143Y191071D02*
X-324059Y191132D01*
G01X-324562Y191071D02*
X-324478Y191132D01*
G01X-274803Y154961D02*
X-276772Y152992D01*
G01X-324080Y190968D02*
X-324038Y191009D01*
G01X-324457D02*
X-324499Y190968D01*
G01X-284252Y193012D02*
X-283721Y193544D01*
G01X-284252Y196162D02*
X-283721Y196693D01*
G01X-284252Y199311D02*
X-283721Y199843D01*
G01X-284252Y202461D02*
X-283721Y202992D01*
G01X-306244Y192802D02*
X-306142Y192905D01*
G01X-308913Y192238D02*
X-309016Y192135D01*
G01X-308662Y193544D02*
X-309193Y193012D01*
G01X-306244Y195952D02*
X-306142Y196054D01*
G01X-309193Y193012D02*
X-308662Y193544D01*
G01X-312992Y190453D02*
X-313386Y190059D01*
G01X-308913Y195387D02*
X-309016Y195285D01*
G01X-312815Y191496D02*
X-312284Y192028D01*
G01X-308662Y196693D02*
X-309193Y196162D01*
G01X-306244Y199101D02*
X-306142Y199204D01*
G01X-309193Y196162D02*
X-308662Y196693D01*
G01X-312992Y193603D02*
X-313386Y193209D01*
G01X-308913Y198537D02*
X-309016Y198435D01*
G01X-312815Y194646D02*
X-312284Y195177D01*
G01X-308662Y199843D02*
X-309193Y199311D01*
G01X-306244Y202251D02*
X-306142Y202353D01*
G01X-309193Y199311D02*
X-308662Y199843D01*
G01X-312992Y196752D02*
X-313386Y196359D01*
G01X-308913Y201687D02*
X-309016Y201584D01*
G01X-312815Y197796D02*
X-312284Y198327D01*
G01X-320670Y190433D02*
X-321260Y189843D01*
G01X-308662Y202992D02*
X-309193Y202461D01*
G01D02*
X-308662Y202992D01*
G01X-312992Y199902D02*
X-313386Y199508D01*
G01X-312815Y200945D02*
X-312284Y201477D01*
G01X-320670Y193583D02*
X-321260Y192992D01*
G01X-312992Y203052D02*
X-313386Y202658D01*
G01X-312815Y204095D02*
X-312284Y204626D01*
G01X-320670Y196733D02*
X-321260Y196142D01*
G01X-320670Y199882D02*
X-321260Y199292D01*
G01X-320670Y203032D02*
X-321260Y202441D01*
G01X-324625Y190989D02*
X-324562Y191071D01*
G01X-274803Y166536D02*
X-276772Y162992D01*
G01X-324164Y191030D02*
X-324143Y191071D01*
G01X-309669Y193012D02*
X-309449Y193544D01*
G01X-309669Y196162D02*
X-309449Y196693D01*
G01X-309669Y199311D02*
X-309449Y199843D01*
G01X-309669Y202461D02*
X-309449Y202992D01*
G01X-324101Y190907D02*
X-324080Y190968D01*
G01X-324499D02*
X-324520Y190907D01*
G01X-324646Y190886D02*
X-324625Y190989D01*
G01X-285338Y197444D02*
Y197045D01*
G01Y200593D02*
Y200195D01*
G01Y191144D02*
Y190746D01*
G01Y194294D02*
Y193896D01*
G01Y203743D02*
Y203344D01*
G01X-274803Y172992D02*
Y149843D01*
G01X-275610Y197638D02*
Y182973D01*
G01X-276378Y152402D02*
Y150433D01*
G01Y153386D02*
Y149843D01*
G01Y162402D02*
Y160433D01*
G01Y163701D02*
Y159134D01*
G01Y172402D02*
Y170433D01*
G01Y172992D02*
Y169370D01*
G01X-276772Y171516D02*
Y171270D01*
G01X-277599Y170433D02*
Y172402D01*
G01Y160433D02*
Y162402D01*
G01Y150433D02*
Y152402D01*
G01X-277739Y199607D02*
Y237402D01*
G01X-278012D02*
Y199607D01*
G01X-278347Y152402D02*
Y150433D01*
G01Y162402D02*
Y160433D01*
G01Y172402D02*
Y170433D01*
G01X-278740Y171270D02*
Y171516D01*
G01Y150433D02*
Y148229D01*
G01Y160433D02*
Y152402D01*
G01Y170433D02*
Y162402D01*
G01Y174607D02*
Y172402D01*
G01X-279528Y252756D02*
Y184252D01*
G01X-280217Y187796D02*
Y184252D01*
G01X-280512D02*
Y189508D01*
G01X-282225Y187402D02*
Y249607D01*
G01X-282284Y193307D02*
Y191733D01*
G01Y196457D02*
Y194882D01*
G01Y202756D02*
Y201181D01*
G01Y199607D02*
Y198032D01*
G01X-282677Y178544D02*
Y144292D01*
G01X-283721Y204095D02*
Y206142D01*
G01Y197796D02*
Y199843D01*
G01Y200945D02*
Y202992D01*
G01Y194646D02*
Y196693D01*
G01Y191496D02*
Y193544D01*
G01X-284252Y201477D02*
Y202461D01*
G01Y198327D02*
Y199311D01*
G01Y195177D02*
Y196162D01*
G01Y192028D02*
Y193012D01*
G01X-285329Y203346D02*
Y203740D01*
G01Y200197D02*
Y200591D01*
G01Y193897D02*
Y194292D01*
G01Y197048D02*
Y197441D01*
G01Y190747D02*
Y191142D01*
G01X-285546Y192914D02*
Y192126D01*
G01Y196063D02*
Y195276D01*
G01Y199213D02*
Y198426D01*
G01Y202363D02*
Y201575D01*
G01X-285573Y192914D02*
Y192126D01*
G01Y196063D02*
Y195276D01*
G01Y199213D02*
Y198426D01*
G01Y202363D02*
Y201575D01*
G01X-285582Y191210D02*
Y190681D01*
G01Y194359D02*
Y193830D01*
G01Y197509D02*
Y196980D01*
G01Y200659D02*
Y200129D01*
G01Y203808D02*
Y203279D01*
G01X-285587Y203278D02*
Y203809D01*
G01Y200128D02*
Y200660D01*
G01Y193829D02*
Y194361D01*
G01Y196979D02*
Y197510D01*
G01Y190679D02*
Y191211D01*
G01X-285627Y198426D02*
Y199213D01*
G01Y201575D02*
Y202363D01*
G01Y195276D02*
Y196063D01*
G01Y192126D02*
Y192914D01*
G01X-285827Y184252D02*
Y189508D01*
G01X-285850Y203207D02*
Y203880D01*
G01Y200058D02*
Y200730D01*
G01Y193759D02*
Y194431D01*
G01Y196908D02*
Y197581D01*
G01Y190609D02*
Y191281D01*
G01X-285877Y192914D02*
Y192126D01*
G01Y196063D02*
Y195276D01*
G01Y199213D02*
Y198426D01*
G01Y202363D02*
Y201575D01*
G01X-286344Y199607D02*
Y237402D01*
G01X-286614Y189508D02*
Y184252D01*
G01X-286617Y237402D02*
Y199607D01*
G01X-286688Y191339D02*
Y190552D01*
G01Y194489D02*
Y193701D01*
G01Y197638D02*
Y196851D01*
G01Y200788D02*
Y200000D01*
G01Y203937D02*
Y203150D01*
G01X-286934Y199607D02*
Y237402D01*
G01X-286986D02*
Y199607D01*
G01X-287160Y198426D02*
Y199213D01*
G01Y201575D02*
Y202363D01*
G01Y195276D02*
Y196063D01*
G01Y192126D02*
Y192914D01*
G01X-287425Y237402D02*
Y199607D01*
G01X-287872D02*
Y237402D01*
G01X-287992Y204095D02*
Y204626D01*
G01Y202461D02*
Y202992D01*
G01Y200945D02*
Y201477D01*
G01Y199311D02*
Y199843D01*
G01Y197796D02*
Y198327D01*
G01Y196162D02*
Y196693D01*
G01Y194646D02*
Y195177D01*
G01Y193012D02*
Y193544D01*
G01Y191496D02*
Y192028D01*
G01X-288878Y184252D02*
Y187796D01*
G01X-288977Y189508D02*
Y184252D01*
G01X-289725Y199607D02*
Y237402D01*
G01X-290085Y192799D02*
Y192241D01*
G01Y195949D02*
Y195390D01*
G01Y199098D02*
Y198540D01*
G01Y202248D02*
Y201690D01*
G01X-290119Y237402D02*
Y199607D01*
G01X-290510Y198426D02*
Y199213D01*
G01Y201575D02*
Y202363D01*
G01Y195276D02*
Y196063D01*
G01Y192126D02*
Y192914D01*
G01X-290539Y203311D02*
Y203776D01*
G01Y200161D02*
Y200627D01*
G01Y193862D02*
Y194327D01*
G01Y197012D02*
Y197477D01*
G01Y190713D02*
Y191178D01*
G01X-290840Y191339D02*
Y190552D01*
G01Y194489D02*
Y193701D01*
G01Y197638D02*
Y196851D01*
G01Y200788D02*
Y200000D01*
G01Y203937D02*
Y203150D01*
G01X-291057D02*
Y203937D01*
G01Y200000D02*
Y200788D01*
G01Y193701D02*
Y194489D01*
G01Y196851D02*
Y197638D01*
G01Y190552D02*
Y191339D01*
G01X-291197D02*
Y190552D01*
G01Y194489D02*
Y193701D01*
G01Y197638D02*
Y196851D01*
G01Y200788D02*
Y200000D01*
G01Y203937D02*
Y203150D01*
G01X-291380D02*
Y203937D01*
G01Y200000D02*
Y200788D01*
G01Y193701D02*
Y194489D01*
G01Y196851D02*
Y197638D01*
G01Y190552D02*
Y191339D01*
G01X-291414Y191189D02*
Y190702D01*
G01Y194339D02*
Y193851D01*
G01Y197488D02*
Y197001D01*
G01Y200638D02*
Y200150D01*
G01Y203787D02*
Y203300D01*
G01X-291438Y203295D02*
Y203792D01*
G01Y200145D02*
Y200643D01*
G01Y193846D02*
Y194344D01*
G01Y196996D02*
Y197493D01*
G01Y190696D02*
Y191194D01*
G01X-291535Y192914D02*
Y192126D01*
G01Y196063D02*
Y195276D01*
G01Y199213D02*
Y198426D01*
G01Y202363D02*
Y201575D01*
G01X-291637Y191224D02*
Y190666D01*
G01Y194374D02*
Y193816D01*
G01Y197524D02*
Y196965D01*
G01Y200673D02*
Y200115D01*
G01Y203823D02*
Y203265D01*
G01X-291879Y198531D02*
Y199107D01*
G01Y201681D02*
Y202257D01*
G01Y195381D02*
Y195958D01*
G01Y192232D02*
Y192808D01*
G01X-292677Y199607D02*
Y237402D01*
G01X-293070D02*
Y199607D01*
G01X-293898Y193544D02*
Y193012D01*
G01Y192028D02*
Y191496D01*
G01Y198327D02*
Y197796D01*
G01Y196693D02*
Y196162D01*
G01Y195177D02*
Y194646D01*
G01Y202992D02*
Y202461D01*
G01Y201477D02*
Y200945D01*
G01Y199843D02*
Y199311D01*
G01Y204626D02*
Y204095D01*
G01X-294488Y189508D02*
Y184252D01*
G01X-295010Y237402D02*
Y199607D01*
G01X-295276Y189508D02*
Y184252D01*
G01X-295456Y199607D02*
Y237402D01*
G01X-295896Y199607D02*
Y237402D01*
G01X-295925Y185237D02*
Y184252D01*
G01X-295948Y237402D02*
Y199607D01*
G01X-296418Y185237D02*
Y186221D01*
G01X-296720Y237402D02*
Y199607D01*
G01X-301240Y185366D02*
Y184252D01*
G01X-302028Y185237D02*
Y184252D01*
G01X-302422D02*
Y185237D01*
G01X-303504D02*
Y184252D01*
G01X-303603D02*
Y185237D01*
G01X-303622Y249607D02*
Y187402D01*
G01X-304331Y191339D02*
Y190552D01*
G01Y194489D02*
Y193701D01*
G01Y197638D02*
Y196851D01*
G01Y200788D02*
Y200000D01*
G01Y203937D02*
Y203150D01*
G01X-304799Y192914D02*
Y192126D01*
G01Y196063D02*
Y195276D01*
G01Y199213D02*
Y198426D01*
G01Y202363D02*
Y201575D01*
G01X-304922Y203150D02*
Y203937D01*
G01Y200000D02*
Y200788D01*
G01Y193701D02*
Y194489D01*
G01Y196851D02*
Y197638D01*
G01Y190552D02*
Y191339D01*
G01X-305233Y198426D02*
Y199213D01*
G01Y201575D02*
Y202363D01*
G01Y195276D02*
Y196063D01*
G01Y192126D02*
Y192914D01*
G01X-305457Y198426D02*
Y199213D01*
G01Y201575D02*
Y202363D01*
G01Y195276D02*
Y196063D01*
G01Y192126D02*
Y192914D01*
G01X-305473Y198327D02*
Y199311D01*
G01Y201477D02*
Y202461D01*
G01Y195177D02*
Y196162D01*
G01Y192028D02*
Y193012D01*
G01X-305512Y191339D02*
Y190552D01*
G01Y194489D02*
Y193701D01*
G01Y197638D02*
Y196851D01*
G01Y200788D02*
Y200000D01*
G01Y203937D02*
Y203150D01*
G01X-305788Y198327D02*
Y199311D01*
G01Y201477D02*
Y202461D01*
G01Y195177D02*
Y196162D01*
G01Y192028D02*
Y193012D01*
G01X-305890Y192914D02*
Y192126D01*
G01Y196063D02*
Y195276D01*
G01Y199213D02*
Y198426D01*
G01Y202363D02*
Y201575D01*
G01X-306103Y191339D02*
Y190552D01*
G01Y193012D02*
Y192028D01*
G01Y194489D02*
Y193701D01*
G01Y197638D02*
Y196851D01*
G01Y196162D02*
Y195177D01*
G01Y200788D02*
Y200000D01*
G01Y199311D02*
Y198327D01*
G01Y202461D02*
Y201477D01*
G01Y203937D02*
Y203150D01*
G01X-306142Y198435D02*
Y199204D01*
G01Y201584D02*
Y202353D01*
G01Y195285D02*
Y196054D01*
G01Y192135D02*
Y192905D01*
G01X-306244Y192802D02*
Y192238D01*
G01Y195952D02*
Y195387D01*
G01Y199101D02*
Y198537D01*
G01Y202251D02*
Y201687D01*
G01X-306500Y198622D02*
Y199016D01*
G01Y201772D02*
Y202166D01*
G01Y195473D02*
Y195866D01*
G01Y192323D02*
Y192717D01*
G01X-306693Y191339D02*
Y190552D01*
G01Y194489D02*
Y193701D01*
G01Y197638D02*
Y196851D01*
G01Y200788D02*
Y200000D01*
G01Y203937D02*
Y203150D01*
G01X-307351Y191339D02*
Y190552D01*
G01Y194489D02*
Y193701D01*
G01Y197638D02*
Y196851D01*
G01Y200788D02*
Y200000D01*
G01Y203937D02*
Y203150D01*
G01X-307605D02*
Y203937D01*
G01Y200000D02*
Y200788D01*
G01Y193701D02*
Y194489D01*
G01Y196851D02*
Y197638D01*
G01Y190552D02*
Y191339D01*
G01X-307628Y203150D02*
Y203937D01*
G01Y200000D02*
Y200788D01*
G01Y193701D02*
Y194489D01*
G01Y196851D02*
Y197638D01*
G01Y190552D02*
Y191339D01*
G01X-307874Y199311D02*
Y201477D01*
G01Y202461D02*
Y204626D01*
G01Y196162D02*
Y198327D01*
G01Y193012D02*
Y195177D01*
G01Y184252D02*
Y192028D01*
G01X-308657Y192717D02*
Y192323D01*
G01Y195866D02*
Y195473D01*
G01Y199016D02*
Y198622D01*
G01Y202166D02*
Y201772D01*
G01X-308662Y191496D02*
Y184252D01*
G01Y194646D02*
Y193544D01*
G01Y197796D02*
Y196693D01*
G01Y200945D02*
Y199843D01*
G01Y204095D02*
Y202992D01*
G01X-308783Y191339D02*
Y190552D01*
G01Y194489D02*
Y193701D01*
G01Y197638D02*
Y196851D01*
G01Y200788D02*
Y200000D01*
G01Y203937D02*
Y203150D01*
G01X-308888Y198426D02*
Y199213D01*
G01Y201575D02*
Y202363D01*
G01Y195276D02*
Y196063D01*
G01Y192126D02*
Y192914D01*
G01X-308901Y203150D02*
Y203937D01*
G01Y200000D02*
Y200788D01*
G01Y193701D02*
Y194489D01*
G01Y196851D02*
Y197638D01*
G01Y190552D02*
Y191339D01*
G01X-308913Y198537D02*
Y199101D01*
G01Y201687D02*
Y202251D01*
G01Y195387D02*
Y195952D01*
G01Y192238D02*
Y192802D01*
G01X-308969Y198426D02*
Y199213D01*
G01Y201575D02*
Y202363D01*
G01Y195276D02*
Y196063D01*
G01Y192126D02*
Y192914D01*
G01X-309003D02*
Y192126D01*
G01Y196063D02*
Y195276D01*
G01Y199213D02*
Y198426D01*
G01Y202363D02*
Y201575D01*
G01X-309016Y192905D02*
Y192135D01*
G01Y196054D02*
Y195285D01*
G01Y199204D02*
Y198435D01*
G01Y202353D02*
Y201584D01*
G01X-309055Y192914D02*
Y192126D01*
G01Y196063D02*
Y195276D01*
G01Y199213D02*
Y198426D01*
G01Y202363D02*
Y201575D01*
G01X-309076Y198426D02*
Y199213D01*
G01Y201575D02*
Y202363D01*
G01Y195276D02*
Y196063D01*
G01Y192126D02*
Y192914D01*
G01X-309114Y193012D02*
Y192028D01*
G01Y196162D02*
Y195177D01*
G01Y199311D02*
Y198327D01*
G01Y202461D02*
Y201477D01*
G01X-309370Y198426D02*
Y199213D01*
G01Y201575D02*
Y202363D01*
G01Y195276D02*
Y196063D01*
G01Y192126D02*
Y192914D01*
G01X-309429Y198327D02*
Y199311D01*
G01Y201477D02*
Y202461D01*
G01Y195177D02*
Y196162D01*
G01Y192028D02*
Y193012D01*
G01X-309449Y192914D02*
Y192126D01*
G01Y191496D02*
Y184252D01*
G01Y196063D02*
Y195276D01*
G01Y194646D02*
Y193544D01*
G01Y197796D02*
Y196693D01*
G01Y199213D02*
Y198426D01*
G01Y202363D02*
Y201575D01*
G01Y200945D02*
Y199843D01*
G01Y204095D02*
Y202992D01*
G01X-309685Y198426D02*
Y199213D01*
G01Y201575D02*
Y202363D01*
G01Y195276D02*
Y196063D01*
G01Y192126D02*
Y192914D01*
G01X-309722Y191339D02*
Y190552D01*
G01Y194489D02*
Y193701D01*
G01Y197638D02*
Y196851D01*
G01Y200788D02*
Y200000D01*
G01Y203937D02*
Y203150D01*
G01X-309862Y192914D02*
Y192126D01*
G01Y196063D02*
Y195276D01*
G01Y199213D02*
Y198426D01*
G01Y202363D02*
Y201575D01*
G01X-309960Y203150D02*
Y203937D01*
G01Y200000D02*
Y200788D01*
G01Y193701D02*
Y194489D01*
G01Y196851D02*
Y197638D01*
G01Y190552D02*
Y191339D01*
G01X-310000Y203150D02*
Y203937D01*
G01Y200000D02*
Y200788D01*
G01Y193701D02*
Y194489D01*
G01Y196851D02*
Y197638D01*
G01Y190552D02*
Y191339D01*
G01X-310040Y192914D02*
Y192126D01*
G01Y196063D02*
Y195276D01*
G01Y199213D02*
Y198426D01*
G01Y202363D02*
Y201575D01*
G01X-310276Y198426D02*
Y199213D01*
G01Y201575D02*
Y202363D01*
G01Y195276D02*
Y196063D01*
G01Y192126D02*
Y192914D01*
G01X-311378Y198426D02*
Y199213D01*
G01Y201575D02*
Y202363D01*
G01Y195276D02*
Y196063D01*
G01Y192126D02*
Y192914D01*
G01X-311418Y191733D02*
Y190158D01*
G01Y192914D02*
Y192126D01*
G01Y198032D02*
Y196457D01*
G01Y194882D02*
Y193307D01*
G01Y196063D02*
Y195276D01*
G01Y201181D02*
Y199607D01*
G01Y199213D02*
Y198426D01*
G01Y202363D02*
Y201575D01*
G01Y204331D02*
Y202756D01*
G01X-311792Y192914D02*
Y192126D01*
G01Y196063D02*
Y195276D01*
G01Y199213D02*
Y198426D01*
G01Y202363D02*
Y201575D01*
G01X-311890Y191339D02*
Y190552D01*
G01Y194489D02*
Y193701D01*
G01Y197638D02*
Y196851D01*
G01Y200788D02*
Y200000D01*
G01Y203937D02*
Y203150D01*
G01X-311969Y198426D02*
Y199213D01*
G01Y201575D02*
Y202363D01*
G01Y195276D02*
Y196063D01*
G01Y192126D02*
Y192914D01*
G01X-312008Y203150D02*
Y203937D01*
G01Y200000D02*
Y200788D01*
G01Y193701D02*
Y194489D01*
G01Y196851D02*
Y197638D01*
G01Y190552D02*
Y191339D01*
G01X-312205Y192914D02*
Y192126D01*
G01Y196063D02*
Y195276D01*
G01Y199213D02*
Y198426D01*
G01Y202363D02*
Y201575D01*
G01X-312284Y193012D02*
Y192028D01*
G01Y196162D02*
Y195177D01*
G01Y199311D02*
Y198327D01*
G01Y202461D02*
Y201477D01*
G01X-312796Y191339D02*
Y190552D01*
G01Y194489D02*
Y193701D01*
G01Y197638D02*
Y196851D01*
G01Y200788D02*
Y200000D01*
G01Y203937D02*
Y203150D01*
G01X-312815Y193544D02*
Y191496D01*
G01Y196693D02*
Y194646D01*
G01Y199843D02*
Y197796D01*
G01Y202992D02*
Y200945D01*
G01Y206142D02*
Y204095D01*
G01X-312992Y190453D02*
Y191437D01*
G01Y194587D02*
Y193603D01*
G01Y197737D02*
Y196752D01*
G01Y200886D02*
Y199902D01*
G01Y204036D02*
Y203052D01*
G01X-313110Y192914D02*
Y192126D01*
G01Y196063D02*
Y195276D01*
G01Y199213D02*
Y198426D01*
G01Y202363D02*
Y201575D01*
G01X-313386Y252756D02*
Y184252D01*
G01X-313701Y192914D02*
Y192126D01*
G01Y196063D02*
Y195276D01*
G01Y199213D02*
Y198426D01*
G01Y202363D02*
Y201575D01*
G01X-313977Y191339D02*
Y190552D01*
G01Y194489D02*
Y193701D01*
G01Y197638D02*
Y196851D01*
G01Y200788D02*
Y200000D01*
G01Y203937D02*
Y203150D01*
G01X-314961Y249607D02*
Y187402D01*
G01X-285698Y202363D02*
X-285697Y201575D01*
G01X-285698Y199213D02*
X-285697Y198426D01*
G01X-285698Y196063D02*
X-285697Y195276D01*
G01X-285698Y192914D02*
X-285697Y192126D01*
G01X-297028Y186181D02*
X-296841Y185215D01*
G01X-323683Y190989D02*
X-323662Y190886D01*
G01X-279528Y204174D02*
X-313130D01*
G01X-312815Y204095D02*
X-283721D01*
G01X-319016Y204055D02*
X-320670D01*
G01X-303622Y204036D02*
X-312992D01*
G01X-286064Y203937D02*
X-323347D01*
G01Y203150D02*
X-286064D01*
G01X-303622Y203052D02*
X-312992D01*
G01X-320670Y203032D02*
X-319016D01*
G01X-283721Y202992D02*
X-312815D01*
G01X-313130Y202914D02*
X-279528D01*
G01X-313386Y202756D02*
X-311418D01*
G01X-279528D02*
X-282284D01*
G01X-293898Y202461D02*
X-312284D01*
G01X-284252D02*
X-287992D01*
G01X-313701Y202363D02*
X-285546D01*
G01X-308657Y202166D02*
X-306500D01*
G01Y201772D02*
X-308657D01*
G01X-313701Y201575D02*
X-285546D01*
G01X-287992Y201477D02*
X-284252D01*
G01X-312284D02*
X-293898D01*
G01X-311418Y201181D02*
X-313386D01*
G01X-279528D02*
X-282284D01*
G01X-279528Y201024D02*
X-313130D01*
G01X-312815Y200945D02*
X-283721D01*
G01X-319016Y200906D02*
X-320670D01*
G01X-303622Y200886D02*
X-312992D01*
G01X-286064Y200788D02*
X-323347D01*
G01Y200000D02*
X-286064D01*
G01X-303622Y199902D02*
X-312992D01*
G01X-320670Y199882D02*
X-319016D01*
G01X-283721Y199843D02*
X-312815D01*
G01X-313130Y199764D02*
X-279528D01*
G01X-296720Y199607D02*
X-282284D01*
G01X-313386D02*
X-311418D01*
G01X-270689D02*
X-279528D01*
G01D02*
X-282284D01*
G01X-293898Y199311D02*
X-312284D01*
G01X-284252D02*
X-287992D01*
G01X-313701Y199213D02*
X-285546D01*
G01X-308657Y199016D02*
X-306500D01*
G01Y198622D02*
X-308657D01*
G01X-313701Y198426D02*
X-285546D01*
G01X-287992Y198327D02*
X-284252D01*
G01X-312284D02*
X-293898D01*
G01X-311418Y198032D02*
X-313386D01*
G01X-279528D02*
X-282284D01*
G01X-279528Y197874D02*
X-313130D01*
G01X-312815Y197796D02*
X-283721D01*
G01X-319016Y197756D02*
X-320670D01*
G01X-303622Y197737D02*
X-312992D01*
G01X-286064Y197638D02*
X-323347D01*
G01X-270689D02*
X-275610D01*
G01X-323347Y196851D02*
X-286064D01*
G01X-303622Y196752D02*
X-312992D01*
G01X-320670Y196733D02*
X-319016D01*
G01X-283721Y196693D02*
X-312815D01*
G01X-313130Y196615D02*
X-279528D01*
G01X-313386Y196457D02*
X-311418D01*
G01X-279528D02*
X-282284D01*
G01X-293898Y196162D02*
X-312284D01*
G01X-284252D02*
X-287992D01*
G01X-313701Y196063D02*
X-285546D01*
G01X-308657Y195866D02*
X-306500D01*
G01Y195473D02*
X-308657D01*
G01X-313701Y195276D02*
X-285546D01*
G01X-287992Y195177D02*
X-284252D01*
G01X-312284D02*
X-293898D01*
G01X-311418Y194882D02*
X-313386D01*
G01X-279528D02*
X-282284D01*
G01X-279528Y194725D02*
X-313130D01*
G01X-312815Y194646D02*
X-283721D01*
G01X-319016Y194607D02*
X-320670D01*
G01X-303622Y194587D02*
X-312992D01*
G01X-286064Y194489D02*
X-323347D01*
G01X-291637Y203265D02*
X-292794Y203150D01*
G01X-291637Y200115D02*
X-292794Y200000D01*
G01X-291637Y196965D02*
X-292794Y196851D01*
G01X-291637Y193816D02*
X-292794Y193701D01*
G01X-291637Y190666D02*
X-292794Y190552D01*
G01X-290539Y203776D02*
X-289641Y203937D01*
G01X-290539Y200627D02*
X-289641Y200788D01*
G01X-290539Y197477D02*
X-289641Y197638D01*
G01X-290539Y194327D02*
X-289641Y194489D01*
G01X-290539Y191178D02*
X-289641Y191339D01*
G01X-289491Y202363D02*
X-290085Y202248D01*
G01X-289491Y199213D02*
X-290085Y199098D01*
G01X-289491Y196063D02*
X-290085Y195949D01*
G01X-289491Y192914D02*
X-290085Y192799D01*
G01X-297028Y186181D02*
X-301910Y185237D01*
G01X-296841Y185215D02*
X-301815Y184252D01*
G01X-291879Y201681D02*
X-292395Y201575D01*
G01X-291879Y198531D02*
X-292395Y198426D01*
G01X-291879Y195381D02*
X-292395Y195276D01*
G01X-291879Y192232D02*
X-292395Y192126D01*
G01X-291414Y203300D02*
X-291438Y203295D01*
G01X-291414Y200150D02*
X-291438Y200145D01*
G01X-291414Y197001D02*
X-291438Y196996D01*
G01X-291414Y193851D02*
X-291438Y193846D01*
G01X-291414Y190702D02*
X-291438Y190696D01*
G01X-285329Y203347D02*
X-286064Y203150D01*
G01Y200000D02*
X-285329Y200197D01*
G01X-286064Y196851D02*
X-285329Y197048D01*
G01Y193898D02*
X-286064Y193701D01*
G01X-285329Y190748D02*
X-286064Y190552D01*
G01X-318425Y203150D02*
Y203937D01*
G01Y200000D02*
Y200788D01*
G01Y193701D02*
Y194489D01*
G01Y196851D02*
Y197638D01*
G01Y190552D02*
Y191339D01*
G01X-318504Y184252D02*
Y187402D01*
G01X-319016Y203032D02*
Y204055D01*
G01Y199882D02*
Y200906D01*
G01Y196733D02*
Y197756D01*
G01Y193583D02*
Y194607D01*
G01Y190433D02*
Y191457D01*
G01X-319292Y184252D02*
Y187402D01*
G01X-319607Y191339D02*
Y190552D01*
G01Y194489D02*
Y193701D01*
G01Y197638D02*
Y196851D01*
G01Y200788D02*
Y200000D01*
G01Y203937D02*
Y203150D01*
G01X-320079Y184252D02*
Y187402D01*
G01X-320473Y184252D02*
Y187402D01*
G01X-320551Y191339D02*
Y190552D01*
G01Y194489D02*
Y193701D01*
G01Y197638D02*
Y196851D01*
G01Y200788D02*
Y200000D01*
G01Y203937D02*
Y203150D01*
G01X-321260Y201496D02*
Y202441D01*
G01Y198347D02*
Y199292D01*
G01Y195197D02*
Y196142D01*
G01Y184252D02*
Y189843D01*
G01Y192048D02*
Y192992D01*
G01Y191339D02*
Y190552D01*
G01Y194489D02*
Y193701D01*
G01Y197638D02*
Y196851D01*
G01Y200788D02*
Y200000D01*
G01Y203937D02*
Y203150D01*
G01X-321851D02*
Y203937D01*
G01Y200000D02*
Y200788D01*
G01Y193701D02*
Y194489D01*
G01Y196851D02*
Y197638D01*
G01Y190552D02*
Y191339D01*
G01X-322756D02*
Y190552D01*
G01Y194489D02*
Y193701D01*
G01Y197638D02*
Y196851D01*
G01Y200788D02*
Y200000D01*
G01Y203937D02*
Y203150D01*
G01X-323347Y191339D02*
Y190552D01*
G01Y194489D02*
Y193701D01*
G01Y197638D02*
Y196851D01*
G01Y200788D02*
Y200000D01*
G01Y203937D02*
Y203150D01*
G01X-323662Y191563D02*
Y191440D01*
G01Y190886D02*
Y190394D01*
G01X-323787Y190907D02*
Y190517D01*
G01X-324016Y184252D02*
Y187402D01*
G01X-324101Y190517D02*
Y190907D01*
G01X-324227Y190517D02*
Y190907D01*
G01X-324520D02*
Y190517D01*
G01X-324646Y191440D02*
Y191563D01*
G01Y190394D02*
Y190886D01*
G01X-324803Y184252D02*
Y187402D01*
G01X-326811Y255906D02*
Y181103D01*
G01X-323808Y190968D02*
X-323787Y190907D01*
G01X-324227D02*
X-324248Y190968D01*
G01X-309449Y204095D02*
X-309669Y204626D01*
G01X-309449Y200945D02*
X-309669Y201477D01*
G01X-309449Y197796D02*
X-309669Y198327D01*
G01X-309449Y194646D02*
X-309669Y195177D01*
G01Y192028D02*
X-309449Y191496D01*
G01X-324185Y191071D02*
X-324164Y191030D01*
G01X-276772Y159843D02*
X-274803Y156300D01*
G01X-323745Y191071D02*
X-323683Y190989D01*
G01X-274803Y167481D02*
X-276772Y169843D01*
G01X-284252Y204626D02*
X-283721Y204095D01*
G01X-284252Y201477D02*
X-283721Y200945D01*
G01X-284252Y198327D02*
X-283721Y197796D01*
G01X-284252Y195177D02*
X-283721Y194646D01*
G01X-284252Y192028D02*
X-283721Y191496D01*
G01X-279528Y185237D02*
X-280512Y186221D01*
G01X-282225Y187402D02*
X-279528Y184705D01*
G01X-306142Y201584D02*
X-306244Y201687D01*
G01X-308662Y204095D02*
X-309193Y204626D01*
G01X-308913Y202251D02*
X-309016Y202353D01*
G01X-306142Y198435D02*
X-306244Y198537D01*
G01X-308662Y200945D02*
X-309193Y201477D01*
G01X-313386Y204429D02*
X-312992Y204036D01*
G01X-308913Y199101D02*
X-309016Y199204D01*
G01X-312284Y202461D02*
X-312815Y202992D01*
G01X-306142Y195285D02*
X-306244Y195387D01*
G01X-308662Y197796D02*
X-309193Y198327D01*
G01X-313386Y201280D02*
X-312992Y200886D01*
G01X-308913Y195952D02*
X-309016Y196054D01*
G01X-312284Y199311D02*
X-312815Y199843D01*
G01X-306142Y192135D02*
X-306244Y192238D01*
G01X-308662Y194646D02*
X-309193Y195177D01*
G01X-313386Y198130D02*
X-312992Y197737D01*
G01X-308913Y192802D02*
X-309016Y192905D01*
G01X-312284Y196162D02*
X-312815Y196693D01*
G01X-320670Y204055D02*
X-321260Y204646D01*
G01X-308662Y191496D02*
X-309193Y192028D01*
G01X-313386Y194981D02*
X-312992Y194587D01*
G01X-312284Y193012D02*
X-312815Y193544D01*
G01X-320670Y200906D02*
X-321260Y201496D01*
G01X-312992Y191437D02*
X-313386Y191831D01*
G01X-320670Y197756D02*
X-321260Y198347D01*
G01X-320670Y194607D02*
X-321260Y195197D01*
G01X-320670Y191457D02*
X-321260Y192048D01*
G01X-278405Y171270D02*
X-278112Y171024D01*
G01X-278447D02*
X-278740Y171270D01*
G01X-275688Y183957D02*
X-279395Y185187D01*
G01X-276148Y183073D02*
X-279403Y184152D01*
G01X-323892Y191153D02*
X-323829Y191132D01*
G01X-323913Y191030D02*
X-323850Y191009D01*
G01X-324332Y191153D02*
X-324269Y191132D01*
G01X-324290Y191009D02*
X-324353Y191030D01*
G01X-286064Y203937D02*
X-285329Y203740D01*
G01X-286064Y200788D02*
X-285329Y200591D01*
G01X-286064Y197638D02*
X-285329Y197441D01*
G01X-286064Y194489D02*
X-285329Y194292D01*
G01X-286064Y191339D02*
X-285329Y191142D01*
G01X-291438Y203792D02*
X-291414Y203787D01*
G01X-291438Y200643D02*
X-291414Y200638D01*
G01X-291438Y197493D02*
X-291414Y197488D01*
G01X-291438Y194344D02*
X-291414Y194339D01*
G01X-291438Y191194D02*
X-291414Y191189D01*
G01X-291879Y202257D02*
X-292395Y202363D01*
G01X-291879Y199107D02*
X-292395Y199213D01*
G01X-291879Y195958D02*
X-292395Y196063D01*
G01X-291879Y192808D02*
X-292395Y192914D01*
G01X-290085Y201690D02*
X-289491Y201575D01*
G01X-290085Y198540D02*
X-289491Y198426D01*
G01X-290085Y195390D02*
X-289491Y195276D01*
G01X-290085Y192241D02*
X-289491Y192126D01*
G01X-289641Y203150D02*
X-290539Y203311D01*
G01X-289641Y200000D02*
X-290539Y200161D01*
G01X-289641Y196851D02*
X-290539Y197012D01*
G01X-289641Y193701D02*
X-290539Y193862D01*
G01X-289641Y190552D02*
X-290539Y190713D01*
G01X-292794Y203937D02*
X-291637Y203823D01*
G01X-292794Y200788D02*
X-291637Y200673D01*
G01X-292794Y197638D02*
X-291637Y197524D01*
G01X-292794Y194489D02*
X-291637Y194374D01*
G01X-292794Y191339D02*
X-291637Y191224D01*
G01X-323347Y193701D02*
X-286064D01*
G01X-303622Y193603D02*
X-312992D01*
G01X-320670Y193583D02*
X-319016D01*
G01X-283721Y193544D02*
X-312815D01*
G01X-313130Y193465D02*
X-279528D01*
G01X-313386Y193307D02*
X-311418D01*
G01X-279528D02*
X-282284D01*
G01X-293898Y193012D02*
X-312284D01*
G01X-284252D02*
X-287992D01*
G01X-313701Y192914D02*
X-285546D01*
G01X-308657Y192717D02*
X-306500D01*
G01Y192323D02*
X-308657D01*
G01X-313701Y192126D02*
X-285546D01*
G01X-287992Y192028D02*
X-284252D01*
G01X-312284D02*
X-293898D01*
G01X-311418Y191733D02*
X-313386D01*
G01X-279528D02*
X-282284D01*
G01X-313130Y191575D02*
X-279528D01*
G01X-324646Y191563D02*
X-323662D01*
G01X-312815Y191496D02*
X-283721D01*
G01X-319016Y191457D02*
X-320670D01*
G01X-323662Y191440D02*
X-324478D01*
G01X-303622Y191437D02*
X-312992D01*
G01X-286064Y191339D02*
X-323347D01*
G01X-324332Y191317D02*
X-324499D01*
G01X-323997Y191153D02*
X-323892D01*
G01X-324416D02*
X-324332D01*
G01X-323976Y191030D02*
X-323913D01*
G01X-324353D02*
X-324394D01*
G01X-323347Y190552D02*
X-286064D01*
G01X-324520Y190517D02*
X-324227D01*
G01X-323787D02*
X-324101D01*
G01X-303622Y190453D02*
X-312992D01*
G01X-320670Y190433D02*
X-319016D01*
G01X-323662Y190394D02*
X-324646D01*
G01X-313130Y190315D02*
X-279528D01*
G01X-313386Y190158D02*
X-311418D01*
G01X-279528Y189508D02*
X-295276D01*
G01X-281398Y188977D02*
X-287697D01*
G01X-289974Y188721D02*
X-291916D01*
G01X-303622Y187402D02*
X-282225D01*
G01X-324803D02*
X-320473D01*
G01X-314961D02*
X-320079D01*
G01X-296418Y186221D02*
X-313386D01*
G01X-280217D02*
X-280512D01*
G01D02*
X-288977D01*
G01X-238996Y185433D02*
X-275610D01*
G01X-303504Y185237D02*
X-303603D01*
G01X-279528D02*
X-303504D01*
G01X-324803Y184252D02*
X-279528D01*
G01X-275610Y183957D02*
X-238996D01*
G01X-275610D02*
X-275688D01*
G01X-238996Y182973D02*
X-275610D01*
G01X-326811Y181103D02*
X-236260D01*
G01X-240158Y178544D02*
X-282677D01*
G01X-251969Y174607D02*
X-278740D01*
G01Y172992D02*
X-274803D01*
G01X-251969Y172599D02*
X-276378D01*
G01X-278347Y172402D02*
X-260118D01*
G01X-278740D02*
X-276378D01*
G01Y171851D02*
X-255906D01*
G01X-278740Y171516D02*
X-276772D01*
G01Y171270D02*
X-278405D01*
G01X-278112Y171024D02*
X-278447D01*
G01X-278740Y170433D02*
X-276378D01*
G01X-264173D02*
X-278347D01*
G01X-276772Y169843D02*
X-278740D01*
G01X-276772Y162992D02*
X-278740D01*
G01Y162402D02*
X-276378D01*
G01X-257481D02*
X-278347D01*
G01X-278740Y160433D02*
X-276378D01*
G01X-257481D02*
X-278347D01*
G01X-276772Y159843D02*
X-278740D01*
G01X-276772Y152992D02*
X-278740D01*
G01Y152402D02*
X-276378D01*
G01X-263942D02*
X-278347D01*
G01X-276378Y150985D02*
X-255906D01*
G01X-278740Y150433D02*
X-276378D01*
G01X-260197D02*
X-278347D01*
G01X-251969Y150237D02*
X-276378D01*
G01X-278740Y149843D02*
X-274803D01*
G01X-251969Y148229D02*
X-278740D01*
G01X-240158Y144292D02*
X-282677D01*
G01X-240158Y137796D02*
X-311024D01*
G01X-240158D02*
X-311024D01*
G01X-323850Y191009D02*
X-323808Y190968D01*
G01X-324248D02*
X-324290Y191009D01*
G01X-324478Y191440D02*
X-324332Y191317D01*
G01X-324499D02*
X-324646Y191440D01*
G01X-323829Y191132D02*
X-323745Y191071D01*
G01X-324269Y191132D02*
X-324185Y191071D01*
G01X-289847Y247774D02*
X-289785Y247500D01*
G01X-289910Y248035D02*
X-289847Y247774D01*
G01X-289974Y248288D02*
X-289910Y248035D01*
G01X-291979Y248041D02*
X-291916Y248288D01*
G01X-292042Y247779D02*
X-291979Y248041D01*
G01X-292105Y247500D02*
X-292042Y247779D01*
G01X-275610Y254034D02*
G03X-276148Y253936I80J-1967D01*
G01X-279705Y251772D02*
G03X-279395Y251822I0J984D01*
G01X-281398Y248032D02*
G03X-280217Y249213I0J1181D01*
G01X-280023Y252756D02*
G03X-279403Y252856I1J1969D01*
G01X-288878Y249213D02*
G03X-287697Y248032I1181J0D01*
G01X-289974Y248288D02*
G03X-291916I-971J1712D01*
G01X-289785Y247500D02*
G03X-292105I-1160J2500D01*
G01X-287874Y250000D02*
G03I-3071J0D01*
G01X-275688Y253052D02*
X-279395Y251822D01*
G01X-276148Y253936D02*
X-279403Y252856D01*
G01X-284252Y205611D02*
X-283721Y206142D01*
G01X-284252Y208760D02*
X-283721Y209292D01*
G01X-284252Y211910D02*
X-283721Y212441D01*
G01X-284252Y215059D02*
X-283721Y215591D01*
G01X-284252Y218209D02*
X-283721Y218740D01*
G01X-284252Y221359D02*
X-283721Y221890D01*
G01X-284252Y224508D02*
X-283721Y225040D01*
G01X-306244Y205400D02*
X-306142Y205503D01*
G01X-284252Y227658D02*
X-283721Y228189D01*
G01X-308913Y204836D02*
X-309016Y204734D01*
G01X-308662Y206142D02*
X-309193Y205611D01*
G01X-306244Y208550D02*
X-306142Y208653D01*
G01X-309193Y205611D02*
X-308662Y206142D01*
G01X-284252Y230807D02*
X-283721Y231339D01*
G01X-308913Y207986D02*
X-309016Y207883D01*
G01X-306244Y211700D02*
X-306142Y211802D01*
G01X-308662Y209292D02*
X-309193Y208760D01*
G01D02*
X-308662Y209292D01*
G01X-284252Y233957D02*
X-283721Y234489D01*
G01X-312992Y206201D02*
X-313386Y205807D01*
G01X-308913Y211135D02*
X-309016Y211033D01*
G01X-312815Y207244D02*
X-312284Y207776D01*
G01X-306244Y214849D02*
X-306142Y214952D01*
G01X-308662Y212441D02*
X-309193Y211910D01*
G01D02*
X-308662Y212441D01*
G01X-284252Y237107D02*
X-283721Y237638D01*
G01X-312992Y209351D02*
X-313386Y208957D01*
G01X-308913Y214285D02*
X-309016Y214183D01*
G01X-312815Y210394D02*
X-312284Y210926D01*
G01X-306244Y217999D02*
X-306142Y218102D01*
G01X-308662Y215591D02*
X-309193Y215059D01*
G01D02*
X-308662Y215591D01*
G01X-284252Y240256D02*
X-283721Y240788D01*
G01X-312992Y212500D02*
X-313386Y212107D01*
G01X-308913Y217435D02*
X-309016Y217332D01*
G01X-312815Y213544D02*
X-312284Y214075D01*
G01X-320670Y206181D02*
X-321260Y205591D01*
G01X-306244Y221148D02*
X-306142Y221251D01*
G01X-308662Y218740D02*
X-309193Y218209D01*
G01D02*
X-308662Y218740D01*
G01X-284252Y243406D02*
X-283721Y243937D01*
G01X-312992Y215650D02*
X-313386Y215256D01*
G01X-308913Y220584D02*
X-309016Y220482D01*
G01X-312815Y216693D02*
X-312284Y217225D01*
G01X-320670Y209331D02*
X-321260Y208740D01*
G01X-306244Y224298D02*
X-306142Y224401D01*
G01X-308662Y221890D02*
X-309193Y221359D01*
G01D02*
X-308662Y221890D01*
G01X-284252Y246555D02*
X-283721Y247087D01*
G01X-280512Y250788D02*
X-279528Y251772D01*
G01X-312992Y218800D02*
X-313386Y218406D01*
G01X-279528Y252303D02*
X-282225Y249607D01*
G01X-308913Y223734D02*
X-309016Y223631D01*
G01X-312815Y219843D02*
X-312284Y220374D01*
G01X-320670Y212481D02*
X-321260Y211890D01*
G01X-306244Y227448D02*
X-306142Y227550D01*
G01X-308662Y225040D02*
X-309193Y224508D01*
G01D02*
X-308662Y225040D01*
G01X-312992Y221949D02*
X-313386Y221555D01*
G01X-308913Y226883D02*
X-309016Y226781D01*
G01X-312815Y222992D02*
X-312284Y223524D01*
G01X-320670Y215630D02*
X-321260Y215040D01*
G01X-306244Y230597D02*
X-306142Y230700D01*
G01X-308662Y228189D02*
X-309193Y227658D01*
G01D02*
X-308662Y228189D01*
G01X-312992Y225099D02*
X-313386Y224705D01*
G01X-308913Y230033D02*
X-309016Y229931D01*
G01X-312815Y226142D02*
X-312284Y226674D01*
G01X-320670Y218780D02*
X-321260Y218189D01*
G01X-306244Y233747D02*
X-306142Y233850D01*
G01X-308662Y231339D02*
X-309193Y230807D01*
G01D02*
X-308662Y231339D01*
G01X-312992Y228248D02*
X-313386Y227855D01*
G01X-308913Y233183D02*
X-309016Y233080D01*
G01X-312815Y229292D02*
X-312284Y229823D01*
G01X-320670Y221929D02*
X-321260Y221339D01*
G01X-306244Y236896D02*
X-306142Y236999D01*
G01X-308662Y234489D02*
X-309193Y233957D01*
G01D02*
X-308662Y234489D01*
G01X-312992Y231398D02*
X-313386Y231004D01*
G01X-308913Y236332D02*
X-309016Y236230D01*
G01X-312815Y232441D02*
X-312284Y232973D01*
G01X-320670Y225079D02*
X-321260Y224489D01*
G01X-306244Y240046D02*
X-306142Y240149D01*
G01X-308662Y237638D02*
X-309193Y237107D01*
G01D02*
X-308662Y237638D01*
G01X-312992Y234548D02*
X-313386Y234154D01*
G01X-274803Y273071D02*
X-276772Y271103D01*
G01X-308913Y239482D02*
X-309016Y239379D01*
G01X-312815Y235591D02*
X-312284Y236122D01*
G01X-320670Y228229D02*
X-321260Y227638D01*
G01X-306244Y243196D02*
X-306142Y243298D01*
G01X-308662Y240788D02*
X-309193Y240256D01*
G01D02*
X-308662Y240788D01*
G01X-312992Y237697D02*
X-313386Y237303D01*
G01X-308913Y242631D02*
X-309016Y242529D01*
G01X-312815Y238740D02*
X-312284Y239272D01*
G01X-320670Y231378D02*
X-321260Y230788D01*
G01X-306244Y246345D02*
X-306142Y246448D01*
G01X-308662Y243937D02*
X-309193Y243406D01*
G01D02*
X-308662Y243937D01*
G01X-312992Y240847D02*
X-313386Y240453D01*
G01X-308913Y245781D02*
X-309016Y245679D01*
G01X-312815Y241890D02*
X-312284Y242422D01*
G01X-320670Y234528D02*
X-321260Y233937D01*
G01X-308662Y247087D02*
X-309193Y246555D01*
G01D02*
X-308662Y247087D01*
G01X-312992Y243996D02*
X-313386Y243603D01*
G01X-312815Y245040D02*
X-312284Y245571D01*
G01X-320670Y237677D02*
X-321260Y237087D01*
G01X-320670Y240827D02*
X-321260Y240237D01*
G01X-320670Y243977D02*
X-321260Y243386D01*
G01X-309669Y205611D02*
X-309449Y206142D01*
G01X-309669Y208760D02*
X-309449Y209292D01*
G01X-309669Y211910D02*
X-309449Y212441D01*
G01X-309669Y215059D02*
X-309449Y215591D01*
G01X-309669Y218209D02*
X-309449Y218740D01*
G01X-309669Y221359D02*
X-309449Y221890D01*
G01X-309669Y224508D02*
X-309449Y225040D01*
G01X-309669Y227658D02*
X-309449Y228189D01*
G01X-309669Y230807D02*
X-309449Y231339D01*
G01X-309669Y233957D02*
X-309449Y234489D01*
G01X-309669Y237107D02*
X-309449Y237638D01*
G01X-309669Y240256D02*
X-309449Y240788D01*
G01X-309669Y243406D02*
X-309449Y243937D01*
G01X-309669Y246555D02*
X-309449Y247087D01*
G01X-276772Y271103D02*
X-278740D01*
G01Y270512D02*
X-276378D01*
G01X-263942D02*
X-278347D01*
G01X-276378Y269095D02*
X-255906D01*
G01X-278740Y268544D02*
X-276378D01*
G01X-260197D02*
X-278347D01*
G01X-340636Y268465D02*
X-343097D01*
G01X-326693D02*
X-329154D01*
G01X-251969Y268347D02*
X-276378D01*
G01X-278740Y267953D02*
X-274803D01*
G01X-251969Y266339D02*
X-278740D01*
G01X-290539Y244721D02*
X-289641Y244882D01*
G01X-290539Y241572D02*
X-289641Y241733D01*
G01X-290539Y238422D02*
X-289641Y238583D01*
G01X-290539Y235272D02*
X-289641Y235433D01*
G01X-290539Y232123D02*
X-289641Y232284D01*
G01X-289491Y246457D02*
X-290085Y246342D01*
G01X-289491Y243307D02*
X-290085Y243193D01*
G01X-289491Y240158D02*
X-290085Y240043D01*
G01X-289491Y237008D02*
X-290085Y236894D01*
G01X-289491Y233859D02*
X-290085Y233744D01*
G01X-289491Y230709D02*
X-290085Y230594D01*
G01X-289491Y227559D02*
X-290085Y227445D01*
G01X-291879Y245775D02*
X-292395Y245670D01*
G01X-291879Y242626D02*
X-292395Y242520D01*
G01X-291879Y239476D02*
X-292395Y239370D01*
G01X-291879Y236326D02*
X-292395Y236221D01*
G01X-291879Y233177D02*
X-292395Y233071D01*
G01X-291879Y230027D02*
X-292395Y229922D01*
G01X-291879Y226877D02*
X-292395Y226772D01*
G01X-291414Y244245D02*
X-291438Y244240D01*
G01X-291414Y241095D02*
X-291438Y241090D01*
G01X-291414Y237946D02*
X-291438Y237940D01*
G01X-291414Y234796D02*
X-291438Y234791D01*
G01X-291414Y231646D02*
X-291438Y231641D01*
G01X-291414Y228497D02*
X-291438Y228492D01*
G01X-291414Y225347D02*
X-291438Y225342D01*
G01X-286064Y244095D02*
X-285329Y244292D01*
G01X-286064Y240945D02*
X-285329Y241142D01*
G01X-286064Y237796D02*
X-285329Y237992D01*
G01X-286064Y234646D02*
X-285329Y234843D01*
G01X-286064Y231496D02*
X-285329Y231693D01*
G01X-286064Y228347D02*
X-285329Y228544D01*
G01X-286064Y225197D02*
X-285329Y225394D01*
G01X-286064Y222048D02*
X-285329Y222244D01*
G01X-286064Y218898D02*
X-285329Y219095D01*
G01X-286064Y215748D02*
X-285329Y215945D01*
G01X-286064Y212599D02*
X-285329Y212796D01*
G01X-296841Y251793D02*
X-297028Y250827D01*
G01X-285338Y210042D02*
Y209644D01*
G01Y213192D02*
Y212793D01*
G01Y216341D02*
Y215943D01*
G01Y219491D02*
Y219092D01*
G01Y222640D02*
Y222242D01*
G01Y225790D02*
Y225392D01*
G01Y228940D02*
Y228541D01*
G01Y232089D02*
Y231691D01*
G01Y235239D02*
Y234840D01*
G01Y238389D02*
Y237990D01*
G01Y241538D02*
Y241140D01*
G01Y244688D02*
Y244289D01*
G01Y206892D02*
Y206494D01*
G01X-274803Y291103D02*
Y267953D01*
G01X-275610Y254036D02*
Y239370D01*
G01X-276378Y270512D02*
Y268544D01*
G01Y271496D02*
Y267953D01*
G01X-277599Y268544D02*
Y270512D01*
G01X-278347D02*
Y268544D01*
G01X-278740D02*
Y266339D01*
G01Y278544D02*
Y270512D01*
G01X-280217Y252756D02*
Y249213D01*
G01X-280512Y247500D02*
Y252756D01*
G01X-282284Y205906D02*
Y204331D01*
G01Y212205D02*
Y210630D01*
G01Y209055D02*
Y207481D01*
G01Y215355D02*
Y213780D01*
G01Y221654D02*
Y220079D01*
G01Y218504D02*
Y216929D01*
G01Y224803D02*
Y223229D01*
G01Y231103D02*
Y229528D01*
G01Y227953D02*
Y226378D01*
G01Y234252D02*
Y232677D01*
G01Y240552D02*
Y238977D01*
G01Y237402D02*
Y235827D01*
G01Y243701D02*
Y242126D01*
G01Y246851D02*
Y245276D01*
G01X-282677Y296654D02*
Y262402D01*
G01X-283721Y245040D02*
Y247087D01*
G01Y238740D02*
Y240788D01*
G01Y241890D02*
Y243937D01*
G01Y235591D02*
Y237638D01*
G01Y229292D02*
Y231339D01*
G01Y232441D02*
Y234489D01*
G01Y226142D02*
Y228189D01*
G01Y222992D02*
Y225040D01*
G01Y216693D02*
Y218740D01*
G01Y219843D02*
Y221890D01*
G01Y213544D02*
Y215591D01*
G01Y207244D02*
Y209292D01*
G01Y210394D02*
Y212441D01*
G01X-284252Y245571D02*
Y246555D01*
G01Y242422D02*
Y243406D01*
G01Y239272D02*
Y240256D01*
G01Y236122D02*
Y237107D01*
G01Y232973D02*
Y233957D01*
G01Y229823D02*
Y230807D01*
G01Y226674D02*
Y227658D01*
G01Y223524D02*
Y224508D01*
G01Y220374D02*
Y221359D01*
G01Y217225D02*
Y218209D01*
G01Y214075D02*
Y215059D01*
G01Y210926D02*
Y211910D01*
G01Y207776D02*
Y208760D01*
G01Y204626D02*
Y205611D01*
G01X-285329Y241142D02*
Y241536D01*
G01Y244292D02*
Y244685D01*
G01Y237992D02*
Y238386D01*
G01Y231693D02*
Y232087D01*
G01Y234843D02*
Y235237D01*
G01Y228544D02*
Y228937D01*
G01Y222244D02*
Y222638D01*
G01Y225394D02*
Y225788D01*
G01Y219095D02*
Y219489D01*
G01Y212796D02*
Y213189D01*
G01Y215945D02*
Y216339D01*
G01Y209646D02*
Y210040D01*
G01Y206495D02*
Y206890D01*
G01X-285546Y205512D02*
Y204725D01*
G01Y208662D02*
Y207874D01*
G01Y211811D02*
Y211024D01*
G01Y214961D02*
Y214174D01*
G01Y218111D02*
Y217323D01*
G01Y221260D02*
Y220473D01*
G01Y224410D02*
Y223622D01*
G01Y227559D02*
Y226772D01*
G01Y230709D02*
Y229922D01*
G01Y233859D02*
Y233071D01*
G01Y237008D02*
Y236221D01*
G01Y240158D02*
Y239370D01*
G01Y243307D02*
Y242520D01*
G01Y246457D02*
Y245670D01*
G01X-285573Y205512D02*
Y204725D01*
G01Y208662D02*
Y207874D01*
G01Y211811D02*
Y211024D01*
G01Y214961D02*
Y214174D01*
G01Y218111D02*
Y217323D01*
G01Y221260D02*
Y220473D01*
G01Y224410D02*
Y223622D01*
G01Y227559D02*
Y226772D01*
G01Y230709D02*
Y229922D01*
G01Y233859D02*
Y233071D01*
G01Y237008D02*
Y236221D01*
G01Y240158D02*
Y239370D01*
G01Y243307D02*
Y242520D01*
G01Y246457D02*
Y245670D01*
G01X-285582Y206958D02*
Y206429D01*
G01Y210107D02*
Y209578D01*
G01Y213257D02*
Y212728D01*
G01Y216407D02*
Y215877D01*
G01Y219556D02*
Y219027D01*
G01Y222706D02*
Y222177D01*
G01Y225855D02*
Y225326D01*
G01Y229005D02*
Y228476D01*
G01Y232155D02*
Y231626D01*
G01Y235304D02*
Y234775D01*
G01Y238454D02*
Y237925D01*
G01Y241603D02*
Y241074D01*
G01Y244753D02*
Y244224D01*
G01X-285587Y241073D02*
Y241605D01*
G01Y244223D02*
Y244754D01*
G01Y237924D02*
Y238455D01*
G01Y231624D02*
Y232156D01*
G01Y234774D02*
Y235305D01*
G01Y228475D02*
Y229006D01*
G01Y222176D02*
Y222707D01*
G01Y225325D02*
Y225857D01*
G01Y219026D02*
Y219557D01*
G01Y212727D02*
Y213258D01*
G01Y215876D02*
Y216408D01*
G01Y209577D02*
Y210109D01*
G01Y206427D02*
Y206959D01*
G01X-285627Y245670D02*
Y246457D01*
G01Y242520D02*
Y243307D01*
G01Y236221D02*
Y237008D01*
G01Y239370D02*
Y240158D01*
G01Y233071D02*
Y233859D01*
G01Y226772D02*
Y227559D01*
G01Y229922D02*
Y230709D01*
G01Y223622D02*
Y224410D01*
G01Y217323D02*
Y218111D01*
G01Y220473D02*
Y221260D01*
G01Y214174D02*
Y214961D01*
G01Y207874D02*
Y208662D01*
G01Y211024D02*
Y211811D01*
G01Y204725D02*
Y205512D01*
G01X-285827Y247500D02*
Y252756D01*
G01X-285850Y241003D02*
Y241675D01*
G01Y244152D02*
Y244825D01*
G01Y237853D02*
Y238526D01*
G01Y231554D02*
Y232226D01*
G01Y234703D02*
Y235376D01*
G01Y228404D02*
Y229077D01*
G01Y222105D02*
Y222777D01*
G01Y225255D02*
Y225927D01*
G01Y218955D02*
Y219628D01*
G01Y212656D02*
Y213329D01*
G01Y215806D02*
Y216478D01*
G01Y209507D02*
Y210179D01*
G01Y206357D02*
Y207029D01*
G01X-285877Y205512D02*
Y204725D01*
G01Y208662D02*
Y207874D01*
G01Y211811D02*
Y211024D01*
G01Y214961D02*
Y214174D01*
G01Y218111D02*
Y217323D01*
G01Y221260D02*
Y220473D01*
G01Y224410D02*
Y223622D01*
G01Y227559D02*
Y226772D01*
G01Y230709D02*
Y229922D01*
G01Y233859D02*
Y233071D01*
G01Y237008D02*
Y236221D01*
G01Y240158D02*
Y239370D01*
G01Y243307D02*
Y242520D01*
G01Y246457D02*
Y245670D01*
G01X-286614Y252756D02*
Y247500D01*
G01X-286688Y207087D02*
Y206300D01*
G01Y210237D02*
Y209449D01*
G01Y213386D02*
Y212599D01*
G01Y216536D02*
Y215748D01*
G01Y219685D02*
Y218898D01*
G01Y222835D02*
Y222048D01*
G01Y225985D02*
Y225197D01*
G01Y229134D02*
Y228347D01*
G01Y232284D02*
Y231496D01*
G01Y235433D02*
Y234646D01*
G01Y238583D02*
Y237796D01*
G01Y241733D02*
Y240945D01*
G01Y244882D02*
Y244095D01*
G01X-287160Y245670D02*
Y246457D01*
G01Y242520D02*
Y243307D01*
G01Y236221D02*
Y237008D01*
G01Y239370D02*
Y240158D01*
G01Y233071D02*
Y233859D01*
G01Y226772D02*
Y227559D01*
G01Y229922D02*
Y230709D01*
G01Y223622D02*
Y224410D01*
G01Y217323D02*
Y218111D01*
G01Y220473D02*
Y221260D01*
G01Y214174D02*
Y214961D01*
G01Y207874D02*
Y208662D01*
G01Y211024D02*
Y211811D01*
G01Y204725D02*
Y205512D01*
G01X-287992Y246555D02*
Y247087D01*
G01Y245040D02*
Y245571D01*
G01Y243406D02*
Y243937D01*
G01Y241890D02*
Y242422D01*
G01Y240256D02*
Y240788D01*
G01Y238740D02*
Y239272D01*
G01Y237107D02*
Y237638D01*
G01Y235591D02*
Y236122D01*
G01Y233957D02*
Y234489D01*
G01Y232441D02*
Y232973D01*
G01Y230807D02*
Y231339D01*
G01Y229292D02*
Y229823D01*
G01Y227658D02*
Y228189D01*
G01Y226142D02*
Y226674D01*
G01Y224508D02*
Y225040D01*
G01Y222992D02*
Y223524D01*
G01Y221359D02*
Y221890D01*
G01Y219843D02*
Y220374D01*
G01Y218209D02*
Y218740D01*
G01Y216693D02*
Y217225D01*
G01Y215059D02*
Y215591D01*
G01Y213544D02*
Y214075D01*
G01Y211910D02*
Y212441D01*
G01Y210394D02*
Y210926D01*
G01Y208760D02*
Y209292D01*
G01Y207244D02*
Y207776D01*
G01Y205611D02*
Y206142D01*
G01X-288878Y249213D02*
Y252756D01*
G01X-288977D02*
Y247500D01*
G01X-290085Y205398D02*
Y204839D01*
G01Y208547D02*
Y207989D01*
G01Y211697D02*
Y211139D01*
G01Y214846D02*
Y214288D01*
G01Y217996D02*
Y217438D01*
G01Y221146D02*
Y220587D01*
G01Y224295D02*
Y223737D01*
G01Y227445D02*
Y226887D01*
G01Y230594D02*
Y230036D01*
G01Y233744D02*
Y233186D01*
G01Y236894D02*
Y236335D01*
G01Y240043D02*
Y239485D01*
G01Y243193D02*
Y242635D01*
G01Y246342D02*
Y245784D01*
G01X-290510Y245670D02*
Y246457D01*
G01Y242520D02*
Y243307D01*
G01Y236221D02*
Y237008D01*
G01Y239370D02*
Y240158D01*
G01Y233071D02*
Y233859D01*
G01Y226772D02*
Y227559D01*
G01Y229922D02*
Y230709D01*
G01Y223622D02*
Y224410D01*
G01Y217323D02*
Y218111D01*
G01Y220473D02*
Y221260D01*
G01Y214174D02*
Y214961D01*
G01Y207874D02*
Y208662D01*
G01Y211024D02*
Y211811D01*
G01Y204725D02*
Y205512D01*
G01X-290539Y241106D02*
Y241572D01*
G01Y244256D02*
Y244721D01*
G01Y237957D02*
Y238422D01*
G01Y231657D02*
Y232123D01*
G01Y234807D02*
Y235272D01*
G01Y228508D02*
Y228973D01*
G01Y222209D02*
Y222674D01*
G01Y225358D02*
Y225824D01*
G01Y219059D02*
Y219524D01*
G01Y212760D02*
Y213225D01*
G01Y215909D02*
Y216375D01*
G01Y209610D02*
Y210076D01*
G01Y206461D02*
Y206926D01*
G01X-290840Y207087D02*
Y206300D01*
G01Y210237D02*
Y209449D01*
G01Y213386D02*
Y212599D01*
G01Y216536D02*
Y215748D01*
G01Y219685D02*
Y218898D01*
G01Y222835D02*
Y222048D01*
G01Y225985D02*
Y225197D01*
G01Y229134D02*
Y228347D01*
G01Y232284D02*
Y231496D01*
G01Y235433D02*
Y234646D01*
G01Y238583D02*
Y237796D01*
G01Y241733D02*
Y240945D01*
G01Y244882D02*
Y244095D01*
G01X-291057Y240945D02*
Y241733D01*
G01Y244095D02*
Y244882D01*
G01Y237796D02*
Y238583D01*
G01Y231496D02*
Y232284D01*
G01Y234646D02*
Y235433D01*
G01Y228347D02*
Y229134D01*
G01Y222048D02*
Y222835D01*
G01Y225197D02*
Y225985D01*
G01Y218898D02*
Y219685D01*
G01Y212599D02*
Y213386D01*
G01Y215748D02*
Y216536D01*
G01Y209449D02*
Y210237D01*
G01Y206300D02*
Y207087D01*
G01X-291197D02*
Y206300D01*
G01Y210237D02*
Y209449D01*
G01Y213386D02*
Y212599D01*
G01Y216536D02*
Y215748D01*
G01Y219685D02*
Y218898D01*
G01Y222835D02*
Y222048D01*
G01Y225985D02*
Y225197D01*
G01Y229134D02*
Y228347D01*
G01Y232284D02*
Y231496D01*
G01Y235433D02*
Y234646D01*
G01Y238583D02*
Y237796D01*
G01Y241733D02*
Y240945D01*
G01Y244882D02*
Y244095D01*
G01X-291380Y240945D02*
Y241733D01*
G01Y244095D02*
Y244882D01*
G01Y237796D02*
Y238583D01*
G01Y231496D02*
Y232284D01*
G01Y234646D02*
Y235433D01*
G01Y228347D02*
Y229134D01*
G01Y222048D02*
Y222835D01*
G01Y225197D02*
Y225985D01*
G01Y218898D02*
Y219685D01*
G01Y212599D02*
Y213386D01*
G01Y215748D02*
Y216536D01*
G01Y209449D02*
Y210237D01*
G01Y206300D02*
Y207087D01*
G01X-291414Y206937D02*
Y206450D01*
G01Y210087D02*
Y209599D01*
G01Y213236D02*
Y212749D01*
G01Y216386D02*
Y215898D01*
G01Y219535D02*
Y219048D01*
G01Y222685D02*
Y222198D01*
G01Y225835D02*
Y225347D01*
G01Y228984D02*
Y228497D01*
G01Y232134D02*
Y231646D01*
G01Y235283D02*
Y234796D01*
G01Y238433D02*
Y237946D01*
G01Y241583D02*
Y241095D01*
G01Y244732D02*
Y244245D01*
G01X-291438Y241090D02*
Y241588D01*
G01Y244240D02*
Y244737D01*
G01Y237940D02*
Y238438D01*
G01Y231641D02*
Y232139D01*
G01Y234791D02*
Y235289D01*
G01Y228492D02*
Y228989D01*
G01Y222192D02*
Y222690D01*
G01Y225342D02*
Y225840D01*
G01Y219043D02*
Y219540D01*
G01Y212744D02*
Y213241D01*
G01Y215893D02*
Y216391D01*
G01Y209594D02*
Y210092D01*
G01Y206444D02*
Y206942D01*
G01X-291535Y205512D02*
Y204725D01*
G01Y208662D02*
Y207874D01*
G01Y211811D02*
Y211024D01*
G01Y214961D02*
Y214174D01*
G01Y218111D02*
Y217323D01*
G01Y221260D02*
Y220473D01*
G01Y224410D02*
Y223622D01*
G01Y227559D02*
Y226772D01*
G01Y230709D02*
Y229922D01*
G01Y233859D02*
Y233071D01*
G01Y237008D02*
Y236221D01*
G01Y240158D02*
Y239370D01*
G01Y243307D02*
Y242520D01*
G01Y246457D02*
Y245670D01*
G01X-291637Y206972D02*
Y206414D01*
G01Y210122D02*
Y209564D01*
G01Y213272D02*
Y212713D01*
G01Y216421D02*
Y215863D01*
G01Y219571D02*
Y219013D01*
G01Y222720D02*
Y222162D01*
G01Y225870D02*
Y225312D01*
G01Y229020D02*
Y228461D01*
G01Y232169D02*
Y231611D01*
G01Y235319D02*
Y234761D01*
G01Y238468D02*
Y237910D01*
G01Y241618D02*
Y241060D01*
G01Y244768D02*
Y244209D01*
G01X-291879Y245775D02*
Y246352D01*
G01Y242626D02*
Y243202D01*
G01Y236326D02*
Y236903D01*
G01Y239476D02*
Y240052D01*
G01Y233177D02*
Y233753D01*
G01Y226877D02*
Y227454D01*
G01Y230027D02*
Y230603D01*
G01Y223728D02*
Y224304D01*
G01Y217429D02*
Y218005D01*
G01Y220578D02*
Y221155D01*
G01Y214279D02*
Y214855D01*
G01Y207980D02*
Y208556D01*
G01Y211129D02*
Y211706D01*
G01Y204830D02*
Y205407D01*
G01X-293898Y207776D02*
Y207244D01*
G01Y206142D02*
Y205611D01*
G01Y212441D02*
Y211910D01*
G01Y210926D02*
Y210394D01*
G01Y209292D02*
Y208760D01*
G01Y217225D02*
Y216693D01*
G01Y215591D02*
Y215059D01*
G01Y214075D02*
Y213544D01*
G01Y221890D02*
Y221359D01*
G01Y220374D02*
Y219843D01*
G01Y218740D02*
Y218209D01*
G01Y225040D02*
Y224508D01*
G01Y223524D02*
Y222992D01*
G01Y229823D02*
Y229292D01*
G01Y228189D02*
Y227658D01*
G01Y226674D02*
Y226142D01*
G01Y234489D02*
Y233957D01*
G01Y232973D02*
Y232441D01*
G01Y231339D02*
Y230807D01*
G01Y239272D02*
Y238740D01*
G01Y237638D02*
Y237107D01*
G01Y236122D02*
Y235591D01*
G01Y243937D02*
Y243406D01*
G01Y242422D02*
Y241890D01*
G01Y240788D02*
Y240256D01*
G01Y247087D02*
Y246555D01*
G01Y245571D02*
Y245040D01*
G01X-294488Y252756D02*
Y247500D01*
G01X-295276Y252756D02*
Y247500D01*
G01X-295925Y251772D02*
Y252756D01*
G01X-296418Y250788D02*
Y251772D01*
G01X-301240Y252756D02*
Y251642D01*
G01X-302028Y252756D02*
Y251772D01*
G01X-302422D02*
Y252756D01*
G01X-303504D02*
Y251772D01*
G01X-303603D02*
Y252756D01*
G01X-304331Y207087D02*
Y206300D01*
G01Y210237D02*
Y209449D01*
G01Y213386D02*
Y212599D01*
G01Y216536D02*
Y215748D01*
G01Y219685D02*
Y218898D01*
G01Y222835D02*
Y222048D01*
G01Y225985D02*
Y225197D01*
G01Y229134D02*
Y228347D01*
G01Y232284D02*
Y231496D01*
G01Y235433D02*
Y234646D01*
G01Y238583D02*
Y237796D01*
G01Y241733D02*
Y240945D01*
G01Y244882D02*
Y244095D01*
G01X-304799Y205512D02*
Y204725D01*
G01Y208662D02*
Y207874D01*
G01Y211811D02*
Y211024D01*
G01Y214961D02*
Y214174D01*
G01Y218111D02*
Y217323D01*
G01Y221260D02*
Y220473D01*
G01Y224410D02*
Y223622D01*
G01Y227559D02*
Y226772D01*
G01Y230709D02*
Y229922D01*
G01Y233859D02*
Y233071D01*
G01Y237008D02*
Y236221D01*
G01Y240158D02*
Y239370D01*
G01Y243307D02*
Y242520D01*
G01Y246457D02*
Y245670D01*
G01X-304922Y240945D02*
Y241733D01*
G01Y244095D02*
Y244882D01*
G01Y237796D02*
Y238583D01*
G01Y231496D02*
Y232284D01*
G01Y234646D02*
Y235433D01*
G01Y228347D02*
Y229134D01*
G01Y222048D02*
Y222835D01*
G01Y225197D02*
Y225985D01*
G01Y218898D02*
Y219685D01*
G01Y212599D02*
Y213386D01*
G01Y215748D02*
Y216536D01*
G01Y209449D02*
Y210237D01*
G01Y206300D02*
Y207087D01*
G01X-305233Y245670D02*
Y246457D01*
G01Y242520D02*
Y243307D01*
G01Y236221D02*
Y237008D01*
G01Y239370D02*
Y240158D01*
G01Y233071D02*
Y233859D01*
G01Y226772D02*
Y227559D01*
G01Y229922D02*
Y230709D01*
G01Y223622D02*
Y224410D01*
G01Y217323D02*
Y218111D01*
G01Y220473D02*
Y221260D01*
G01Y214174D02*
Y214961D01*
G01Y207874D02*
Y208662D01*
G01Y211024D02*
Y211811D01*
G01Y204725D02*
Y205512D01*
G01X-305457Y245670D02*
Y246457D01*
G01Y242520D02*
Y243307D01*
G01Y236221D02*
Y237008D01*
G01Y239370D02*
Y240158D01*
G01Y233071D02*
Y233859D01*
G01Y226772D02*
Y227559D01*
G01Y229922D02*
Y230709D01*
G01Y223622D02*
Y224410D01*
G01Y217323D02*
Y218111D01*
G01Y220473D02*
Y221260D01*
G01Y214174D02*
Y214961D01*
G01Y207874D02*
Y208662D01*
G01Y211024D02*
Y211811D01*
G01Y204725D02*
Y205512D01*
G01X-305473Y245571D02*
Y246555D01*
G01Y242422D02*
Y243406D01*
G01Y236122D02*
Y237107D01*
G01Y239272D02*
Y240256D01*
G01Y232973D02*
Y233957D01*
G01Y226674D02*
Y227658D01*
G01Y229823D02*
Y230807D01*
G01Y223524D02*
Y224508D01*
G01Y217225D02*
Y218209D01*
G01Y220374D02*
Y221359D01*
G01Y214075D02*
Y215059D01*
G01Y207776D02*
Y208760D01*
G01Y210926D02*
Y211910D01*
G01Y204626D02*
Y205611D01*
G01X-305512Y207087D02*
Y206300D01*
G01Y210237D02*
Y209449D01*
G01Y213386D02*
Y212599D01*
G01Y216536D02*
Y215748D01*
G01Y219685D02*
Y218898D01*
G01Y222835D02*
Y222048D01*
G01Y225985D02*
Y225197D01*
G01Y229134D02*
Y228347D01*
G01Y232284D02*
Y231496D01*
G01Y235433D02*
Y234646D01*
G01Y238583D02*
Y237796D01*
G01Y241733D02*
Y240945D01*
G01Y244882D02*
Y244095D01*
G01X-305788Y245571D02*
Y246555D01*
G01Y242422D02*
Y243406D01*
G01Y236122D02*
Y237107D01*
G01Y239272D02*
Y240256D01*
G01Y232973D02*
Y233957D01*
G01Y226674D02*
Y227658D01*
G01Y229823D02*
Y230807D01*
G01Y223524D02*
Y224508D01*
G01Y217225D02*
Y218209D01*
G01Y220374D02*
Y221359D01*
G01Y214075D02*
Y215059D01*
G01Y207776D02*
Y208760D01*
G01Y210926D02*
Y211910D01*
G01Y204626D02*
Y205611D01*
G01X-305890Y205512D02*
Y204725D01*
G01Y208662D02*
Y207874D01*
G01Y211811D02*
Y211024D01*
G01Y214961D02*
Y214174D01*
G01Y218111D02*
Y217323D01*
G01Y221260D02*
Y220473D01*
G01Y224410D02*
Y223622D01*
G01Y227559D02*
Y226772D01*
G01Y230709D02*
Y229922D01*
G01Y233859D02*
Y233071D01*
G01Y237008D02*
Y236221D01*
G01Y240158D02*
Y239370D01*
G01Y243307D02*
Y242520D01*
G01Y246457D02*
Y245670D01*
G01X-306103Y207087D02*
Y206300D01*
G01Y205611D02*
Y204626D01*
G01Y210237D02*
Y209449D01*
G01Y208760D02*
Y207776D01*
G01Y211910D02*
Y210926D01*
G01Y213386D02*
Y212599D01*
G01Y216536D02*
Y215748D01*
G01Y215059D02*
Y214075D01*
G01Y219685D02*
Y218898D01*
G01Y218209D02*
Y217225D01*
G01Y221359D02*
Y220374D01*
G01Y222835D02*
Y222048D01*
G01Y225985D02*
Y225197D01*
G01Y224508D02*
Y223524D01*
G01Y229134D02*
Y228347D01*
G01Y227658D02*
Y226674D01*
G01Y230807D02*
Y229823D01*
G01Y232284D02*
Y231496D01*
G01Y235433D02*
Y234646D01*
G01Y233957D02*
Y232973D01*
G01Y238583D02*
Y237796D01*
G01Y237107D02*
Y236122D01*
G01Y240256D02*
Y239272D01*
G01Y241733D02*
Y240945D01*
G01Y244882D02*
Y244095D01*
G01Y243406D02*
Y242422D01*
G01Y246555D02*
Y245571D01*
G01X-306142Y245679D02*
Y246448D01*
G01Y242529D02*
Y243298D01*
G01Y236230D02*
Y236999D01*
G01Y239379D02*
Y240149D01*
G01Y233080D02*
Y233850D01*
G01Y226781D02*
Y227550D01*
G01Y229931D02*
Y230700D01*
G01Y223631D02*
Y224401D01*
G01Y217332D02*
Y218102D01*
G01Y220482D02*
Y221251D01*
G01Y214183D02*
Y214952D01*
G01Y207883D02*
Y208653D01*
G01Y211033D02*
Y211802D01*
G01Y204734D02*
Y205503D01*
G01X-306244Y205400D02*
Y204836D01*
G01Y208550D02*
Y207986D01*
G01Y211700D02*
Y211135D01*
G01Y214849D02*
Y214285D01*
G01Y217999D02*
Y217435D01*
G01Y221148D02*
Y220584D01*
G01Y224298D02*
Y223734D01*
G01Y227448D02*
Y226883D01*
G01Y230597D02*
Y230033D01*
G01Y233747D02*
Y233183D01*
G01Y236896D02*
Y236332D01*
G01Y240046D02*
Y239482D01*
G01Y243196D02*
Y242631D01*
G01Y246345D02*
Y245781D01*
G01X-306500Y245866D02*
Y246260D01*
G01Y242717D02*
Y243111D01*
G01Y236418D02*
Y236811D01*
G01Y239567D02*
Y239961D01*
G01Y233268D02*
Y233662D01*
G01Y226969D02*
Y227363D01*
G01Y230118D02*
Y230512D01*
G01Y223819D02*
Y224213D01*
G01Y217520D02*
Y217914D01*
G01Y220670D02*
Y221063D01*
G01Y214370D02*
Y214764D01*
G01Y208071D02*
Y208465D01*
G01Y211221D02*
Y211615D01*
G01Y204922D02*
Y205315D01*
G01X-306693Y207087D02*
Y206300D01*
G01Y210237D02*
Y209449D01*
G01Y213386D02*
Y212599D01*
G01Y216536D02*
Y215748D01*
G01Y219685D02*
Y218898D01*
G01Y222835D02*
Y222048D01*
G01Y225985D02*
Y225197D01*
G01Y229134D02*
Y228347D01*
G01Y232284D02*
Y231496D01*
G01Y235433D02*
Y234646D01*
G01Y238583D02*
Y237796D01*
G01Y241733D02*
Y240945D01*
G01Y244882D02*
Y244095D01*
G01X-307351Y207087D02*
Y206300D01*
G01Y210237D02*
Y209449D01*
G01Y213386D02*
Y212599D01*
G01Y216536D02*
Y215748D01*
G01Y219685D02*
Y218898D01*
G01Y222835D02*
Y222048D01*
G01Y225985D02*
Y225197D01*
G01Y229134D02*
Y228347D01*
G01Y232284D02*
Y231496D01*
G01Y235433D02*
Y234646D01*
G01Y238583D02*
Y237796D01*
G01Y241733D02*
Y240945D01*
G01Y244882D02*
Y244095D01*
G01X-307605Y240945D02*
Y241733D01*
G01Y244095D02*
Y244882D01*
G01Y237796D02*
Y238583D01*
G01Y231496D02*
Y232284D01*
G01Y234646D02*
Y235433D01*
G01Y228347D02*
Y229134D01*
G01Y222048D02*
Y222835D01*
G01Y225197D02*
Y225985D01*
G01Y218898D02*
Y219685D01*
G01Y212599D02*
Y213386D01*
G01Y215748D02*
Y216536D01*
G01Y209449D02*
Y210237D01*
G01Y206300D02*
Y207087D01*
G01X-307628Y240945D02*
Y241733D01*
G01Y244095D02*
Y244882D01*
G01Y237796D02*
Y238583D01*
G01Y231496D02*
Y232284D01*
G01Y234646D02*
Y235433D01*
G01Y228347D02*
Y229134D01*
G01Y222048D02*
Y222835D01*
G01Y225197D02*
Y225985D01*
G01Y218898D02*
Y219685D01*
G01Y212599D02*
Y213386D01*
G01Y215748D02*
Y216536D01*
G01Y209449D02*
Y210237D01*
G01Y206300D02*
Y207087D01*
G01X-307874Y246555D02*
Y252756D01*
G01Y240256D02*
Y242422D01*
G01Y243406D02*
Y245571D01*
G01Y237107D02*
Y239272D01*
G01Y230807D02*
Y232973D01*
G01Y233957D02*
Y236122D01*
G01Y227658D02*
Y229823D01*
G01Y224508D02*
Y226674D01*
G01Y218209D02*
Y220374D01*
G01Y221359D02*
Y223524D01*
G01Y215059D02*
Y217225D01*
G01Y208760D02*
Y210926D01*
G01Y211910D02*
Y214075D01*
G01Y205611D02*
Y207776D01*
G01X-308657Y205315D02*
Y204922D01*
G01Y208465D02*
Y208071D01*
G01Y211615D02*
Y211221D01*
G01Y214764D02*
Y214370D01*
G01Y217914D02*
Y217520D01*
G01Y221063D02*
Y220670D01*
G01Y224213D02*
Y223819D01*
G01Y227363D02*
Y226969D01*
G01Y230512D02*
Y230118D01*
G01Y233662D02*
Y233268D01*
G01Y236811D02*
Y236418D01*
G01Y239961D02*
Y239567D01*
G01Y243111D02*
Y242717D01*
G01Y246260D02*
Y245866D01*
G01X-308662Y207244D02*
Y206142D01*
G01Y210394D02*
Y209292D01*
G01Y213544D02*
Y212441D01*
G01Y216693D02*
Y215591D01*
G01Y219843D02*
Y218740D01*
G01Y222992D02*
Y221890D01*
G01Y226142D02*
Y225040D01*
G01Y229292D02*
Y228189D01*
G01Y232441D02*
Y231339D01*
G01Y235591D02*
Y234489D01*
G01Y238740D02*
Y237638D01*
G01Y241890D02*
Y240788D01*
G01Y245040D02*
Y243937D01*
G01Y252756D02*
Y247087D01*
G01X-308783Y207087D02*
Y206300D01*
G01Y210237D02*
Y209449D01*
G01Y213386D02*
Y212599D01*
G01Y216536D02*
Y215748D01*
G01Y219685D02*
Y218898D01*
G01Y222835D02*
Y222048D01*
G01Y225985D02*
Y225197D01*
G01Y229134D02*
Y228347D01*
G01Y232284D02*
Y231496D01*
G01Y235433D02*
Y234646D01*
G01Y238583D02*
Y237796D01*
G01Y241733D02*
Y240945D01*
G01Y244882D02*
Y244095D01*
G01X-308888Y245670D02*
Y246457D01*
G01Y242520D02*
Y243307D01*
G01Y236221D02*
Y237008D01*
G01Y239370D02*
Y240158D01*
G01Y233071D02*
Y233859D01*
G01Y226772D02*
Y227559D01*
G01Y229922D02*
Y230709D01*
G01Y223622D02*
Y224410D01*
G01Y217323D02*
Y218111D01*
G01Y220473D02*
Y221260D01*
G01Y214174D02*
Y214961D01*
G01Y207874D02*
Y208662D01*
G01Y211024D02*
Y211811D01*
G01Y204725D02*
Y205512D01*
G01X-308901Y240945D02*
Y241733D01*
G01Y244095D02*
Y244882D01*
G01Y237796D02*
Y238583D01*
G01Y231496D02*
Y232284D01*
G01Y234646D02*
Y235433D01*
G01Y228347D02*
Y229134D01*
G01Y222048D02*
Y222835D01*
G01Y225197D02*
Y225985D01*
G01Y218898D02*
Y219685D01*
G01Y212599D02*
Y213386D01*
G01Y215748D02*
Y216536D01*
G01Y209449D02*
Y210237D01*
G01Y206300D02*
Y207087D01*
G01X-308913Y245781D02*
Y246345D01*
G01Y242631D02*
Y243196D01*
G01Y236332D02*
Y236896D01*
G01Y239482D02*
Y240046D01*
G01Y233183D02*
Y233747D01*
G01Y226883D02*
Y227448D01*
G01Y230033D02*
Y230597D01*
G01Y223734D02*
Y224298D01*
G01Y217435D02*
Y217999D01*
G01Y220584D02*
Y221148D01*
G01Y214285D02*
Y214849D01*
G01Y207986D02*
Y208550D01*
G01Y211135D02*
Y211700D01*
G01Y204836D02*
Y205400D01*
G01X-308969Y245670D02*
Y246457D01*
G01Y242520D02*
Y243307D01*
G01Y236221D02*
Y237008D01*
G01Y239370D02*
Y240158D01*
G01Y233071D02*
Y233859D01*
G01Y226772D02*
Y227559D01*
G01Y229922D02*
Y230709D01*
G01Y223622D02*
Y224410D01*
G01Y217323D02*
Y218111D01*
G01Y220473D02*
Y221260D01*
G01Y214174D02*
Y214961D01*
G01Y207874D02*
Y208662D01*
G01Y211024D02*
Y211811D01*
G01Y204725D02*
Y205512D01*
G01X-309003D02*
Y204725D01*
G01Y208662D02*
Y207874D01*
G01Y211811D02*
Y211024D01*
G01Y214961D02*
Y214174D01*
G01Y218111D02*
Y217323D01*
G01Y221260D02*
Y220473D01*
G01Y224410D02*
Y223622D01*
G01Y227559D02*
Y226772D01*
G01Y230709D02*
Y229922D01*
G01Y233859D02*
Y233071D01*
G01Y237008D02*
Y236221D01*
G01Y240158D02*
Y239370D01*
G01Y243307D02*
Y242520D01*
G01Y246457D02*
Y245670D01*
G01X-309016Y205503D02*
Y204734D01*
G01Y208653D02*
Y207883D01*
G01Y211802D02*
Y211033D01*
G01Y214952D02*
Y214183D01*
G01Y218102D02*
Y217332D01*
G01Y221251D02*
Y220482D01*
G01Y224401D02*
Y223631D01*
G01Y227550D02*
Y226781D01*
G01Y230700D02*
Y229931D01*
G01Y233850D02*
Y233080D01*
G01Y236999D02*
Y236230D01*
G01Y240149D02*
Y239379D01*
G01Y243298D02*
Y242529D01*
G01Y246448D02*
Y245679D01*
G01X-309055Y205512D02*
Y204725D01*
G01Y208662D02*
Y207874D01*
G01Y211811D02*
Y211024D01*
G01Y214961D02*
Y214174D01*
G01Y218111D02*
Y217323D01*
G01Y221260D02*
Y220473D01*
G01Y224410D02*
Y223622D01*
G01Y227559D02*
Y226772D01*
G01Y230709D02*
Y229922D01*
G01Y233859D02*
Y233071D01*
G01Y237008D02*
Y236221D01*
G01Y240158D02*
Y239370D01*
G01Y243307D02*
Y242520D01*
G01Y246457D02*
Y245670D01*
G01X-309076D02*
Y246457D01*
G01Y242520D02*
Y243307D01*
G01Y236221D02*
Y237008D01*
G01Y239370D02*
Y240158D01*
G01Y233071D02*
Y233859D01*
G01Y226772D02*
Y227559D01*
G01Y229922D02*
Y230709D01*
G01Y223622D02*
Y224410D01*
G01Y217323D02*
Y218111D01*
G01Y220473D02*
Y221260D01*
G01Y214174D02*
Y214961D01*
G01Y207874D02*
Y208662D01*
G01Y211024D02*
Y211811D01*
G01Y204725D02*
Y205512D01*
G01X-309114Y205611D02*
Y204626D01*
G01Y208760D02*
Y207776D01*
G01Y211910D02*
Y210926D01*
G01Y215059D02*
Y214075D01*
G01Y218209D02*
Y217225D01*
G01Y221359D02*
Y220374D01*
G01Y224508D02*
Y223524D01*
G01Y227658D02*
Y226674D01*
G01Y230807D02*
Y229823D01*
G01Y233957D02*
Y232973D01*
G01Y237107D02*
Y236122D01*
G01Y240256D02*
Y239272D01*
G01Y243406D02*
Y242422D01*
G01Y246555D02*
Y245571D01*
G01X-309370Y245670D02*
Y246457D01*
G01Y242520D02*
Y243307D01*
G01Y236221D02*
Y237008D01*
G01Y239370D02*
Y240158D01*
G01Y233071D02*
Y233859D01*
G01Y226772D02*
Y227559D01*
G01Y229922D02*
Y230709D01*
G01Y223622D02*
Y224410D01*
G01Y217323D02*
Y218111D01*
G01Y220473D02*
Y221260D01*
G01Y214174D02*
Y214961D01*
G01Y207874D02*
Y208662D01*
G01Y211024D02*
Y211811D01*
G01Y204725D02*
Y205512D01*
G01X-309429Y245571D02*
Y246555D01*
G01Y242422D02*
Y243406D01*
G01Y236122D02*
Y237107D01*
G01Y239272D02*
Y240256D01*
G01Y232973D02*
Y233957D01*
G01Y226674D02*
Y227658D01*
G01Y229823D02*
Y230807D01*
G01Y223524D02*
Y224508D01*
G01Y217225D02*
Y218209D01*
G01Y220374D02*
Y221359D01*
G01Y214075D02*
Y215059D01*
G01Y207776D02*
Y208760D01*
G01Y210926D02*
Y211910D01*
G01Y204626D02*
Y205611D01*
G01X-309449Y205512D02*
Y204725D01*
G01Y207244D02*
Y206142D01*
G01Y208662D02*
Y207874D01*
G01Y211811D02*
Y211024D01*
G01Y210394D02*
Y209292D01*
G01Y214961D02*
Y214174D01*
G01Y213544D02*
Y212441D01*
G01Y216693D02*
Y215591D01*
G01Y218111D02*
Y217323D01*
G01Y221260D02*
Y220473D01*
G01Y219843D02*
Y218740D01*
G01Y224410D02*
Y223622D01*
G01Y222992D02*
Y221890D01*
G01Y226142D02*
Y225040D01*
G01Y227559D02*
Y226772D01*
G01Y230709D02*
Y229922D01*
G01Y229292D02*
Y228189D01*
G01Y233859D02*
Y233071D01*
G01Y232441D02*
Y231339D01*
G01Y235591D02*
Y234489D01*
G01Y237008D02*
Y236221D01*
G01Y240158D02*
Y239370D01*
G01Y238740D02*
Y237638D01*
G01Y243307D02*
Y242520D01*
G01Y241890D02*
Y240788D01*
G01Y245040D02*
Y243937D01*
G01Y246457D02*
Y245670D01*
G01Y252756D02*
Y247087D01*
G01X-309685Y245670D02*
Y246457D01*
G01Y242520D02*
Y243307D01*
G01Y236221D02*
Y237008D01*
G01Y239370D02*
Y240158D01*
G01Y233071D02*
Y233859D01*
G01Y226772D02*
Y227559D01*
G01Y229922D02*
Y230709D01*
G01Y223622D02*
Y224410D01*
G01Y217323D02*
Y218111D01*
G01Y220473D02*
Y221260D01*
G01Y214174D02*
Y214961D01*
G01Y207874D02*
Y208662D01*
G01Y211024D02*
Y211811D01*
G01Y204725D02*
Y205512D01*
G01X-309722Y207087D02*
Y206300D01*
G01Y210237D02*
Y209449D01*
G01Y213386D02*
Y212599D01*
G01Y216536D02*
Y215748D01*
G01Y219685D02*
Y218898D01*
G01Y222835D02*
Y222048D01*
G01Y225985D02*
Y225197D01*
G01Y229134D02*
Y228347D01*
G01Y232284D02*
Y231496D01*
G01Y235433D02*
Y234646D01*
G01Y238583D02*
Y237796D01*
G01Y241733D02*
Y240945D01*
G01Y244882D02*
Y244095D01*
G01X-309862Y205512D02*
Y204725D01*
G01Y208662D02*
Y207874D01*
G01Y211811D02*
Y211024D01*
G01Y214961D02*
Y214174D01*
G01Y218111D02*
Y217323D01*
G01Y221260D02*
Y220473D01*
G01Y224410D02*
Y223622D01*
G01Y227559D02*
Y226772D01*
G01Y230709D02*
Y229922D01*
G01Y233859D02*
Y233071D01*
G01Y237008D02*
Y236221D01*
G01Y240158D02*
Y239370D01*
G01Y243307D02*
Y242520D01*
G01Y246457D02*
Y245670D01*
G01X-309960Y240945D02*
Y241733D01*
G01Y244095D02*
Y244882D01*
G01Y237796D02*
Y238583D01*
G01Y231496D02*
Y232284D01*
G01Y234646D02*
Y235433D01*
G01Y228347D02*
Y229134D01*
G01Y222048D02*
Y222835D01*
G01Y225197D02*
Y225985D01*
G01Y218898D02*
Y219685D01*
G01Y212599D02*
Y213386D01*
G01Y215748D02*
Y216536D01*
G01Y209449D02*
Y210237D01*
G01Y206300D02*
Y207087D01*
G01X-310000Y240945D02*
Y241733D01*
G01Y244095D02*
Y244882D01*
G01Y237796D02*
Y238583D01*
G01Y231496D02*
Y232284D01*
G01Y234646D02*
Y235433D01*
G01Y228347D02*
Y229134D01*
G01Y222048D02*
Y222835D01*
G01Y225197D02*
Y225985D01*
G01Y218898D02*
Y219685D01*
G01Y212599D02*
Y213386D01*
G01Y215748D02*
Y216536D01*
G01Y209449D02*
Y210237D01*
G01Y206300D02*
Y207087D01*
G01X-310040Y205512D02*
Y204725D01*
G01Y208662D02*
Y207874D01*
G01Y211811D02*
Y211024D01*
G01Y214961D02*
Y214174D01*
G01Y218111D02*
Y217323D01*
G01Y221260D02*
Y220473D01*
G01Y224410D02*
Y223622D01*
G01Y227559D02*
Y226772D01*
G01Y230709D02*
Y229922D01*
G01Y233859D02*
Y233071D01*
G01Y237008D02*
Y236221D01*
G01Y240158D02*
Y239370D01*
G01Y243307D02*
Y242520D01*
G01Y246457D02*
Y245670D01*
G01X-310276D02*
Y246457D01*
G01Y242520D02*
Y243307D01*
G01Y236221D02*
Y237008D01*
G01Y239370D02*
Y240158D01*
G01Y233071D02*
Y233859D01*
G01Y226772D02*
Y227559D01*
G01Y229922D02*
Y230709D01*
G01Y223622D02*
Y224410D01*
G01Y217323D02*
Y218111D01*
G01Y220473D02*
Y221260D01*
G01Y214174D02*
Y214961D01*
G01Y207874D02*
Y208662D01*
G01Y211024D02*
Y211811D01*
G01Y204725D02*
Y205512D01*
G01X-311378Y245670D02*
Y246457D01*
G01Y242520D02*
Y243307D01*
G01Y236221D02*
Y237008D01*
G01Y239370D02*
Y240158D01*
G01Y233071D02*
Y233859D01*
G01Y226772D02*
Y227559D01*
G01Y229922D02*
Y230709D01*
G01Y223622D02*
Y224410D01*
G01Y217323D02*
Y218111D01*
G01Y220473D02*
Y221260D01*
G01Y214174D02*
Y214961D01*
G01Y207874D02*
Y208662D01*
G01Y211024D02*
Y211811D01*
G01Y204725D02*
Y205512D01*
G01X-311418Y207481D02*
Y205906D01*
G01Y205512D02*
Y204725D01*
G01Y210630D02*
Y209055D01*
G01Y208662D02*
Y207874D01*
G01Y211811D02*
Y211024D01*
G01Y216929D02*
Y215355D01*
G01Y213780D02*
Y212205D01*
G01Y214961D02*
Y214174D01*
G01Y220079D02*
Y218504D01*
G01Y218111D02*
Y217323D01*
G01Y221260D02*
Y220473D01*
G01Y226378D02*
Y224803D01*
G01Y223229D02*
Y221654D01*
G01Y224410D02*
Y223622D01*
G01Y229528D02*
Y227953D01*
G01Y227559D02*
Y226772D01*
G01Y230709D02*
Y229922D01*
G01Y235827D02*
Y234252D01*
G01Y232677D02*
Y231103D01*
G01Y233859D02*
Y233071D01*
G01Y238977D02*
Y237402D01*
G01Y237008D02*
Y236221D01*
G01Y240158D02*
Y239370D01*
G01Y245276D02*
Y243701D01*
G01Y242126D02*
Y240552D01*
G01Y243307D02*
Y242520D01*
G01Y246457D02*
Y245670D01*
G01X-311792Y205512D02*
Y204725D01*
G01Y208662D02*
Y207874D01*
G01Y211811D02*
Y211024D01*
G01Y214961D02*
Y214174D01*
G01Y218111D02*
Y217323D01*
G01Y221260D02*
Y220473D01*
G01Y224410D02*
Y223622D01*
G01Y227559D02*
Y226772D01*
G01Y230709D02*
Y229922D01*
G01Y233859D02*
Y233071D01*
G01Y237008D02*
Y236221D01*
G01Y240158D02*
Y239370D01*
G01Y243307D02*
Y242520D01*
G01Y246457D02*
Y245670D01*
G01X-311890Y207087D02*
Y206300D01*
G01Y210237D02*
Y209449D01*
G01Y213386D02*
Y212599D01*
G01Y216536D02*
Y215748D01*
G01Y219685D02*
Y218898D01*
G01Y222835D02*
Y222048D01*
G01Y225985D02*
Y225197D01*
G01Y229134D02*
Y228347D01*
G01Y232284D02*
Y231496D01*
G01Y235433D02*
Y234646D01*
G01Y238583D02*
Y237796D01*
G01Y241733D02*
Y240945D01*
G01Y244882D02*
Y244095D01*
G01X-311969Y245670D02*
Y246457D01*
G01Y242520D02*
Y243307D01*
G01Y236221D02*
Y237008D01*
G01Y239370D02*
Y240158D01*
G01Y233071D02*
Y233859D01*
G01Y226772D02*
Y227559D01*
G01Y229922D02*
Y230709D01*
G01Y223622D02*
Y224410D01*
G01Y217323D02*
Y218111D01*
G01Y220473D02*
Y221260D01*
G01Y214174D02*
Y214961D01*
G01Y207874D02*
Y208662D01*
G01Y211024D02*
Y211811D01*
G01Y204725D02*
Y205512D01*
G01X-312008Y240945D02*
Y241733D01*
G01Y244095D02*
Y244882D01*
G01Y237796D02*
Y238583D01*
G01Y231496D02*
Y232284D01*
G01Y234646D02*
Y235433D01*
G01Y228347D02*
Y229134D01*
G01Y222048D02*
Y222835D01*
G01Y225197D02*
Y225985D01*
G01Y218898D02*
Y219685D01*
G01Y212599D02*
Y213386D01*
G01Y215748D02*
Y216536D01*
G01Y209449D02*
Y210237D01*
G01Y206300D02*
Y207087D01*
G01X-312205Y205512D02*
Y204725D01*
G01Y208662D02*
Y207874D01*
G01Y211811D02*
Y211024D01*
G01Y214961D02*
Y214174D01*
G01Y218111D02*
Y217323D01*
G01Y221260D02*
Y220473D01*
G01Y224410D02*
Y223622D01*
G01Y227559D02*
Y226772D01*
G01Y230709D02*
Y229922D01*
G01Y233859D02*
Y233071D01*
G01Y237008D02*
Y236221D01*
G01Y240158D02*
Y239370D01*
G01Y243307D02*
Y242520D01*
G01Y246457D02*
Y245670D01*
G01X-312284Y205611D02*
Y204626D01*
G01Y208760D02*
Y207776D01*
G01Y211910D02*
Y210926D01*
G01Y215059D02*
Y214075D01*
G01Y218209D02*
Y217225D01*
G01Y221359D02*
Y220374D01*
G01Y224508D02*
Y223524D01*
G01Y227658D02*
Y226674D01*
G01Y230807D02*
Y229823D01*
G01Y233957D02*
Y232973D01*
G01Y237107D02*
Y236122D01*
G01Y240256D02*
Y239272D01*
G01Y243406D02*
Y242422D01*
G01Y246555D02*
Y245571D01*
G01X-312796Y207087D02*
Y206300D01*
G01Y210237D02*
Y209449D01*
G01Y213386D02*
Y212599D01*
G01Y216536D02*
Y215748D01*
G01Y219685D02*
Y218898D01*
G01Y222835D02*
Y222048D01*
G01Y225985D02*
Y225197D01*
G01Y229134D02*
Y228347D01*
G01Y232284D02*
Y231496D01*
G01Y235433D02*
Y234646D01*
G01Y238583D02*
Y237796D01*
G01Y241733D02*
Y240945D01*
G01Y244882D02*
Y244095D01*
G01X-312815Y209292D02*
Y207244D01*
G01Y212441D02*
Y210394D01*
G01Y215591D02*
Y213544D01*
G01Y218740D02*
Y216693D01*
G01Y221890D02*
Y219843D01*
G01Y225040D02*
Y222992D01*
G01Y228189D02*
Y226142D01*
G01Y231339D02*
Y229292D01*
G01Y234489D02*
Y232441D01*
G01Y237638D02*
Y235591D01*
G01Y240788D02*
Y238740D01*
G01Y243937D02*
Y241890D01*
G01Y247087D02*
Y245040D01*
G01X-312992Y243996D02*
Y244981D01*
G01Y207185D02*
Y206201D01*
G01Y210335D02*
Y209351D01*
G01Y213485D02*
Y212500D01*
G01Y216634D02*
Y215650D01*
G01Y219784D02*
Y218800D01*
G01Y222933D02*
Y221949D01*
G01Y226083D02*
Y225099D01*
G01Y229233D02*
Y228248D01*
G01Y232382D02*
Y231398D01*
G01Y235532D02*
Y234548D01*
G01Y238681D02*
Y237697D01*
G01Y241831D02*
Y240847D01*
G01X-313110Y205512D02*
Y204725D01*
G01Y208662D02*
Y207874D01*
G01Y211811D02*
Y211024D01*
G01Y214961D02*
Y214174D01*
G01Y218111D02*
Y217323D01*
G01Y221260D02*
Y220473D01*
G01Y224410D02*
Y223622D01*
G01Y227559D02*
Y226772D01*
G01Y230709D02*
Y229922D01*
G01Y233859D02*
Y233071D01*
G01Y237008D02*
Y236221D01*
G01Y240158D02*
Y239370D01*
G01Y243307D02*
Y242520D01*
G01Y246457D02*
Y245670D01*
G01X-313701Y205512D02*
Y204725D01*
G01Y208662D02*
Y207874D01*
G01Y211811D02*
Y211024D01*
G01Y214961D02*
Y214174D01*
G01Y218111D02*
Y217323D01*
G01Y221260D02*
Y220473D01*
G01Y224410D02*
Y223622D01*
G01Y227559D02*
Y226772D01*
G01Y230709D02*
Y229922D01*
G01Y233859D02*
Y233071D01*
G01Y237008D02*
Y236221D01*
G01Y240158D02*
Y239370D01*
G01Y243307D02*
Y242520D01*
G01Y246457D02*
Y245670D01*
G01X-313977Y207087D02*
Y206300D01*
G01Y210237D02*
Y209449D01*
G01Y213386D02*
Y212599D01*
G01Y216536D02*
Y215748D01*
G01Y219685D02*
Y218898D01*
G01Y222835D02*
Y222048D01*
G01Y225985D02*
Y225197D01*
G01Y229134D02*
Y228347D01*
G01Y232284D02*
Y231496D01*
G01Y235433D02*
Y234646D01*
G01Y238583D02*
Y237796D01*
G01Y241733D02*
Y240945D01*
G01Y244882D02*
Y244095D01*
G01X-285698Y246457D02*
X-285697Y245670D01*
G01X-285698Y243307D02*
X-285697Y242520D01*
G01X-285698Y240158D02*
X-285697Y239370D01*
G01X-285698Y237008D02*
X-285697Y236221D01*
G01X-285698Y233859D02*
X-285697Y233071D01*
G01X-285698Y230709D02*
X-285697Y229922D01*
G01X-285698Y227559D02*
X-285697Y226772D01*
G01X-285698Y224410D02*
X-285697Y223622D01*
G01X-285698Y221260D02*
X-285697Y220473D01*
G01X-285698Y218111D02*
X-285697Y217323D01*
G01X-285698Y214961D02*
X-285697Y214174D01*
G01X-285698Y211811D02*
X-285697Y211024D01*
G01X-285698Y208662D02*
X-285697Y207874D01*
G01X-285698Y205512D02*
X-285697Y204725D01*
G01X-309449Y245040D02*
X-309669Y245571D01*
G01X-309449Y241890D02*
X-309669Y242422D01*
G01X-309449Y238740D02*
X-309669Y239272D01*
G01X-309449Y235591D02*
X-309669Y236122D01*
G01X-309449Y232441D02*
X-309669Y232973D01*
G01X-309449Y229292D02*
X-309669Y229823D01*
G01X-309449Y226142D02*
X-309669Y226674D01*
G01X-276772Y277953D02*
X-274803Y274410D01*
G01X-286064Y244882D02*
X-285329Y244685D01*
G01X-286064Y241733D02*
X-285329Y241536D01*
G01X-286064Y238583D02*
X-285329Y238386D01*
G01X-286064Y235433D02*
X-285329Y235237D01*
G01X-286064Y232284D02*
X-285329Y232087D01*
G01X-291438Y244737D02*
X-291414Y244732D01*
G01X-291438Y241588D02*
X-291414Y241583D01*
G01X-291438Y238438D02*
X-291414Y238433D01*
G01X-291438Y235289D02*
X-291414Y235283D01*
G01X-291438Y232139D02*
X-291414Y232134D01*
G01X-291438Y228989D02*
X-291414Y228984D01*
G01X-291438Y225840D02*
X-291414Y225835D01*
G01X-291879Y246352D02*
X-292395Y246457D01*
G01X-291879Y243202D02*
X-292395Y243307D01*
G01X-291879Y240052D02*
X-292395Y240158D01*
G01X-291879Y236903D02*
X-292395Y237008D01*
G01X-291879Y233753D02*
X-292395Y233859D01*
G01X-291879Y230603D02*
X-292395Y230709D01*
G01X-291879Y227454D02*
X-292395Y227559D01*
G01X-296841Y251793D02*
X-301815Y252756D01*
G01X-297028Y250827D02*
X-301910Y251772D01*
G01X-290085Y245784D02*
X-289491Y245670D01*
G01X-290085Y242635D02*
X-289491Y242520D01*
G01X-290085Y239485D02*
X-289491Y239370D01*
G01X-290085Y236335D02*
X-289491Y236221D01*
G01X-290085Y233186D02*
X-289491Y233071D01*
G01X-290085Y230036D02*
X-289491Y229922D01*
G01X-290085Y226887D02*
X-289491Y226772D01*
G01X-290085Y223737D02*
X-289491Y223622D01*
G01X-289641Y244095D02*
X-290539Y244256D01*
G01X-289641Y240945D02*
X-290539Y241106D01*
G01X-289641Y237796D02*
X-290539Y237957D01*
G01X-289641Y234646D02*
X-290539Y234807D01*
G01X-289641Y231496D02*
X-290539Y231657D01*
G01X-289641Y228347D02*
X-290539Y228508D01*
G01X-289641Y225197D02*
X-290539Y225358D01*
G01X-289641Y222048D02*
X-290539Y222209D01*
G01X-292794Y244882D02*
X-291637Y244768D01*
G01X-292794Y241733D02*
X-291637Y241618D01*
G01X-292794Y238583D02*
X-291637Y238468D01*
G01X-292794Y235433D02*
X-291637Y235319D01*
G01X-292794Y232284D02*
X-291637Y232169D01*
G01X-292794Y229134D02*
X-291637Y229020D01*
G01X-292794Y225985D02*
X-291637Y225870D01*
G01X-292794Y222835D02*
X-291637Y222720D01*
G01X-292794Y219685D02*
X-291637Y219571D01*
G01X-292794Y216536D02*
X-291637Y216421D01*
G01X-292794Y213386D02*
X-291637Y213272D01*
G01X-240158Y262402D02*
X-282677D01*
G01X-236260Y255906D02*
X-326811D01*
G01X-275610Y254036D02*
X-238996D01*
G01X-275610Y253052D02*
X-275688D01*
G01X-238996D02*
X-275610D01*
G01X-324803Y252756D02*
X-279528D01*
G01X-303603Y251772D02*
X-303504D01*
G01D02*
X-279528D01*
G01X-238996Y251575D02*
X-275610D01*
G01X-280512Y250788D02*
X-280217D01*
G01X-288977D02*
X-280512D01*
G01X-313386D02*
X-296418D01*
G01X-320079Y249607D02*
X-314961D01*
G01X-320473D02*
X-324803D01*
G01X-282225D02*
X-303622D01*
G01X-291916Y248288D02*
X-289974D01*
G01X-281398Y248032D02*
X-287697D01*
G01X-295276Y247500D02*
X-279528D01*
G01X-283721Y247087D02*
X-312815D01*
G01X-279528Y246851D02*
X-282284D01*
G01X-293898Y246555D02*
X-312284D01*
G01X-284252D02*
X-287992D01*
G01X-313701Y246457D02*
X-285546D01*
G01X-308657Y246260D02*
X-306500D01*
G01Y245866D02*
X-308657D01*
G01X-313701Y245670D02*
X-285546D01*
G01X-287992Y245571D02*
X-284252D01*
G01X-312284D02*
X-293898D01*
G01X-311418Y245276D02*
X-313386D01*
G01X-279528D02*
X-282284D01*
G01X-279528Y245118D02*
X-313130D01*
G01X-312815Y245040D02*
X-283721D01*
G01X-319016Y245000D02*
X-320670D01*
G01X-303622Y244981D02*
X-312992D01*
G01X-286064Y244882D02*
X-323347D01*
G01Y244095D02*
X-286064D01*
G01X-303622Y243996D02*
X-312992D01*
G01X-320670Y243977D02*
X-319016D01*
G01X-283721Y243937D02*
X-312815D01*
G01X-279528Y243859D02*
X-313130D01*
G01X-313386Y243701D02*
X-311418D01*
G01X-279528D02*
X-282284D01*
G01X-293898Y243406D02*
X-312284D01*
G01X-284252D02*
X-287992D01*
G01X-313701Y243307D02*
X-285546D01*
G01X-308657Y243111D02*
X-306500D01*
G01Y242717D02*
X-308657D01*
G01X-313701Y242520D02*
X-285546D01*
G01X-287992Y242422D02*
X-284252D01*
G01X-312284D02*
X-293898D01*
G01X-311418Y242126D02*
X-313386D01*
G01X-279528D02*
X-282284D01*
G01X-279528Y241969D02*
X-313130D01*
G01X-312815Y241890D02*
X-283721D01*
G01X-319016Y241851D02*
X-320670D01*
G01X-303622Y241831D02*
X-312992D01*
G01X-286064Y241733D02*
X-323347D01*
G01Y240945D02*
X-286064D01*
G01X-303622Y240847D02*
X-312992D01*
G01X-320670Y240827D02*
X-319016D01*
G01X-283721Y240788D02*
X-312815D01*
G01X-313130Y240709D02*
X-279528D01*
G01X-313386Y240552D02*
X-311418D01*
G01X-279528D02*
X-282284D01*
G01X-293898Y240256D02*
X-312284D01*
G01X-284252D02*
X-287992D01*
G01X-313701Y240158D02*
X-285546D01*
G01X-308657Y239961D02*
X-306500D01*
G01Y239567D02*
X-308657D01*
G01X-313701Y239370D02*
X-285546D01*
G01X-270689D02*
X-275610D01*
G01X-287992Y239272D02*
X-284252D01*
G01X-312284D02*
X-293898D01*
G01X-311418Y238977D02*
X-313386D01*
G01X-279528D02*
X-282284D01*
G01X-279528Y238819D02*
X-313130D01*
G01X-312815Y238740D02*
X-283721D01*
G01X-319016Y238701D02*
X-320670D01*
G01X-303622Y238681D02*
X-312992D01*
G01X-286064Y238583D02*
X-323347D01*
G01Y237796D02*
X-286064D01*
G01X-303622Y237697D02*
X-312992D01*
G01X-320670Y237677D02*
X-319016D01*
G01X-283721Y237638D02*
X-312815D01*
G01X-313130Y237559D02*
X-279528D01*
G01X-296720Y237402D02*
X-282284D01*
G01X-313386D02*
X-311418D01*
G01X-270689D02*
X-279528D01*
G01D02*
X-282284D01*
G01X-293898Y237107D02*
X-312284D01*
G01X-284252D02*
X-287992D01*
G01X-313701Y237008D02*
X-285546D01*
G01X-308657Y236811D02*
X-306500D01*
G01Y236418D02*
X-308657D01*
G01X-313701Y236221D02*
X-285546D01*
G01X-287992Y236122D02*
X-284252D01*
G01X-312284D02*
X-293898D01*
G01X-311418Y235827D02*
X-313386D01*
G01X-279528D02*
X-282284D01*
G01X-279528Y235670D02*
X-313130D01*
G01X-312815Y235591D02*
X-283721D01*
G01X-319016Y235552D02*
X-320670D01*
G01X-303622Y235532D02*
X-312992D01*
G01X-286064Y235433D02*
X-323347D01*
G01Y234646D02*
X-286064D01*
G01X-303622Y234548D02*
X-312992D01*
G01X-320670Y234528D02*
X-319016D01*
G01X-283721Y234489D02*
X-312815D01*
G01X-313130Y234410D02*
X-279528D01*
G01X-313386Y234252D02*
X-311418D01*
G01X-279528D02*
X-282284D01*
G01X-293898Y233957D02*
X-312284D01*
G01X-284252D02*
X-287992D01*
G01X-313701Y233859D02*
X-285546D01*
G01X-308657Y233662D02*
X-306500D01*
G01Y233268D02*
X-308657D01*
G01X-313701Y233071D02*
X-285546D01*
G01X-287992Y232973D02*
X-284252D01*
G01X-312284D02*
X-293898D01*
G01X-311418Y232677D02*
X-313386D01*
G01X-279528D02*
X-282284D01*
G01X-279528Y232520D02*
X-313130D01*
G01X-312815Y232441D02*
X-283721D01*
G01X-319016Y232402D02*
X-320670D01*
G01X-303622Y232382D02*
X-312992D01*
G01X-286064Y232284D02*
X-323347D01*
G01Y231496D02*
X-286064D01*
G01X-303622Y231398D02*
X-312992D01*
G01X-320670Y231378D02*
X-319016D01*
G01X-283721Y231339D02*
X-312815D01*
G01X-313130Y231260D02*
X-279528D01*
G01X-313386Y231103D02*
X-311418D01*
G01X-279528D02*
X-282284D01*
G01X-293898Y230807D02*
X-312284D01*
G01X-284252D02*
X-287992D01*
G01X-313701Y230709D02*
X-285546D01*
G01X-308657Y230512D02*
X-306500D01*
G01Y230118D02*
X-308657D01*
G01X-313701Y229922D02*
X-285546D01*
G01X-287992Y229823D02*
X-284252D01*
G01X-312284D02*
X-293898D01*
G01X-311418Y229528D02*
X-313386D01*
G01X-279528D02*
X-282284D01*
G01X-279528Y229370D02*
X-313130D01*
G01X-312815Y229292D02*
X-283721D01*
G01X-319016Y229252D02*
X-320670D01*
G01X-303622Y229233D02*
X-312992D01*
G01X-286064Y229134D02*
X-323347D01*
G01Y228347D02*
X-286064D01*
G01X-303622Y228248D02*
X-312992D01*
G01X-320670Y228229D02*
X-319016D01*
G01X-283721Y228189D02*
X-312815D01*
G01X-313130Y228111D02*
X-279528D01*
G01X-313386Y227953D02*
X-311418D01*
G01X-279528D02*
X-282284D01*
G01X-293898Y227658D02*
X-312284D01*
G01X-284252D02*
X-287992D01*
G01X-313701Y227559D02*
X-285546D01*
G01X-308657Y227363D02*
X-306500D01*
G01Y226969D02*
X-308657D01*
G01X-313701Y226772D02*
X-285546D01*
G01X-287992Y226674D02*
X-284252D01*
G01X-312284D02*
X-293898D01*
G01X-311418Y226378D02*
X-313386D01*
G01X-279528D02*
X-282284D01*
G01X-279528Y226221D02*
X-313130D01*
G01X-312815Y226142D02*
X-283721D01*
G01X-319016Y226103D02*
X-320670D01*
G01X-303622Y226083D02*
X-312992D01*
G01X-286064Y225985D02*
X-323347D01*
G01Y225197D02*
X-286064D01*
G01X-303622Y225099D02*
X-312992D01*
G01X-320670Y225079D02*
X-319016D01*
G01X-283721Y225040D02*
X-312815D01*
G01X-313130Y224961D02*
X-279528D01*
G01X-313386Y224803D02*
X-311418D01*
G01X-279528D02*
X-282284D01*
G01X-293898Y224508D02*
X-312284D01*
G01X-284252D02*
X-287992D01*
G01X-313701Y224410D02*
X-285546D01*
G01X-308657Y224213D02*
X-306500D01*
G01Y223819D02*
X-308657D01*
G01X-313701Y223622D02*
X-285546D01*
G01X-287992Y223524D02*
X-284252D01*
G01X-312284D02*
X-293898D01*
G01X-311418Y223229D02*
X-313386D01*
G01X-279528D02*
X-282284D01*
G01X-279528Y223071D02*
X-313130D01*
G01X-312815Y222992D02*
X-283721D01*
G01X-319016Y222953D02*
X-320670D01*
G01X-303622Y222933D02*
X-312992D01*
G01X-286064Y222835D02*
X-323347D01*
G01Y222048D02*
X-286064D01*
G01X-303622Y221949D02*
X-312992D01*
G01X-320670Y221929D02*
X-319016D01*
G01X-283721Y221890D02*
X-312815D01*
G01X-313130Y221811D02*
X-279528D01*
G01X-313386Y221654D02*
X-311418D01*
G01X-279528D02*
X-282284D01*
G01X-293898Y221359D02*
X-312284D01*
G01X-284252D02*
X-287992D01*
G01X-313701Y221260D02*
X-285546D01*
G01X-308657Y221063D02*
X-306500D01*
G01Y220670D02*
X-308657D01*
G01X-313701Y220473D02*
X-285546D01*
G01X-287992Y220374D02*
X-284252D01*
G01X-312284D02*
X-293898D01*
G01X-311418Y220079D02*
X-313386D01*
G01X-279528D02*
X-282284D01*
G01X-279528Y219922D02*
X-313130D01*
G01X-312815Y219843D02*
X-283721D01*
G01X-319016Y219803D02*
X-320670D01*
G01X-303622Y219784D02*
X-312992D01*
G01X-286064Y219685D02*
X-323347D01*
G01Y218898D02*
X-286064D01*
G01X-303622Y218800D02*
X-312992D01*
G01X-320670Y218780D02*
X-319016D01*
G01X-283721Y218740D02*
X-312815D01*
G01X-313130Y218662D02*
X-279528D01*
G01X-313386Y218504D02*
X-311418D01*
G01X-279528D02*
X-282284D01*
G01X-293898Y218209D02*
X-312284D01*
G01X-284252D02*
X-287992D01*
G01X-313701Y218111D02*
X-285546D01*
G01X-308657Y217914D02*
X-306500D01*
G01Y217520D02*
X-308657D01*
G01X-313701Y217323D02*
X-285546D01*
G01X-287992Y217225D02*
X-284252D01*
G01X-312284D02*
X-293898D01*
G01X-311418Y216929D02*
X-313386D01*
G01X-279528D02*
X-282284D01*
G01X-279528Y216772D02*
X-313130D01*
G01X-312815Y216693D02*
X-283721D01*
G01X-319016Y216654D02*
X-320670D01*
G01X-303622Y216634D02*
X-312992D01*
G01X-286064Y216536D02*
X-323347D01*
G01Y215748D02*
X-286064D01*
G01X-303622Y215650D02*
X-312992D01*
G01X-320670Y215630D02*
X-319016D01*
G01X-283721Y215591D02*
X-312815D01*
G01X-313130Y215512D02*
X-279528D01*
G01X-313386Y215355D02*
X-311418D01*
G01X-279528D02*
X-282284D01*
G01X-293898Y215059D02*
X-312284D01*
G01X-284252D02*
X-287992D01*
G01X-313701Y214961D02*
X-285546D01*
G01X-308657Y214764D02*
X-306500D01*
G01Y214370D02*
X-308657D01*
G01X-313701Y214174D02*
X-285546D01*
G01X-287992Y214075D02*
X-284252D01*
G01X-312284D02*
X-293898D01*
G01X-311418Y213780D02*
X-313386D01*
G01X-279528D02*
X-282284D01*
G01X-279528Y213622D02*
X-313130D01*
G01X-312815Y213544D02*
X-283721D01*
G01X-319016Y213504D02*
X-320670D01*
G01X-303622Y213485D02*
X-312992D01*
G01X-286064Y213386D02*
X-323347D01*
G01Y212599D02*
X-286064D01*
G01X-303622Y212500D02*
X-312992D01*
G01X-320670Y212481D02*
X-319016D01*
G01X-283721Y212441D02*
X-312815D01*
G01X-313130Y212363D02*
X-279528D01*
G01X-313386Y212205D02*
X-311418D01*
G01X-279528D02*
X-282284D01*
G01X-293898Y211910D02*
X-312284D01*
G01X-284252D02*
X-287992D01*
G01X-313701Y211811D02*
X-285546D01*
G01X-308657Y211615D02*
X-306500D01*
G01Y211221D02*
X-308657D01*
G01X-313701Y211024D02*
X-285546D01*
G01X-287992Y210926D02*
X-284252D01*
G01X-312284D02*
X-293898D01*
G01X-311418Y210630D02*
X-313386D01*
G01X-279528D02*
X-282284D01*
G01X-279528Y210473D02*
X-313130D01*
G01X-312815Y210394D02*
X-283721D01*
G01X-319016Y210355D02*
X-320670D01*
G01X-303622Y210335D02*
X-312992D01*
G01X-286064Y210237D02*
X-323347D01*
G01Y209449D02*
X-286064D01*
G01X-303622Y209351D02*
X-312992D01*
G01X-320670Y209331D02*
X-319016D01*
G01X-283721Y209292D02*
X-312815D01*
G01X-313130Y209213D02*
X-279528D01*
G01X-313386Y209055D02*
X-311418D01*
G01X-279528D02*
X-282284D01*
G01X-293898Y208760D02*
X-312284D01*
G01X-284252D02*
X-287992D01*
G01X-313701Y208662D02*
X-285546D01*
G01X-308657Y208465D02*
X-306500D01*
G01Y208071D02*
X-308657D01*
G01X-313701Y207874D02*
X-285546D01*
G01X-287992Y207776D02*
X-284252D01*
G01X-312284D02*
X-293898D01*
G01X-311418Y207481D02*
X-313386D01*
G01X-279528D02*
X-282284D01*
G01X-279528Y207323D02*
X-313130D01*
G01X-312815Y207244D02*
X-283721D01*
G01X-319016Y207205D02*
X-320670D01*
G01X-303622Y207185D02*
X-312992D01*
G01X-286064Y207087D02*
X-323347D01*
G01Y206300D02*
X-286064D01*
G01X-303622Y206201D02*
X-312992D01*
G01X-320670Y206181D02*
X-319016D01*
G01X-283721Y206142D02*
X-312815D01*
G01X-313130Y206063D02*
X-279528D01*
G01X-313386Y205906D02*
X-311418D01*
G01X-279528D02*
X-282284D01*
G01X-293898Y205611D02*
X-312284D01*
G01X-284252D02*
X-287992D01*
G01X-313701Y205512D02*
X-285546D01*
G01X-308657Y205315D02*
X-306500D01*
G01Y204922D02*
X-308657D01*
G01X-313701Y204725D02*
X-285546D01*
G01X-287992Y204626D02*
X-284252D01*
G01X-312284D02*
X-293898D01*
G01X-311418Y204331D02*
X-313386D01*
G01X-279528D02*
X-282284D01*
G01X-291637Y244209D02*
X-292794Y244095D01*
G01X-291637Y241060D02*
X-292794Y240945D01*
G01X-291637Y237910D02*
X-292794Y237796D01*
G01X-291637Y234761D02*
X-292794Y234646D01*
G01X-291637Y231611D02*
X-292794Y231496D01*
G01X-291637Y228461D02*
X-292794Y228347D01*
G01X-291637Y225312D02*
X-292794Y225197D01*
G01X-291637Y222162D02*
X-292794Y222048D01*
G01X-291637Y219013D02*
X-292794Y218898D01*
G01X-291637Y215863D02*
X-292794Y215748D01*
G01X-291637Y212713D02*
X-292794Y212599D01*
G01X-291637Y209564D02*
X-292794Y209449D01*
G01X-291637Y206414D02*
X-292794Y206300D01*
G01X-290539Y228973D02*
X-289641Y229134D01*
G01X-290539Y225824D02*
X-289641Y225985D01*
G01X-290539Y222674D02*
X-289641Y222835D01*
G01X-290539Y219524D02*
X-289641Y219685D01*
G01X-290539Y216375D02*
X-289641Y216536D01*
G01X-290539Y213225D02*
X-289641Y213386D01*
G01X-290539Y210076D02*
X-289641Y210237D01*
G01X-290539Y206926D02*
X-289641Y207087D01*
G01X-289491Y224410D02*
X-290085Y224295D01*
G01X-289491Y221260D02*
X-290085Y221146D01*
G01X-289491Y218111D02*
X-290085Y217996D01*
G01X-289491Y214961D02*
X-290085Y214846D01*
G01X-289491Y211811D02*
X-290085Y211697D01*
G01X-289491Y208662D02*
X-290085Y208547D01*
G01X-289491Y205512D02*
X-290085Y205398D01*
G01X-291879Y223728D02*
X-292395Y223622D01*
G01X-291879Y220578D02*
X-292395Y220473D01*
G01X-291879Y217429D02*
X-292395Y217323D01*
G01X-291879Y214279D02*
X-292395Y214174D01*
G01X-291879Y211129D02*
X-292395Y211024D01*
G01X-291879Y207980D02*
X-292395Y207874D01*
G01X-291879Y204830D02*
X-292395Y204725D01*
G01X-291414Y222198D02*
X-291438Y222192D01*
G01X-291414Y219048D02*
X-291438Y219043D01*
G01X-291414Y215898D02*
X-291438Y215893D01*
G01X-291414Y212749D02*
X-291438Y212744D01*
G01X-291414Y209599D02*
X-291438Y209594D01*
G01X-291414Y206450D02*
X-291438Y206444D01*
G01X-286064Y209449D02*
X-285329Y209646D01*
G01Y206496D02*
X-286064Y206300D01*
G01X-318425Y240945D02*
Y241733D01*
G01Y244095D02*
Y244882D01*
G01Y237796D02*
Y238583D01*
G01Y231496D02*
Y232284D01*
G01Y234646D02*
Y235433D01*
G01Y228347D02*
Y229134D01*
G01Y222048D02*
Y222835D01*
G01Y225197D02*
Y225985D01*
G01Y218898D02*
Y219685D01*
G01Y212599D02*
Y213386D01*
G01Y215748D02*
Y216536D01*
G01Y209449D02*
Y210237D01*
G01Y206300D02*
Y207087D01*
G01X-318504Y249607D02*
Y252756D01*
G01X-319016Y243977D02*
Y245000D01*
G01Y240827D02*
Y241851D01*
G01Y237677D02*
Y238701D01*
G01Y234528D02*
Y235552D01*
G01Y231378D02*
Y232402D01*
G01Y228229D02*
Y229252D01*
G01Y225079D02*
Y226103D01*
G01Y221929D02*
Y222953D01*
G01Y218780D02*
Y219803D01*
G01Y215630D02*
Y216654D01*
G01Y212481D02*
Y213504D01*
G01Y209331D02*
Y210355D01*
G01Y206181D02*
Y207205D01*
G01X-319292Y249607D02*
Y252756D01*
G01X-319607Y207087D02*
Y206300D01*
G01Y210237D02*
Y209449D01*
G01Y213386D02*
Y212599D01*
G01Y216536D02*
Y215748D01*
G01Y219685D02*
Y218898D01*
G01Y222835D02*
Y222048D01*
G01Y225985D02*
Y225197D01*
G01Y229134D02*
Y228347D01*
G01Y232284D02*
Y231496D01*
G01Y235433D02*
Y234646D01*
G01Y238583D02*
Y237796D01*
G01Y241733D02*
Y240945D01*
G01Y244882D02*
Y244095D01*
G01X-320079Y249607D02*
Y252756D01*
G01X-320473Y249607D02*
Y252756D01*
G01X-320551Y207087D02*
Y206300D01*
G01Y210237D02*
Y209449D01*
G01Y213386D02*
Y212599D01*
G01Y216536D02*
Y215748D01*
G01Y219685D02*
Y218898D01*
G01Y222835D02*
Y222048D01*
G01Y225985D02*
Y225197D01*
G01Y229134D02*
Y228347D01*
G01Y232284D02*
Y231496D01*
G01Y235433D02*
Y234646D01*
G01Y238583D02*
Y237796D01*
G01Y241733D02*
Y240945D01*
G01Y244882D02*
Y244095D01*
G01X-321260Y245591D02*
Y252756D01*
G01Y242441D02*
Y243386D01*
G01Y239292D02*
Y240237D01*
G01Y236142D02*
Y237087D01*
G01Y232992D02*
Y233937D01*
G01Y229843D02*
Y230788D01*
G01Y226693D02*
Y227638D01*
G01Y223544D02*
Y224489D01*
G01Y220394D02*
Y221339D01*
G01Y217244D02*
Y218189D01*
G01Y214095D02*
Y215040D01*
G01Y210945D02*
Y211890D01*
G01Y207796D02*
Y208740D01*
G01Y204646D02*
Y205591D01*
G01Y207087D02*
Y206300D01*
G01Y210237D02*
Y209449D01*
G01Y213386D02*
Y212599D01*
G01Y216536D02*
Y215748D01*
G01Y219685D02*
Y218898D01*
G01Y222835D02*
Y222048D01*
G01Y225985D02*
Y225197D01*
G01Y229134D02*
Y228347D01*
G01Y232284D02*
Y231496D01*
G01Y235433D02*
Y234646D01*
G01Y238583D02*
Y237796D01*
G01Y241733D02*
Y240945D01*
G01Y244882D02*
Y244095D01*
G01X-321851Y240945D02*
Y241733D01*
G01Y244095D02*
Y244882D01*
G01Y237796D02*
Y238583D01*
G01Y231496D02*
Y232284D01*
G01Y234646D02*
Y235433D01*
G01Y228347D02*
Y229134D01*
G01Y222048D02*
Y222835D01*
G01Y225197D02*
Y225985D01*
G01Y218898D02*
Y219685D01*
G01Y212599D02*
Y213386D01*
G01Y215748D02*
Y216536D01*
G01Y209449D02*
Y210237D01*
G01Y206300D02*
Y207087D01*
G01X-322756D02*
Y206300D01*
G01Y210237D02*
Y209449D01*
G01Y213386D02*
Y212599D01*
G01Y216536D02*
Y215748D01*
G01Y219685D02*
Y218898D01*
G01Y222835D02*
Y222048D01*
G01Y225985D02*
Y225197D01*
G01Y229134D02*
Y228347D01*
G01Y232284D02*
Y231496D01*
G01Y235433D02*
Y234646D01*
G01Y238583D02*
Y237796D01*
G01Y241733D02*
Y240945D01*
G01Y244882D02*
Y244095D01*
G01X-323347Y207087D02*
Y206300D01*
G01Y210237D02*
Y209449D01*
G01Y213386D02*
Y212599D01*
G01Y216536D02*
Y215748D01*
G01Y219685D02*
Y218898D01*
G01Y222835D02*
Y222048D01*
G01Y225985D02*
Y225197D01*
G01Y229134D02*
Y228347D01*
G01Y232284D02*
Y231496D01*
G01Y235433D02*
Y234646D01*
G01Y238583D02*
Y237796D01*
G01Y241733D02*
Y240945D01*
G01Y244882D02*
Y244095D01*
G01X-324016Y249607D02*
Y252756D01*
G01X-324803D02*
Y249607D01*
G01X-326693Y288150D02*
Y268465D01*
G01X-329154D02*
Y276423D01*
G01X-340636D02*
Y268465D01*
G01X-343097D02*
Y288150D01*
G01X-309449Y222992D02*
X-309669Y223524D01*
G01X-309449Y219843D02*
X-309669Y220374D01*
G01X-309449Y216693D02*
X-309669Y217225D01*
G01X-309449Y213544D02*
X-309669Y214075D01*
G01X-309449Y210394D02*
X-309669Y210926D01*
G01X-309449Y207244D02*
X-309669Y207776D01*
G01X-284252Y245571D02*
X-283721Y245040D01*
G01X-284252Y242422D02*
X-283721Y241890D01*
G01X-284252Y239272D02*
X-283721Y238740D01*
G01X-284252Y236122D02*
X-283721Y235591D01*
G01X-284252Y232973D02*
X-283721Y232441D01*
G01X-284252Y229823D02*
X-283721Y229292D01*
G01X-284252Y226674D02*
X-283721Y226142D01*
G01X-306142Y245679D02*
X-306244Y245781D01*
G01X-284252Y223524D02*
X-283721Y222992D01*
G01X-308913Y246345D02*
X-309016Y246448D01*
G01X-306142Y242529D02*
X-306244Y242631D01*
G01X-308662Y245040D02*
X-309193Y245571D01*
G01X-284252Y220374D02*
X-283721Y219843D01*
G01X-308913Y243196D02*
X-309016Y243298D01*
G01X-312284Y246555D02*
X-312815Y247087D01*
G01X-306142Y239379D02*
X-306244Y239482D01*
G01X-308662Y241890D02*
X-309193Y242422D01*
G01X-284252Y217225D02*
X-283721Y216693D01*
G01X-312992Y244981D02*
X-313386Y245374D01*
G01X-308913Y240046D02*
X-309016Y240149D01*
G01X-312284Y243406D02*
X-312815Y243937D01*
G01X-306142Y236230D02*
X-306244Y236332D01*
G01X-308662Y238740D02*
X-309193Y239272D01*
G01X-284252Y214075D02*
X-283721Y213544D01*
G01X-313386Y242225D02*
X-312992Y241831D01*
G01X-308913Y236896D02*
X-309016Y236999D01*
G01X-312284Y240256D02*
X-312815Y240788D01*
G01X-306142Y233080D02*
X-306244Y233183D01*
G01X-308662Y235591D02*
X-309193Y236122D01*
G01X-284252Y210926D02*
X-283721Y210394D01*
G01X-313386Y239075D02*
X-312992Y238681D01*
G01X-308913Y233747D02*
X-309016Y233850D01*
G01X-312284Y237107D02*
X-312815Y237638D01*
G01X-320670Y245000D02*
X-321260Y245591D01*
G01X-306142Y229931D02*
X-306244Y230033D01*
G01X-308662Y232441D02*
X-309193Y232973D01*
G01X-284252Y207776D02*
X-283721Y207244D01*
G01X-313386Y235926D02*
X-312992Y235532D01*
G01X-308913Y230597D02*
X-309016Y230700D01*
G01X-312284Y233957D02*
X-312815Y234489D01*
G01X-320670Y241851D02*
X-321260Y242441D01*
G01X-306142Y226781D02*
X-306244Y226883D01*
G01X-308662Y229292D02*
X-309193Y229823D01*
G01X-313386Y232776D02*
X-312992Y232382D01*
G01X-308913Y227448D02*
X-309016Y227550D01*
G01X-312284Y230807D02*
X-312815Y231339D01*
G01X-320670Y238701D02*
X-321260Y239292D01*
G01X-306142Y223631D02*
X-306244Y223734D01*
G01X-308662Y226142D02*
X-309193Y226674D01*
G01X-313386Y229626D02*
X-312992Y229233D01*
G01X-308913Y224298D02*
X-309016Y224401D01*
G01X-312284Y227658D02*
X-312815Y228189D01*
G01X-320670Y235552D02*
X-321260Y236142D01*
G01X-306142Y220482D02*
X-306244Y220584D01*
G01X-308662Y222992D02*
X-309193Y223524D01*
G01X-313386Y226477D02*
X-312992Y226083D01*
G01X-308913Y221148D02*
X-309016Y221251D01*
G01X-312284Y224508D02*
X-312815Y225040D01*
G01X-320670Y232402D02*
X-321260Y232992D01*
G01X-306142Y217332D02*
X-306244Y217435D01*
G01X-308662Y219843D02*
X-309193Y220374D01*
G01X-313386Y223327D02*
X-312992Y222933D01*
G01X-308913Y217999D02*
X-309016Y218102D01*
G01X-312284Y221359D02*
X-312815Y221890D01*
G01X-320670Y229252D02*
X-321260Y229843D01*
G01X-306142Y214183D02*
X-306244Y214285D01*
G01X-308662Y216693D02*
X-309193Y217225D01*
G01X-313386Y220177D02*
X-312992Y219784D01*
G01X-308913Y214849D02*
X-309016Y214952D01*
G01X-312284Y218209D02*
X-312815Y218740D01*
G01X-320670Y226103D02*
X-321260Y226693D01*
G01X-306142Y211033D02*
X-306244Y211135D01*
G01X-308662Y213544D02*
X-309193Y214075D01*
G01X-313386Y217028D02*
X-312992Y216634D01*
G01X-308913Y211700D02*
X-309016Y211802D01*
G01X-312284Y215059D02*
X-312815Y215591D01*
G01X-320670Y222953D02*
X-321260Y223544D01*
G01X-306142Y207883D02*
X-306244Y207986D01*
G01X-308662Y210394D02*
X-309193Y210926D01*
G01X-313386Y213878D02*
X-312992Y213485D01*
G01X-308913Y208550D02*
X-309016Y208653D01*
G01X-312284Y211910D02*
X-312815Y212441D01*
G01X-320670Y219803D02*
X-321260Y220394D01*
G01X-306142Y204734D02*
X-306244Y204836D01*
G01X-308662Y207244D02*
X-309193Y207776D01*
G01X-313386Y210729D02*
X-312992Y210335D01*
G01X-308913Y205400D02*
X-309016Y205503D01*
G01X-312284Y208760D02*
X-312815Y209292D01*
G01X-320670Y216654D02*
X-321260Y217244D01*
G01X-313386Y207579D02*
X-312992Y207185D01*
G01X-312284Y205611D02*
X-312815Y206142D01*
G01X-320670Y213504D02*
X-321260Y214095D01*
G01X-320670Y210355D02*
X-321260Y210945D01*
G01X-320670Y207205D02*
X-321260Y207796D01*
G01X-286064Y229134D02*
X-285329Y228937D01*
G01X-286064Y225985D02*
X-285329Y225788D01*
G01X-286064Y222835D02*
X-285329Y222638D01*
G01X-286064Y219685D02*
X-285329Y219489D01*
G01X-286064Y216536D02*
X-285329Y216339D01*
G01X-286064Y213386D02*
X-285329Y213189D01*
G01X-286064Y210237D02*
X-285329Y210040D01*
G01X-286064Y207087D02*
X-285329Y206890D01*
G01X-291438Y222690D02*
X-291414Y222685D01*
G01X-291438Y219540D02*
X-291414Y219535D01*
G01X-291438Y216391D02*
X-291414Y216386D01*
G01X-291438Y213241D02*
X-291414Y213236D01*
G01X-291438Y210092D02*
X-291414Y210087D01*
G01X-291438Y206942D02*
X-291414Y206937D01*
G01X-291879Y224304D02*
X-292395Y224410D01*
G01X-291879Y221155D02*
X-292395Y221260D01*
G01X-291879Y218005D02*
X-292395Y218111D01*
G01X-291879Y214855D02*
X-292395Y214961D01*
G01X-291879Y211706D02*
X-292395Y211811D01*
G01X-291879Y208556D02*
X-292395Y208662D01*
G01X-291879Y205407D02*
X-292395Y205512D01*
G01X-290085Y220587D02*
X-289491Y220473D01*
G01X-290085Y217438D02*
X-289491Y217323D01*
G01X-290085Y214288D02*
X-289491Y214174D01*
G01X-290085Y211139D02*
X-289491Y211024D01*
G01X-290085Y207989D02*
X-289491Y207874D01*
G01X-290085Y204839D02*
X-289491Y204725D01*
G01X-289641Y218898D02*
X-290539Y219059D01*
G01X-289641Y215748D02*
X-290539Y215909D01*
G01X-289641Y212599D02*
X-290539Y212760D01*
G01X-289641Y209449D02*
X-290539Y209610D01*
G01X-289641Y206300D02*
X-290539Y206461D01*
G01X-292794Y210237D02*
X-291637Y210122D01*
G01X-292794Y207087D02*
X-291637Y206972D01*
G01X-292043Y307345D02*
X-292105Y307618D01*
G01X-291980Y307084D02*
X-292043Y307345D01*
G01X-291916Y306831D02*
X-291980Y307084D01*
G01X-289911Y307077D02*
X-289974Y306831D01*
G01X-289849Y307339D02*
X-289911Y307077D01*
G01X-289785Y307618D02*
X-289849Y307339D01*
G01X-276148Y301183D02*
G03X-275610Y301085I618J1869D01*
G01X-279395Y303297D02*
G03X-279705Y303347I-310J-934D01*
G01X-280217Y305906D02*
G03X-281398Y307087I-1181J0D01*
G01X-279403Y302263D02*
G03X-280023Y302363I-619J-1869D01*
G01X-287697Y307087D02*
G03X-288878Y305906I0J-1181D01*
G01X-291916Y306831D02*
G03X-289974I971J-1712D01*
G01X-292105Y307618D02*
G03X-289785I1160J-2500D01*
G01X-287874Y305118D02*
G03I-3071J0D01*
G01X-324038Y309119D02*
X-323976Y309140D01*
G01X-324059Y309242D02*
X-323997Y309263D01*
G01X-324394Y309140D02*
X-324457Y309119D01*
G01X-324478Y309242D02*
X-324416Y309263D01*
G01X-324143Y309181D02*
X-324059Y309242D01*
G01X-324562Y309181D02*
X-324478Y309242D01*
G01X-324080Y309078D02*
X-324038Y309119D01*
G01X-324457D02*
X-324499Y309078D01*
G01X-284252Y311122D02*
X-283721Y311654D01*
G01X-284252Y314272D02*
X-283721Y314803D01*
G01X-284252Y317422D02*
X-283721Y317953D01*
G01X-284252Y320571D02*
X-283721Y321103D01*
G01X-284252Y323721D02*
X-283721Y324252D01*
G01X-284252Y326870D02*
X-283721Y327402D01*
G01X-284252Y330020D02*
X-283721Y330552D01*
G01X-306244Y310912D02*
X-306142Y311015D01*
G01X-284252Y333170D02*
X-283721Y333701D01*
G01X-308913Y310348D02*
X-309016Y310246D01*
G01X-306244Y314062D02*
X-306142Y314165D01*
G01X-308662Y311654D02*
X-309193Y311122D01*
G01D02*
X-308662Y311654D01*
G01X-284252Y336319D02*
X-283721Y336851D01*
G01X-312992Y308563D02*
X-313386Y308170D01*
G01X-308913Y313498D02*
X-309016Y313395D01*
G01X-312815Y309607D02*
X-312284Y310138D01*
G01X-306244Y317211D02*
X-306142Y317314D01*
G01X-308662Y314803D02*
X-309193Y314272D01*
G01D02*
X-308662Y314803D01*
G01X-284252Y339469D02*
X-283721Y340000D01*
G01X-312992Y311713D02*
X-313386Y311319D01*
G01X-308913Y316647D02*
X-309016Y316545D01*
G01X-312815Y312756D02*
X-312284Y313288D01*
G01X-306244Y320361D02*
X-306142Y320464D01*
G01X-308662Y317953D02*
X-309193Y317422D01*
G01D02*
X-308662Y317953D01*
G01X-284252Y342618D02*
X-283721Y343150D01*
G01X-312992Y314863D02*
X-313386Y314469D01*
G01X-308913Y319797D02*
X-309016Y319694D01*
G01X-312815Y315906D02*
X-312284Y316437D01*
G01X-320670Y308544D02*
X-321260Y307953D01*
G01X-306244Y323511D02*
X-306142Y323613D01*
G01X-308662Y321103D02*
X-309193Y320571D01*
G01D02*
X-308662Y321103D01*
G01X-312992Y318012D02*
X-313386Y317618D01*
G01X-308913Y322946D02*
X-309016Y322844D01*
G01X-312815Y319055D02*
X-312284Y319587D01*
G01X-320670Y311693D02*
X-321260Y311103D01*
G01X-306244Y326660D02*
X-306142Y326763D01*
G01X-308662Y324252D02*
X-309193Y323721D01*
G01D02*
X-308662Y324252D01*
G01X-312992Y321162D02*
X-313386Y320768D01*
G01X-308913Y326096D02*
X-309016Y325994D01*
G01X-312815Y322205D02*
X-312284Y322737D01*
G01X-320670Y314843D02*
X-321260Y314252D01*
G01X-306244Y329810D02*
X-306142Y329913D01*
G01X-308662Y327402D02*
X-309193Y326870D01*
G01D02*
X-308662Y327402D01*
G01X-312992Y324311D02*
X-313386Y323918D01*
G01X-308913Y329246D02*
X-309016Y329143D01*
G01X-312815Y325355D02*
X-312284Y325886D01*
G01X-320670Y317992D02*
X-321260Y317402D01*
G01X-306244Y332959D02*
X-306142Y333062D01*
G01X-308662Y330552D02*
X-309193Y330020D01*
G01D02*
X-308662Y330552D01*
G01X-312992Y327461D02*
X-313386Y327067D01*
G01X-308913Y332395D02*
X-309016Y332293D01*
G01X-312815Y328504D02*
X-312284Y329036D01*
G01X-320670Y321142D02*
X-321260Y320552D01*
G01X-306244Y336109D02*
X-306142Y336212D01*
G01X-308662Y333701D02*
X-309193Y333170D01*
G01D02*
X-308662Y333701D01*
G01X-312992Y330611D02*
X-313386Y330217D01*
G01X-308913Y335545D02*
X-309016Y335442D01*
G01X-312815Y331654D02*
X-312284Y332185D01*
G01X-320670Y324292D02*
X-321260Y323701D01*
G01X-306244Y339259D02*
X-306142Y339361D01*
G01X-308662Y336851D02*
X-309193Y336319D01*
G01D02*
X-308662Y336851D01*
G01X-312992Y333760D02*
X-313386Y333366D01*
G01X-308913Y338694D02*
X-309016Y338592D01*
G01X-312815Y334803D02*
X-312284Y335335D01*
G01X-320670Y327441D02*
X-321260Y326851D01*
G01X-306244Y342408D02*
X-306142Y342511D01*
G01X-308662Y340000D02*
X-309193Y339469D01*
G01D02*
X-308662Y340000D01*
G01X-312992Y336910D02*
X-313386Y336516D01*
G01X-308913Y341844D02*
X-309016Y341742D01*
G01X-312815Y337953D02*
X-312284Y338485D01*
G01X-320670Y330591D02*
X-321260Y330000D01*
G01X-308662Y343150D02*
X-309193Y342618D01*
G01D02*
X-308662Y343150D01*
G01X-312992Y340059D02*
X-313386Y339666D01*
G01X-308913Y344994D02*
X-309016Y344891D01*
G01X-312815Y341103D02*
X-312284Y341634D01*
G01X-320670Y333740D02*
X-321260Y333150D01*
G01X-312992Y343209D02*
X-313386Y342815D01*
G01X-312815Y344252D02*
X-312284Y344784D01*
G01X-320670Y336890D02*
X-321260Y336300D01*
G01X-320670Y340040D02*
X-321260Y339449D01*
G01X-320670Y343189D02*
X-321260Y342599D01*
G01X-274803Y284646D02*
X-276772Y281103D01*
G01X-313701Y344882D02*
X-285546D01*
G01X-287992Y344784D02*
X-284252D01*
G01X-312284D02*
X-293898D01*
G01X-311418Y344489D02*
X-313386D01*
G01X-279528D02*
X-282284D01*
G01X-279528Y344331D02*
X-313130D01*
G01X-312815Y344252D02*
X-283721D01*
G01X-319016Y344213D02*
X-320670D01*
G01X-303622Y344193D02*
X-312992D01*
G01X-286064Y344095D02*
X-323347D01*
G01Y343307D02*
X-286064D01*
G01X-303622Y343209D02*
X-312992D01*
G01X-320670Y343189D02*
X-319016D01*
G01X-283721Y343150D02*
X-312815D01*
G01X-313130Y343071D02*
X-279528D01*
G01X-313386Y342914D02*
X-311418D01*
G01X-279528D02*
X-282284D01*
G01X-293898Y342618D02*
X-312284D01*
G01X-284252D02*
X-287992D01*
G01X-313701Y342520D02*
X-285546D01*
G01X-308657Y342323D02*
X-306500D01*
G01Y341929D02*
X-308657D01*
G01X-313701Y341733D02*
X-285546D01*
G01X-287992Y341634D02*
X-284252D01*
G01X-312284D02*
X-293898D01*
G01X-311418Y341339D02*
X-313386D01*
G01X-279528D02*
X-282284D01*
G01X-279528Y341181D02*
X-313130D01*
G01X-312815Y341103D02*
X-283721D01*
G01X-319016Y341063D02*
X-320670D01*
G01X-303622Y341044D02*
X-312992D01*
G01X-286064Y340945D02*
X-323347D01*
G01Y340158D02*
X-286064D01*
G01X-303622Y340059D02*
X-312992D01*
G01X-320670Y340040D02*
X-319016D01*
G01X-283721Y340000D02*
X-312815D01*
G01X-313130Y339922D02*
X-279528D01*
G01X-313386Y339764D02*
X-311418D01*
G01X-279528D02*
X-282284D01*
G01X-293898Y339469D02*
X-312284D01*
G01X-284252D02*
X-287992D01*
G01X-313701Y339370D02*
X-285546D01*
G01X-308657Y339174D02*
X-306500D01*
G01Y338780D02*
X-308657D01*
G01X-313701Y338583D02*
X-285546D01*
G01X-287992Y338485D02*
X-284252D01*
G01X-312284D02*
X-293898D01*
G01X-311418Y338189D02*
X-313386D01*
G01X-279528D02*
X-282284D01*
G01X-279528Y338032D02*
X-313130D01*
G01X-312815Y337953D02*
X-283721D01*
G01X-319016Y337914D02*
X-320670D01*
G01X-303622Y337894D02*
X-312992D01*
G01X-286064Y337796D02*
X-323347D01*
G01Y337008D02*
X-286064D01*
G01X-303622Y336910D02*
X-312992D01*
G01X-320670Y336890D02*
X-319016D01*
G01X-283721Y336851D02*
X-312815D01*
G01X-313130Y336772D02*
X-279528D01*
G01X-313386Y336615D02*
X-311418D01*
G01X-279528D02*
X-282284D01*
G01X-293898Y336319D02*
X-312284D01*
G01X-284252D02*
X-287992D01*
G01X-313701Y336221D02*
X-285546D01*
G01X-308657Y336024D02*
X-306500D01*
G01Y335630D02*
X-308657D01*
G01X-313701Y335433D02*
X-285546D01*
G01X-287992Y335335D02*
X-284252D01*
G01X-312284D02*
X-293898D01*
G01X-311418Y335040D02*
X-313386D01*
G01X-279528D02*
X-282284D01*
G01X-279528Y334882D02*
X-313130D01*
G01X-312815Y334803D02*
X-283721D01*
G01X-319016Y334764D02*
X-320670D01*
G01X-303622Y334744D02*
X-312992D01*
G01X-286064Y334646D02*
X-323347D01*
G01Y333859D02*
X-286064D01*
G01X-303622Y333760D02*
X-312992D01*
G01X-320670Y333740D02*
X-319016D01*
G01X-283721Y333701D02*
X-312815D01*
G01X-313130Y333622D02*
X-279528D01*
G01X-313386Y333465D02*
X-311418D01*
G01X-279528D02*
X-282284D01*
G01X-291637Y343422D02*
X-292794Y343307D01*
G01X-291637Y340272D02*
X-292794Y340158D01*
G01X-291637Y337123D02*
X-292794Y337008D01*
G01X-291637Y333973D02*
X-292794Y333859D01*
G01X-291637Y330824D02*
X-292794Y330709D01*
G01X-291637Y327674D02*
X-292794Y327559D01*
G01X-291637Y324524D02*
X-292794Y324410D01*
G01X-291637Y321375D02*
X-292794Y321260D01*
G01X-291637Y318225D02*
X-292794Y318111D01*
G01X-290539Y343934D02*
X-289641Y344095D01*
G01X-290539Y340784D02*
X-289641Y340945D01*
G01X-290539Y337635D02*
X-289641Y337796D01*
G01X-290539Y334485D02*
X-289641Y334646D01*
G01X-290539Y331335D02*
X-289641Y331496D01*
G01X-290539Y328186D02*
X-289641Y328347D01*
G01X-290539Y325036D02*
X-289641Y325197D01*
G01X-290539Y321887D02*
X-289641Y322048D01*
G01X-290539Y318737D02*
X-289641Y318898D01*
G01X-290539Y315587D02*
X-289641Y315748D01*
G01X-290539Y312438D02*
X-289641Y312599D01*
G01X-290539Y309288D02*
X-289641Y309449D01*
G01X-289491Y342520D02*
X-290085Y342405D01*
G01X-289491Y339370D02*
X-290085Y339256D01*
G01X-289491Y336221D02*
X-290085Y336106D01*
G01X-289491Y333071D02*
X-290085Y332957D01*
G01X-289491Y329922D02*
X-290085Y329807D01*
G01X-289491Y326772D02*
X-290085Y326657D01*
G01X-289491Y323622D02*
X-290085Y323508D01*
G01X-289491Y320473D02*
X-290085Y320358D01*
G01X-289491Y317323D02*
X-290085Y317209D01*
G01X-289491Y314174D02*
X-290085Y314059D01*
G01X-289491Y311024D02*
X-290085Y310909D01*
G01X-297028Y304292D02*
X-301910Y303347D01*
G01X-296841Y303325D02*
X-301815Y302363D01*
G01X-291879Y344988D02*
X-292395Y344882D01*
G01X-291879Y341838D02*
X-292395Y341733D01*
G01X-291879Y338689D02*
X-292395Y338583D01*
G01X-291879Y335539D02*
X-292395Y335433D01*
G01X-291879Y332389D02*
X-292395Y332284D01*
G01X-291879Y329240D02*
X-292395Y329134D01*
G01X-291879Y326090D02*
X-292395Y325985D01*
G01X-291879Y322940D02*
X-292395Y322835D01*
G01X-291879Y319791D02*
X-292395Y319685D01*
G01X-291879Y316641D02*
X-292395Y316536D01*
G01X-291879Y313492D02*
X-292395Y313386D01*
G01X-291879Y310342D02*
X-292395Y310237D01*
G01X-291414Y343457D02*
X-291438Y343452D01*
G01X-291414Y340308D02*
X-291438Y340303D01*
G01X-291414Y337158D02*
X-291438Y337153D01*
G01X-291414Y334009D02*
X-291438Y334003D01*
G01X-291414Y330859D02*
X-291438Y330854D01*
G01X-291414Y327709D02*
X-291438Y327704D01*
G01X-291414Y324560D02*
X-291438Y324555D01*
G01X-291414Y321410D02*
X-291438Y321405D01*
G01X-291414Y318261D02*
X-291438Y318255D01*
G01X-291414Y315111D02*
X-291438Y315106D01*
G01X-291414Y311961D02*
X-291438Y311956D01*
G01X-291414Y308812D02*
X-291438Y308807D01*
G01X-286064Y343307D02*
X-285329Y343504D01*
G01X-286064Y340158D02*
X-285329Y340355D01*
G01X-286064Y337008D02*
X-285329Y337205D01*
G01X-286064Y333859D02*
X-285329Y334055D01*
G01X-286064Y330709D02*
X-285329Y330906D01*
G01X-286064Y327559D02*
X-285329Y327756D01*
G01Y324607D02*
X-286064Y324410D01*
G01X-285329Y321457D02*
X-286064Y321260D01*
G01Y318111D02*
X-285329Y318307D01*
G01X-286064Y314961D02*
X-285329Y315158D01*
G01Y312008D02*
X-286064Y311811D01*
G01X-285329Y308859D02*
X-286064Y308662D01*
G01X-324625Y309099D02*
X-324562Y309181D01*
G01X-324164Y309140D02*
X-324143Y309181D01*
G01X-309669Y311122D02*
X-309449Y311654D01*
G01X-309669Y314272D02*
X-309449Y314803D01*
G01X-309669Y317422D02*
X-309449Y317953D01*
G01X-309669Y320571D02*
X-309449Y321103D01*
G01X-309669Y323721D02*
X-309449Y324252D01*
G01X-309669Y326870D02*
X-309449Y327402D01*
G01X-309669Y330020D02*
X-309449Y330552D01*
G01X-309669Y333170D02*
X-309449Y333701D01*
G01X-309669Y336319D02*
X-309449Y336851D01*
G01X-286064Y344095D02*
X-285329Y343898D01*
G01X-286064Y340945D02*
X-285329Y340748D01*
G01X-286064Y337796D02*
X-285329Y337599D01*
G01X-286064Y334646D02*
X-285329Y334449D01*
G01X-286064Y331496D02*
X-285329Y331300D01*
G01X-286064Y328347D02*
X-285329Y328150D01*
G01X-286064Y325197D02*
X-285329Y325000D01*
G01X-286064Y322048D02*
X-285329Y321851D01*
G01X-286064Y318898D02*
X-285329Y318701D01*
G01X-286064Y315748D02*
X-285329Y315552D01*
G01X-286064Y312599D02*
X-285329Y312402D01*
G01X-286064Y309449D02*
X-285329Y309252D01*
G01X-291438Y343950D02*
X-291414Y343945D01*
G01X-291438Y340800D02*
X-291414Y340795D01*
G01X-291438Y337651D02*
X-291414Y337646D01*
G01X-291438Y334501D02*
X-291414Y334496D01*
G01X-291438Y331352D02*
X-291414Y331346D01*
G01X-291438Y328202D02*
X-291414Y328197D01*
G01X-291438Y325052D02*
X-291414Y325047D01*
G01X-291438Y321903D02*
X-291414Y321898D01*
G01X-291438Y318753D02*
X-291414Y318748D01*
G01X-291438Y315603D02*
X-291414Y315598D01*
G01X-291438Y312454D02*
X-291414Y312449D01*
G01X-291438Y309304D02*
X-291414Y309299D01*
G01X-291879Y342415D02*
X-292395Y342520D01*
G01X-291879Y339265D02*
X-292395Y339370D01*
G01X-291879Y336115D02*
X-292395Y336221D01*
G01X-291879Y332966D02*
X-292395Y333071D01*
G01X-291879Y329816D02*
X-292395Y329922D01*
G01X-291879Y326666D02*
X-292395Y326772D01*
G01X-291879Y323517D02*
X-292395Y323622D01*
G01X-291879Y320367D02*
X-292395Y320473D01*
G01X-291879Y317218D02*
X-292395Y317323D01*
G01X-291879Y314068D02*
X-292395Y314174D01*
G01X-291879Y310918D02*
X-292395Y311024D01*
G01X-290085Y344997D02*
X-289491Y344882D01*
G01X-290085Y341847D02*
X-289491Y341733D01*
G01X-290085Y338698D02*
X-289491Y338583D01*
G01X-290085Y335548D02*
X-289491Y335433D01*
G01X-290085Y332398D02*
X-289491Y332284D01*
G01X-290085Y329249D02*
X-289491Y329134D01*
G01X-290085Y326099D02*
X-289491Y325985D01*
G01X-290085Y322950D02*
X-289491Y322835D01*
G01X-290085Y319800D02*
X-289491Y319685D01*
G01X-290085Y316650D02*
X-289491Y316536D01*
G01X-290085Y313501D02*
X-289491Y313386D01*
G01X-290085Y310351D02*
X-289491Y310237D01*
G01X-289641Y343307D02*
X-290539Y343468D01*
G01X-289641Y340158D02*
X-290539Y340319D01*
G01X-289641Y337008D02*
X-290539Y337169D01*
G01X-289641Y333859D02*
X-290539Y334020D01*
G01X-289641Y330709D02*
X-290539Y330870D01*
G01X-289641Y327559D02*
X-290539Y327720D01*
G01X-289641Y324410D02*
X-290539Y324571D01*
G01X-289641Y321260D02*
X-290539Y321421D01*
G01X-289641Y318111D02*
X-290539Y318272D01*
G01X-289641Y314961D02*
X-290539Y315122D01*
G01X-289641Y311811D02*
X-290539Y311972D01*
G01X-289641Y308662D02*
X-290539Y308823D01*
G01X-292794Y344095D02*
X-291637Y343980D01*
G01X-292794Y340945D02*
X-291637Y340831D01*
G01X-292794Y337796D02*
X-291637Y337681D01*
G01X-292794Y334646D02*
X-291637Y334531D01*
G01X-292794Y331496D02*
X-291637Y331382D01*
G01X-292794Y328347D02*
X-291637Y328232D01*
G01X-292794Y325197D02*
X-291637Y325083D01*
G01X-292794Y322048D02*
X-291637Y321933D01*
G01X-292794Y318898D02*
X-291637Y318783D01*
G01X-292794Y315748D02*
X-291637Y315634D01*
G01X-292794Y312599D02*
X-291637Y312484D01*
G01X-292794Y309449D02*
X-291637Y309335D01*
G01X-293898Y333170D02*
X-312284D01*
G01X-284252D02*
X-287992D01*
G01X-313701Y333071D02*
X-285546D01*
G01X-308657Y332874D02*
X-306500D01*
G01Y332481D02*
X-308657D01*
G01X-313701Y332284D02*
X-285546D01*
G01X-287992Y332185D02*
X-284252D01*
G01X-312284D02*
X-293898D01*
G01X-311418Y331890D02*
X-313386D01*
G01X-279528D02*
X-282284D01*
G01X-279528Y331733D02*
X-313130D01*
G01X-312815Y331654D02*
X-283721D01*
G01X-319016Y331615D02*
X-320670D01*
G01X-303622Y331595D02*
X-312992D01*
G01X-286064Y331496D02*
X-323347D01*
G01Y330709D02*
X-286064D01*
G01X-303622Y330611D02*
X-312992D01*
G01X-320670Y330591D02*
X-319016D01*
G01X-283721Y330552D02*
X-312815D01*
G01X-313130Y330473D02*
X-279528D01*
G01X-313386Y330315D02*
X-311418D01*
G01X-279528D02*
X-282284D01*
G01X-293898Y330020D02*
X-312284D01*
G01X-284252D02*
X-287992D01*
G01X-313701Y329922D02*
X-285546D01*
G01X-308657Y329725D02*
X-306500D01*
G01Y329331D02*
X-308657D01*
G01X-313701Y329134D02*
X-285546D01*
G01X-287992Y329036D02*
X-284252D01*
G01X-312284D02*
X-293898D01*
G01X-311418Y328740D02*
X-313386D01*
G01X-279528D02*
X-282284D01*
G01X-279528Y328583D02*
X-313130D01*
G01X-312815Y328504D02*
X-283721D01*
G01X-319016Y328465D02*
X-320670D01*
G01X-303622Y328445D02*
X-312992D01*
G01X-286064Y328347D02*
X-323347D01*
G01Y327559D02*
X-286064D01*
G01X-303622Y327461D02*
X-312992D01*
G01X-320670Y327441D02*
X-319016D01*
G01X-283721Y327402D02*
X-312815D01*
G01X-313130Y327323D02*
X-279528D01*
G01X-313386Y327166D02*
X-311418D01*
G01X-279528D02*
X-282284D01*
G01X-293898Y326870D02*
X-312284D01*
G01X-284252D02*
X-287992D01*
G01X-313701Y326772D02*
X-285546D01*
G01X-308657Y326575D02*
X-306500D01*
G01Y326181D02*
X-308657D01*
G01X-313701Y325985D02*
X-285546D01*
G01X-287992Y325886D02*
X-284252D01*
G01X-312284D02*
X-293898D01*
G01X-311418Y325591D02*
X-313386D01*
G01X-279528D02*
X-282284D01*
G01X-279528Y325433D02*
X-313130D01*
G01X-312815Y325355D02*
X-283721D01*
G01X-319016Y325315D02*
X-320670D01*
G01X-303622Y325296D02*
X-312992D01*
G01X-286064Y325197D02*
X-323347D01*
G01Y324410D02*
X-286064D01*
G01X-303622Y324311D02*
X-312992D01*
G01X-320670Y324292D02*
X-319016D01*
G01X-283721Y324252D02*
X-312815D01*
G01X-313130Y324174D02*
X-279528D01*
G01X-313386Y324016D02*
X-311418D01*
G01X-279528D02*
X-282284D01*
G01X-293898Y323721D02*
X-312284D01*
G01X-284252D02*
X-287992D01*
G01X-313701Y323622D02*
X-285546D01*
G01X-308657Y323426D02*
X-306500D01*
G01Y323032D02*
X-308657D01*
G01X-313701Y322835D02*
X-285546D01*
G01X-287992Y322737D02*
X-284252D01*
G01X-312284D02*
X-293898D01*
G01X-311418Y322441D02*
X-313386D01*
G01X-279528D02*
X-282284D01*
G01X-279528Y322284D02*
X-313130D01*
G01X-312815Y322205D02*
X-283721D01*
G01X-319016Y322166D02*
X-320670D01*
G01X-303622Y322146D02*
X-312992D01*
G01X-286064Y322048D02*
X-323347D01*
G01Y321260D02*
X-286064D01*
G01X-303622Y321162D02*
X-312992D01*
G01X-320670Y321142D02*
X-319016D01*
G01X-283721Y321103D02*
X-312815D01*
G01X-313130Y321024D02*
X-279528D01*
G01X-313386Y320866D02*
X-311418D01*
G01X-279528D02*
X-282284D01*
G01X-293898Y320571D02*
X-312284D01*
G01X-284252D02*
X-287992D01*
G01X-313701Y320473D02*
X-285546D01*
G01X-308657Y320276D02*
X-306500D01*
G01Y319882D02*
X-308657D01*
G01X-313701Y319685D02*
X-285546D01*
G01X-287992Y319587D02*
X-284252D01*
G01X-312284D02*
X-293898D01*
G01X-311418Y319292D02*
X-313386D01*
G01X-279528D02*
X-282284D01*
G01X-279528Y319134D02*
X-313130D01*
G01X-312815Y319055D02*
X-283721D01*
G01X-319016Y319016D02*
X-320670D01*
G01X-303622Y318996D02*
X-312992D01*
G01X-286064Y318898D02*
X-323347D01*
G01Y318111D02*
X-286064D01*
G01X-303622Y318012D02*
X-312992D01*
G01X-320670Y317992D02*
X-319016D01*
G01X-283721Y317953D02*
X-312815D01*
G01X-313130Y317874D02*
X-279528D01*
G01X-296720Y317717D02*
X-282284D01*
G01X-313386D02*
X-311418D01*
G01X-270689D02*
X-279528D01*
G01D02*
X-282284D01*
G01X-293898Y317422D02*
X-312284D01*
G01X-284252D02*
X-287992D01*
G01X-313701Y317323D02*
X-285546D01*
G01X-308657Y317126D02*
X-306500D01*
G01Y316733D02*
X-308657D01*
G01X-313701Y316536D02*
X-285546D01*
G01X-287992Y316437D02*
X-284252D01*
G01X-312284D02*
X-293898D01*
G01X-311418Y316142D02*
X-313386D01*
G01X-279528D02*
X-282284D01*
G01X-279528Y315985D02*
X-313130D01*
G01X-312815Y315906D02*
X-283721D01*
G01X-319016Y315866D02*
X-320670D01*
G01X-303622Y315847D02*
X-312992D01*
G01X-286064Y315748D02*
X-323347D01*
G01X-270689D02*
X-275610D01*
G01X-323347Y314961D02*
X-286064D01*
G01X-303622Y314863D02*
X-312992D01*
G01X-320670Y314843D02*
X-319016D01*
G01X-283721Y314803D02*
X-312815D01*
G01X-313130Y314725D02*
X-279528D01*
G01X-313386Y314567D02*
X-311418D01*
G01X-279528D02*
X-282284D01*
G01X-293898Y314272D02*
X-312284D01*
G01X-284252D02*
X-287992D01*
G01X-313701Y314174D02*
X-285546D01*
G01X-308657Y313977D02*
X-306500D01*
G01Y313583D02*
X-308657D01*
G01X-313701Y313386D02*
X-285546D01*
G01X-287992Y313288D02*
X-284252D01*
G01X-312284D02*
X-293898D01*
G01X-311418Y312992D02*
X-313386D01*
G01X-279528D02*
X-282284D01*
G01X-279528Y312835D02*
X-313130D01*
G01X-312815Y312756D02*
X-283721D01*
G01X-319016Y312717D02*
X-320670D01*
G01X-303622Y312697D02*
X-312992D01*
G01X-286064Y312599D02*
X-323347D01*
G01Y311811D02*
X-286064D01*
G01X-303622Y311713D02*
X-312992D01*
G01X-320670Y311693D02*
X-319016D01*
G01X-283721Y311654D02*
X-312815D01*
G01X-313130Y311575D02*
X-279528D01*
G01X-313386Y311418D02*
X-311418D01*
G01X-279528D02*
X-282284D01*
G01X-293898Y311122D02*
X-312284D01*
G01X-284252D02*
X-287992D01*
G01X-313701Y311024D02*
X-285546D01*
G01X-308657Y310827D02*
X-306500D01*
G01Y310433D02*
X-308657D01*
G01X-313701Y310237D02*
X-285546D01*
G01X-287992Y310138D02*
X-284252D01*
G01X-312284D02*
X-293898D01*
G01X-311418Y309843D02*
X-313386D01*
G01X-279528D02*
X-282284D01*
G01X-313130Y309685D02*
X-279528D01*
G01X-324646Y309673D02*
X-323662D01*
G01X-312815Y309607D02*
X-283721D01*
G01X-319016Y309567D02*
X-320670D01*
G01X-323662Y309550D02*
X-324478D01*
G01X-303622Y309548D02*
X-312992D01*
G01X-286064Y309449D02*
X-323347D01*
G01X-324332Y309427D02*
X-324499D01*
G01X-323997Y309263D02*
X-323892D01*
G01X-324416D02*
X-324332D01*
G01X-323976Y309140D02*
X-323913D01*
G01X-324353D02*
X-324394D01*
G01X-323347Y308662D02*
X-286064D01*
G01X-324520Y308627D02*
X-324227D01*
G01X-323787D02*
X-324101D01*
G01X-303622Y308563D02*
X-312992D01*
G01X-320670Y308544D02*
X-319016D01*
G01X-323662Y308504D02*
X-324646D01*
G01X-313130Y308426D02*
X-279528D01*
G01X-313386Y308268D02*
X-311418D01*
G01X-279528Y307618D02*
X-295276D01*
G01X-281398Y307087D02*
X-287697D01*
G01X-289974Y306831D02*
X-291916D01*
G01X-303622Y305512D02*
X-282225D01*
G01X-324803D02*
X-320473D01*
G01X-314961D02*
X-320079D01*
G01X-296418Y304331D02*
X-313386D01*
G01X-280217D02*
X-280512D01*
G01D02*
X-288977D01*
G01X-238996Y303544D02*
X-275610D01*
G01X-303504Y303347D02*
X-303603D01*
G01X-279528D02*
X-303504D01*
G01X-324803Y302363D02*
X-279528D01*
G01X-275610Y302067D02*
X-238996D01*
G01X-275610D02*
X-275688D01*
G01X-238996Y301083D02*
X-275610D01*
G01X-326811Y299213D02*
X-236260D01*
G01X-240158Y296654D02*
X-282677D01*
G01X-251969Y292717D02*
X-278740D01*
G01Y291103D02*
X-274803D01*
G01X-251969Y290709D02*
X-276378D01*
G01X-278347Y290512D02*
X-260118D01*
G01X-278740D02*
X-276378D01*
G01Y289961D02*
X-255906D01*
G01X-278740Y289626D02*
X-276772D01*
G01Y289380D02*
X-278405D01*
G01X-278112Y289134D02*
X-278447D01*
G01X-278740Y288544D02*
X-276378D01*
G01X-264173D02*
X-278347D01*
G01X-329154Y288150D02*
X-326693D01*
G01X-343097D02*
X-340636D01*
G01X-276772Y287953D02*
X-278740D01*
G01X-276772Y281103D02*
X-278740D01*
G01Y280512D02*
X-276378D01*
G01X-257481D02*
X-278347D01*
G01X-340636Y278936D02*
X-329154D01*
G01X-278740Y278544D02*
X-276378D01*
G01X-257481D02*
X-278347D01*
G01X-276772Y277953D02*
X-278740D01*
G01X-329154Y276423D02*
X-340636D01*
G01X-291637Y315076D02*
X-292794Y314961D01*
G01X-291637Y311926D02*
X-292794Y311811D01*
G01X-291637Y308776D02*
X-292794Y308662D01*
G01X-309669Y339469D02*
X-309449Y340000D01*
G01X-309669Y342618D02*
X-309449Y343150D01*
G01X-324101Y309017D02*
X-324080Y309078D01*
G01X-324499D02*
X-324520Y309017D01*
G01X-324646Y308996D02*
X-324625Y309099D01*
G01X-285338Y315554D02*
Y315155D01*
G01Y318703D02*
Y318305D01*
G01Y328152D02*
Y327754D01*
G01Y331302D02*
Y330903D01*
G01Y334452D02*
Y334053D01*
G01Y337601D02*
Y337203D01*
G01Y340751D02*
Y340352D01*
G01Y343900D02*
Y343502D01*
G01Y309255D02*
Y308856D01*
G01Y312404D02*
Y312006D01*
G01Y321853D02*
Y321455D01*
G01Y325003D02*
Y324604D01*
G01X-275610Y315748D02*
Y301083D01*
G01X-276378Y280512D02*
Y278544D01*
G01Y281811D02*
Y277244D01*
G01Y290512D02*
Y288544D01*
G01Y291103D02*
Y287481D01*
G01X-276772Y289626D02*
Y289380D01*
G01X-277599Y288544D02*
Y290512D01*
G01Y278544D02*
Y280512D01*
G01X-277739Y317717D02*
Y355512D01*
G01X-278012D02*
Y317717D01*
G01X-278347Y280512D02*
Y278544D01*
G01Y290512D02*
Y288544D01*
G01X-278740Y289380D02*
Y289626D01*
G01Y288544D02*
Y280512D01*
G01Y292717D02*
Y290512D01*
G01X-279528Y370866D02*
Y302363D01*
G01X-280217Y305906D02*
Y302363D01*
G01X-280512D02*
Y307618D01*
G01X-282225Y305512D02*
Y367717D01*
G01X-282284Y314567D02*
Y312992D01*
G01Y311418D02*
Y309843D01*
G01Y317717D02*
Y316142D01*
G01Y324016D02*
Y322441D01*
G01Y320866D02*
Y319292D01*
G01Y327166D02*
Y325591D01*
G01Y333465D02*
Y331890D01*
G01Y330315D02*
Y328740D01*
G01Y336615D02*
Y335040D01*
G01Y342914D02*
Y341339D01*
G01Y339764D02*
Y338189D01*
G01Y346063D02*
Y344489D01*
G01X-283721Y344252D02*
Y346300D01*
G01Y337953D02*
Y340000D01*
G01Y341103D02*
Y343150D01*
G01Y334803D02*
Y336851D01*
G01Y328504D02*
Y330552D01*
G01Y331654D02*
Y333701D01*
G01Y325355D02*
Y327402D01*
G01Y319055D02*
Y321103D01*
G01Y322205D02*
Y324252D01*
G01Y315906D02*
Y317953D01*
G01Y312756D02*
Y314803D01*
G01Y309607D02*
Y311654D01*
G01X-284252Y344784D02*
Y345768D01*
G01Y341634D02*
Y342618D01*
G01Y338485D02*
Y339469D01*
G01Y335335D02*
Y336319D01*
G01Y332185D02*
Y333170D01*
G01Y329036D02*
Y330020D01*
G01Y325886D02*
Y326870D01*
G01Y322737D02*
Y323721D01*
G01Y319587D02*
Y320571D01*
G01Y316437D02*
Y317422D01*
G01Y313288D02*
Y314272D01*
G01Y310138D02*
Y311122D01*
G01X-285329Y343504D02*
Y343898D01*
G01Y340355D02*
Y340748D01*
G01Y334055D02*
Y334449D01*
G01Y337205D02*
Y337599D01*
G01Y330906D02*
Y331300D01*
G01Y324605D02*
Y325000D01*
G01Y327756D02*
Y328150D01*
G01Y321456D02*
Y321851D01*
G01Y318307D02*
Y318701D01*
G01Y312007D02*
Y312402D01*
G01Y315158D02*
Y315552D01*
G01Y308857D02*
Y309252D01*
G01X-285546Y311024D02*
Y310237D01*
G01Y314174D02*
Y313386D01*
G01Y317323D02*
Y316536D01*
G01Y320473D02*
Y319685D01*
G01Y323622D02*
Y322835D01*
G01Y326772D02*
Y325985D01*
G01Y329922D02*
Y329134D01*
G01Y333071D02*
Y332284D01*
G01Y336221D02*
Y335433D01*
G01Y339370D02*
Y338583D01*
G01Y342520D02*
Y341733D01*
G01Y345670D02*
Y344882D01*
G01X-285573Y311024D02*
Y310237D01*
G01Y314174D02*
Y313386D01*
G01Y317323D02*
Y316536D01*
G01Y320473D02*
Y319685D01*
G01Y323622D02*
Y322835D01*
G01Y326772D02*
Y325985D01*
G01Y329922D02*
Y329134D01*
G01Y333071D02*
Y332284D01*
G01Y336221D02*
Y335433D01*
G01Y339370D02*
Y338583D01*
G01Y342520D02*
Y341733D01*
G01Y345670D02*
Y344882D01*
G01X-285582Y309320D02*
Y308791D01*
G01Y312470D02*
Y311940D01*
G01Y315619D02*
Y315090D01*
G01Y318769D02*
Y318240D01*
G01Y321918D02*
Y321389D01*
G01Y325068D02*
Y324539D01*
G01Y328218D02*
Y327689D01*
G01Y331367D02*
Y330838D01*
G01Y334517D02*
Y333988D01*
G01Y337666D02*
Y337137D01*
G01Y340816D02*
Y340287D01*
G01Y343966D02*
Y343437D01*
G01X-285587Y343435D02*
Y343967D01*
G01Y340286D02*
Y340817D01*
G01Y333987D02*
Y334518D01*
G01Y337136D02*
Y337668D01*
G01Y330837D02*
Y331368D01*
G01Y324538D02*
Y325069D01*
G01Y327687D02*
Y328219D01*
G01Y321388D02*
Y321920D01*
G01Y315089D02*
Y315620D01*
G01Y318239D02*
Y318770D01*
G01Y311939D02*
Y312471D01*
G01Y308790D02*
Y309321D01*
G01X-285627Y344882D02*
Y345670D01*
G01Y338583D02*
Y339370D01*
G01Y341733D02*
Y342520D01*
G01Y335433D02*
Y336221D01*
G01Y329134D02*
Y329922D01*
G01Y332284D02*
Y333071D01*
G01Y325985D02*
Y326772D01*
G01Y319685D02*
Y320473D01*
G01Y322835D02*
Y323622D01*
G01Y316536D02*
Y317323D01*
G01Y310237D02*
Y311024D01*
G01Y313386D02*
Y314174D01*
G01X-285827Y302363D02*
Y307618D01*
G01X-285850Y343365D02*
Y344037D01*
G01Y340215D02*
Y340888D01*
G01Y333916D02*
Y334589D01*
G01Y337066D02*
Y337738D01*
G01Y330766D02*
Y331439D01*
G01Y324467D02*
Y325140D01*
G01Y327617D02*
Y328289D01*
G01Y321318D02*
Y321990D01*
G01Y315018D02*
Y315691D01*
G01Y318168D02*
Y318840D01*
G01Y311869D02*
Y312541D01*
G01Y308719D02*
Y309392D01*
G01X-285877Y311024D02*
Y310237D01*
G01Y314174D02*
Y313386D01*
G01Y317323D02*
Y316536D01*
G01Y320473D02*
Y319685D01*
G01Y323622D02*
Y322835D01*
G01Y326772D02*
Y325985D01*
G01Y329922D02*
Y329134D01*
G01Y333071D02*
Y332284D01*
G01Y336221D02*
Y335433D01*
G01Y339370D02*
Y338583D01*
G01Y342520D02*
Y341733D01*
G01Y345670D02*
Y344882D01*
G01X-286344Y317717D02*
Y355512D01*
G01X-286614Y307618D02*
Y302363D01*
G01X-286617Y355512D02*
Y317717D01*
G01X-286688Y309449D02*
Y308662D01*
G01Y312599D02*
Y311811D01*
G01Y315748D02*
Y314961D01*
G01Y318898D02*
Y318111D01*
G01Y322048D02*
Y321260D01*
G01Y325197D02*
Y324410D01*
G01Y328347D02*
Y327559D01*
G01Y331496D02*
Y330709D01*
G01Y334646D02*
Y333859D01*
G01Y337796D02*
Y337008D01*
G01Y340945D02*
Y340158D01*
G01Y344095D02*
Y343307D01*
G01X-286934Y317717D02*
Y355512D01*
G01X-286986D02*
Y317717D01*
G01X-287160Y344882D02*
Y345670D01*
G01Y338583D02*
Y339370D01*
G01Y341733D02*
Y342520D01*
G01Y335433D02*
Y336221D01*
G01Y329134D02*
Y329922D01*
G01Y332284D02*
Y333071D01*
G01Y325985D02*
Y326772D01*
G01Y319685D02*
Y320473D01*
G01Y322835D02*
Y323622D01*
G01Y316536D02*
Y317323D01*
G01Y310237D02*
Y311024D01*
G01Y313386D02*
Y314174D01*
G01X-287425Y355512D02*
Y317717D01*
G01X-287872D02*
Y355512D01*
G01X-287992Y344252D02*
Y344784D01*
G01Y342618D02*
Y343150D01*
G01Y341103D02*
Y341634D01*
G01Y339469D02*
Y340000D01*
G01Y337953D02*
Y338485D01*
G01Y336319D02*
Y336851D01*
G01Y334803D02*
Y335335D01*
G01Y333170D02*
Y333701D01*
G01Y331654D02*
Y332185D01*
G01Y330020D02*
Y330552D01*
G01Y328504D02*
Y329036D01*
G01Y326870D02*
Y327402D01*
G01Y325355D02*
Y325886D01*
G01Y323721D02*
Y324252D01*
G01Y322205D02*
Y322737D01*
G01Y320571D02*
Y321103D01*
G01Y319055D02*
Y319587D01*
G01Y317422D02*
Y317953D01*
G01Y315906D02*
Y316437D01*
G01Y314272D02*
Y314803D01*
G01Y312756D02*
Y313288D01*
G01Y311122D02*
Y311654D01*
G01Y309607D02*
Y310138D01*
G01X-288878Y302363D02*
Y305906D01*
G01X-288977Y307618D02*
Y302363D01*
G01X-289725Y317717D02*
Y355512D01*
G01X-290085Y310909D02*
Y310351D01*
G01Y314059D02*
Y313501D01*
G01Y317209D02*
Y316650D01*
G01Y320358D02*
Y319800D01*
G01Y323508D02*
Y322950D01*
G01Y326657D02*
Y326099D01*
G01Y329807D02*
Y329249D01*
G01Y332957D02*
Y332398D01*
G01Y336106D02*
Y335548D01*
G01Y339256D02*
Y338698D01*
G01Y342405D02*
Y341847D01*
G01Y345555D02*
Y344997D01*
G01X-290119Y355512D02*
Y317717D01*
G01X-290510Y344882D02*
Y345670D01*
G01Y338583D02*
Y339370D01*
G01Y341733D02*
Y342520D01*
G01Y335433D02*
Y336221D01*
G01Y329134D02*
Y329922D01*
G01Y332284D02*
Y333071D01*
G01Y325985D02*
Y326772D01*
G01Y319685D02*
Y320473D01*
G01Y322835D02*
Y323622D01*
G01Y316536D02*
Y317323D01*
G01Y310237D02*
Y311024D01*
G01Y313386D02*
Y314174D01*
G01X-290539Y343468D02*
Y343934D01*
G01Y340319D02*
Y340784D01*
G01Y334020D02*
Y334485D01*
G01Y337169D02*
Y337635D01*
G01Y330870D02*
Y331335D01*
G01Y324571D02*
Y325036D01*
G01Y327720D02*
Y328186D01*
G01Y321421D02*
Y321887D01*
G01Y315122D02*
Y315587D01*
G01Y318272D02*
Y318737D01*
G01Y311972D02*
Y312438D01*
G01Y308823D02*
Y309288D01*
G01X-290840Y309449D02*
Y308662D01*
G01Y312599D02*
Y311811D01*
G01Y315748D02*
Y314961D01*
G01Y318898D02*
Y318111D01*
G01Y322048D02*
Y321260D01*
G01Y325197D02*
Y324410D01*
G01Y328347D02*
Y327559D01*
G01Y331496D02*
Y330709D01*
G01Y334646D02*
Y333859D01*
G01Y337796D02*
Y337008D01*
G01Y340945D02*
Y340158D01*
G01Y344095D02*
Y343307D01*
G01X-291057D02*
Y344095D01*
G01Y340158D02*
Y340945D01*
G01Y333859D02*
Y334646D01*
G01Y337008D02*
Y337796D01*
G01Y330709D02*
Y331496D01*
G01Y324410D02*
Y325197D01*
G01Y327559D02*
Y328347D01*
G01Y321260D02*
Y322048D01*
G01Y314961D02*
Y315748D01*
G01Y318111D02*
Y318898D01*
G01Y311811D02*
Y312599D01*
G01Y308662D02*
Y309449D01*
G01X-291197D02*
Y308662D01*
G01Y312599D02*
Y311811D01*
G01Y315748D02*
Y314961D01*
G01Y318898D02*
Y318111D01*
G01Y322048D02*
Y321260D01*
G01Y325197D02*
Y324410D01*
G01Y328347D02*
Y327559D01*
G01Y331496D02*
Y330709D01*
G01Y334646D02*
Y333859D01*
G01Y337796D02*
Y337008D01*
G01Y340945D02*
Y340158D01*
G01Y344095D02*
Y343307D01*
G01X-291380D02*
Y344095D01*
G01Y340158D02*
Y340945D01*
G01Y333859D02*
Y334646D01*
G01Y337008D02*
Y337796D01*
G01Y330709D02*
Y331496D01*
G01Y324410D02*
Y325197D01*
G01Y327559D02*
Y328347D01*
G01Y321260D02*
Y322048D01*
G01Y314961D02*
Y315748D01*
G01Y318111D02*
Y318898D01*
G01Y311811D02*
Y312599D01*
G01Y308662D02*
Y309449D01*
G01X-291414Y309299D02*
Y308812D01*
G01Y312449D02*
Y311961D01*
G01Y315598D02*
Y315111D01*
G01Y318748D02*
Y318261D01*
G01Y321898D02*
Y321410D01*
G01Y325047D02*
Y324560D01*
G01Y328197D02*
Y327709D01*
G01Y331346D02*
Y330859D01*
G01Y334496D02*
Y334009D01*
G01Y337646D02*
Y337158D01*
G01Y340795D02*
Y340308D01*
G01Y343945D02*
Y343457D01*
G01X-291438Y343452D02*
Y343950D01*
G01Y340303D02*
Y340800D01*
G01Y334003D02*
Y334501D01*
G01Y337153D02*
Y337651D01*
G01Y330854D02*
Y331352D01*
G01Y324555D02*
Y325052D01*
G01Y327704D02*
Y328202D01*
G01Y321405D02*
Y321903D01*
G01Y315106D02*
Y315603D01*
G01Y318255D02*
Y318753D01*
G01Y311956D02*
Y312454D01*
G01Y308807D02*
Y309304D01*
G01X-291535Y311024D02*
Y310237D01*
G01Y314174D02*
Y313386D01*
G01Y317323D02*
Y316536D01*
G01Y320473D02*
Y319685D01*
G01Y323622D02*
Y322835D01*
G01Y326772D02*
Y325985D01*
G01Y329922D02*
Y329134D01*
G01Y333071D02*
Y332284D01*
G01Y336221D02*
Y335433D01*
G01Y339370D02*
Y338583D01*
G01Y342520D02*
Y341733D01*
G01Y345670D02*
Y344882D01*
G01X-291637Y309335D02*
Y308776D01*
G01Y312484D02*
Y311926D01*
G01Y315634D02*
Y315076D01*
G01Y318783D02*
Y318225D01*
G01Y321933D02*
Y321375D01*
G01Y325083D02*
Y324524D01*
G01Y328232D02*
Y327674D01*
G01Y331382D02*
Y330824D01*
G01Y334531D02*
Y333973D01*
G01Y337681D02*
Y337123D01*
G01Y340831D02*
Y340272D01*
G01Y343980D02*
Y343422D01*
G01X-291879Y344988D02*
Y345564D01*
G01Y338689D02*
Y339265D01*
G01Y341838D02*
Y342415D01*
G01Y335539D02*
Y336115D01*
G01Y329240D02*
Y329816D01*
G01Y332389D02*
Y332966D01*
G01Y326090D02*
Y326666D01*
G01Y319791D02*
Y320367D01*
G01Y322940D02*
Y323517D01*
G01Y316641D02*
Y317218D01*
G01Y310342D02*
Y310918D01*
G01Y313492D02*
Y314068D01*
G01X-292677Y317717D02*
Y355512D01*
G01X-293070D02*
Y317717D01*
G01X-293898Y310138D02*
Y309607D01*
G01Y314803D02*
Y314272D01*
G01Y313288D02*
Y312756D01*
G01Y311654D02*
Y311122D01*
G01Y319587D02*
Y319055D01*
G01Y317953D02*
Y317422D01*
G01Y316437D02*
Y315906D01*
G01Y324252D02*
Y323721D01*
G01Y322737D02*
Y322205D01*
G01Y321103D02*
Y320571D01*
G01Y329036D02*
Y328504D01*
G01Y327402D02*
Y326870D01*
G01Y325886D02*
Y325355D01*
G01Y333701D02*
Y333170D01*
G01Y332185D02*
Y331654D01*
G01Y330552D02*
Y330020D01*
G01Y338485D02*
Y337953D01*
G01Y336851D02*
Y336319D01*
G01Y335335D02*
Y334803D01*
G01Y343150D02*
Y342618D01*
G01Y341634D02*
Y341103D01*
G01Y340000D02*
Y339469D01*
G01Y344784D02*
Y344252D01*
G01X-294488Y307618D02*
Y302363D01*
G01X-295010Y355512D02*
Y317717D01*
G01X-295276Y307618D02*
Y302363D01*
G01X-295456Y317717D02*
Y355512D01*
G01X-295896Y317717D02*
Y355512D01*
G01X-295925Y303347D02*
Y302363D01*
G01X-295948Y355512D02*
Y317717D01*
G01X-296418Y303347D02*
Y304331D01*
G01X-296720Y355512D02*
Y317717D01*
G01X-301240Y303476D02*
Y302363D01*
G01X-302028Y303347D02*
Y302363D01*
G01X-302422D02*
Y303347D01*
G01X-303504D02*
Y302363D01*
G01X-303603D02*
Y303347D01*
G01X-303622Y367717D02*
Y305512D01*
G01X-304331Y309449D02*
Y308662D01*
G01Y312599D02*
Y311811D01*
G01Y315748D02*
Y314961D01*
G01Y318898D02*
Y318111D01*
G01Y322048D02*
Y321260D01*
G01Y325197D02*
Y324410D01*
G01Y328347D02*
Y327559D01*
G01Y331496D02*
Y330709D01*
G01Y334646D02*
Y333859D01*
G01Y337796D02*
Y337008D01*
G01Y340945D02*
Y340158D01*
G01Y344095D02*
Y343307D01*
G01X-304799Y311024D02*
Y310237D01*
G01Y314174D02*
Y313386D01*
G01Y317323D02*
Y316536D01*
G01Y320473D02*
Y319685D01*
G01Y323622D02*
Y322835D01*
G01Y326772D02*
Y325985D01*
G01Y329922D02*
Y329134D01*
G01Y333071D02*
Y332284D01*
G01Y336221D02*
Y335433D01*
G01Y339370D02*
Y338583D01*
G01Y342520D02*
Y341733D01*
G01Y345670D02*
Y344882D01*
G01X-304922Y343307D02*
Y344095D01*
G01Y340158D02*
Y340945D01*
G01Y333859D02*
Y334646D01*
G01Y337008D02*
Y337796D01*
G01Y330709D02*
Y331496D01*
G01Y324410D02*
Y325197D01*
G01Y327559D02*
Y328347D01*
G01Y321260D02*
Y322048D01*
G01Y314961D02*
Y315748D01*
G01Y318111D02*
Y318898D01*
G01Y311811D02*
Y312599D01*
G01Y308662D02*
Y309449D01*
G01X-305233Y344882D02*
Y345670D01*
G01Y338583D02*
Y339370D01*
G01Y341733D02*
Y342520D01*
G01Y335433D02*
Y336221D01*
G01Y329134D02*
Y329922D01*
G01Y332284D02*
Y333071D01*
G01Y325985D02*
Y326772D01*
G01Y319685D02*
Y320473D01*
G01Y322835D02*
Y323622D01*
G01Y316536D02*
Y317323D01*
G01Y310237D02*
Y311024D01*
G01Y313386D02*
Y314174D01*
G01X-305457Y344882D02*
Y345670D01*
G01Y338583D02*
Y339370D01*
G01Y341733D02*
Y342520D01*
G01Y335433D02*
Y336221D01*
G01Y329134D02*
Y329922D01*
G01Y332284D02*
Y333071D01*
G01Y325985D02*
Y326772D01*
G01Y319685D02*
Y320473D01*
G01Y322835D02*
Y323622D01*
G01Y316536D02*
Y317323D01*
G01Y310237D02*
Y311024D01*
G01Y313386D02*
Y314174D01*
G01X-305473Y344784D02*
Y345768D01*
G01Y338485D02*
Y339469D01*
G01Y341634D02*
Y342618D01*
G01Y335335D02*
Y336319D01*
G01Y329036D02*
Y330020D01*
G01Y332185D02*
Y333170D01*
G01Y325886D02*
Y326870D01*
G01Y319587D02*
Y320571D01*
G01Y322737D02*
Y323721D01*
G01Y316437D02*
Y317422D01*
G01Y313288D02*
Y314272D01*
G01Y310138D02*
Y311122D01*
G01X-305512Y309449D02*
Y308662D01*
G01Y312599D02*
Y311811D01*
G01Y315748D02*
Y314961D01*
G01Y318898D02*
Y318111D01*
G01Y322048D02*
Y321260D01*
G01Y325197D02*
Y324410D01*
G01Y328347D02*
Y327559D01*
G01Y331496D02*
Y330709D01*
G01Y334646D02*
Y333859D01*
G01Y337796D02*
Y337008D01*
G01Y340945D02*
Y340158D01*
G01Y344095D02*
Y343307D01*
G01X-305788Y344784D02*
Y345768D01*
G01Y338485D02*
Y339469D01*
G01Y341634D02*
Y342618D01*
G01Y335335D02*
Y336319D01*
G01Y329036D02*
Y330020D01*
G01Y332185D02*
Y333170D01*
G01Y325886D02*
Y326870D01*
G01Y319587D02*
Y320571D01*
G01Y322737D02*
Y323721D01*
G01Y316437D02*
Y317422D01*
G01Y313288D02*
Y314272D01*
G01Y310138D02*
Y311122D01*
G01X-305890Y311024D02*
Y310237D01*
G01Y314174D02*
Y313386D01*
G01Y317323D02*
Y316536D01*
G01Y320473D02*
Y319685D01*
G01Y323622D02*
Y322835D01*
G01Y326772D02*
Y325985D01*
G01Y329922D02*
Y329134D01*
G01Y333071D02*
Y332284D01*
G01Y336221D02*
Y335433D01*
G01Y339370D02*
Y338583D01*
G01Y342520D02*
Y341733D01*
G01Y345670D02*
Y344882D01*
G01X-306103Y309449D02*
Y308662D01*
G01Y312599D02*
Y311811D01*
G01Y314272D02*
Y313288D01*
G01Y311122D02*
Y310138D01*
G01Y315748D02*
Y314961D01*
G01Y318898D02*
Y318111D01*
G01Y317422D02*
Y316437D01*
G01Y322048D02*
Y321260D01*
G01Y320571D02*
Y319587D01*
G01Y323721D02*
Y322737D01*
G01Y325197D02*
Y324410D01*
G01Y328347D02*
Y327559D01*
G01Y326870D02*
Y325886D01*
G01Y331496D02*
Y330709D01*
G01Y330020D02*
Y329036D01*
G01Y333170D02*
Y332185D01*
G01Y334646D02*
Y333859D01*
G01Y337796D02*
Y337008D01*
G01Y336319D02*
Y335335D01*
G01Y340945D02*
Y340158D01*
G01Y339469D02*
Y338485D01*
G01Y342618D02*
Y341634D01*
G01Y344095D02*
Y343307D01*
G01Y345768D02*
Y344784D01*
G01X-306142Y344891D02*
Y345661D01*
G01Y338592D02*
Y339361D01*
G01Y341742D02*
Y342511D01*
G01Y335442D02*
Y336212D01*
G01Y329143D02*
Y329913D01*
G01Y332293D02*
Y333062D01*
G01Y325994D02*
Y326763D01*
G01Y319694D02*
Y320464D01*
G01Y322844D02*
Y323613D01*
G01Y316545D02*
Y317314D01*
G01Y310246D02*
Y311015D01*
G01Y313395D02*
Y314165D01*
G01X-306244Y310912D02*
Y310348D01*
G01Y314062D02*
Y313498D01*
G01Y317211D02*
Y316647D01*
G01Y320361D02*
Y319797D01*
G01Y323511D02*
Y322946D01*
G01Y326660D02*
Y326096D01*
G01Y329810D02*
Y329246D01*
G01Y332959D02*
Y332395D01*
G01Y336109D02*
Y335545D01*
G01Y339259D02*
Y338694D01*
G01Y342408D02*
Y341844D01*
G01Y345558D02*
Y344994D01*
G01X-306500Y338780D02*
Y339174D01*
G01Y341929D02*
Y342323D01*
G01Y335630D02*
Y336024D01*
G01Y329331D02*
Y329725D01*
G01Y332481D02*
Y332874D01*
G01Y326181D02*
Y326575D01*
G01Y319882D02*
Y320276D01*
G01Y323032D02*
Y323426D01*
G01Y316733D02*
Y317126D01*
G01Y313583D02*
Y313977D01*
G01Y310433D02*
Y310827D01*
G01X-306693Y309449D02*
Y308662D01*
G01Y312599D02*
Y311811D01*
G01Y315748D02*
Y314961D01*
G01Y318898D02*
Y318111D01*
G01Y322048D02*
Y321260D01*
G01Y325197D02*
Y324410D01*
G01Y328347D02*
Y327559D01*
G01Y331496D02*
Y330709D01*
G01Y334646D02*
Y333859D01*
G01Y337796D02*
Y337008D01*
G01Y340945D02*
Y340158D01*
G01Y344095D02*
Y343307D01*
G01X-307351Y309449D02*
Y308662D01*
G01Y312599D02*
Y311811D01*
G01Y315748D02*
Y314961D01*
G01Y318898D02*
Y318111D01*
G01Y322048D02*
Y321260D01*
G01Y325197D02*
Y324410D01*
G01Y328347D02*
Y327559D01*
G01Y331496D02*
Y330709D01*
G01Y334646D02*
Y333859D01*
G01Y337796D02*
Y337008D01*
G01Y340945D02*
Y340158D01*
G01Y344095D02*
Y343307D01*
G01X-307605D02*
Y344095D01*
G01Y340158D02*
Y340945D01*
G01Y333859D02*
Y334646D01*
G01Y337008D02*
Y337796D01*
G01Y330709D02*
Y331496D01*
G01Y324410D02*
Y325197D01*
G01Y327559D02*
Y328347D01*
G01Y321260D02*
Y322048D01*
G01Y314961D02*
Y315748D01*
G01Y318111D02*
Y318898D01*
G01Y311811D02*
Y312599D01*
G01Y308662D02*
Y309449D01*
G01X-307628Y343307D02*
Y344095D01*
G01Y340158D02*
Y340945D01*
G01Y333859D02*
Y334646D01*
G01Y337008D02*
Y337796D01*
G01Y330709D02*
Y331496D01*
G01Y324410D02*
Y325197D01*
G01Y327559D02*
Y328347D01*
G01Y321260D02*
Y322048D01*
G01Y314961D02*
Y315748D01*
G01Y318111D02*
Y318898D01*
G01Y311811D02*
Y312599D01*
G01Y308662D02*
Y309449D01*
G01X-307874Y342618D02*
Y344784D01*
G01Y339469D02*
Y341634D01*
G01Y333170D02*
Y335335D01*
G01Y336319D02*
Y338485D01*
G01Y330020D02*
Y332185D01*
G01Y323721D02*
Y325886D01*
G01Y326870D02*
Y329036D01*
G01Y320571D02*
Y322737D01*
G01Y314272D02*
Y316437D01*
G01Y317422D02*
Y319587D01*
G01Y311122D02*
Y313288D01*
G01Y302363D02*
Y310138D01*
G01X-308657Y310827D02*
Y310433D01*
G01Y313977D02*
Y313583D01*
G01Y317126D02*
Y316733D01*
G01Y320276D02*
Y319882D01*
G01Y323426D02*
Y323032D01*
G01Y326575D02*
Y326181D01*
G01Y329725D02*
Y329331D01*
G01Y332874D02*
Y332481D01*
G01Y336024D02*
Y335630D01*
G01Y339174D02*
Y338780D01*
G01Y342323D02*
Y341929D01*
G01X-308662Y309607D02*
Y302363D01*
G01Y312756D02*
Y311654D01*
G01Y315906D02*
Y314803D01*
G01Y319055D02*
Y317953D01*
G01Y322205D02*
Y321103D01*
G01Y325355D02*
Y324252D01*
G01Y328504D02*
Y327402D01*
G01Y331654D02*
Y330552D01*
G01Y334803D02*
Y333701D01*
G01Y337953D02*
Y336851D01*
G01Y341103D02*
Y340000D01*
G01Y344252D02*
Y343150D01*
G01X-308783Y309449D02*
Y308662D01*
G01Y312599D02*
Y311811D01*
G01Y315748D02*
Y314961D01*
G01Y318898D02*
Y318111D01*
G01Y322048D02*
Y321260D01*
G01Y325197D02*
Y324410D01*
G01Y328347D02*
Y327559D01*
G01Y331496D02*
Y330709D01*
G01Y334646D02*
Y333859D01*
G01Y337796D02*
Y337008D01*
G01Y340945D02*
Y340158D01*
G01Y344095D02*
Y343307D01*
G01X-308888Y344882D02*
Y345670D01*
G01Y338583D02*
Y339370D01*
G01Y341733D02*
Y342520D01*
G01Y335433D02*
Y336221D01*
G01Y329134D02*
Y329922D01*
G01Y332284D02*
Y333071D01*
G01Y325985D02*
Y326772D01*
G01Y319685D02*
Y320473D01*
G01Y322835D02*
Y323622D01*
G01Y316536D02*
Y317323D01*
G01Y310237D02*
Y311024D01*
G01Y313386D02*
Y314174D01*
G01X-308901Y343307D02*
Y344095D01*
G01Y340158D02*
Y340945D01*
G01Y333859D02*
Y334646D01*
G01Y337008D02*
Y337796D01*
G01Y330709D02*
Y331496D01*
G01Y324410D02*
Y325197D01*
G01Y327559D02*
Y328347D01*
G01Y321260D02*
Y322048D01*
G01Y314961D02*
Y315748D01*
G01Y318111D02*
Y318898D01*
G01Y311811D02*
Y312599D01*
G01Y308662D02*
Y309449D01*
G01X-308913Y344994D02*
Y345558D01*
G01Y338694D02*
Y339259D01*
G01Y341844D02*
Y342408D01*
G01Y335545D02*
Y336109D01*
G01Y329246D02*
Y329810D01*
G01Y332395D02*
Y332959D01*
G01Y326096D02*
Y326660D01*
G01Y319797D02*
Y320361D01*
G01Y322946D02*
Y323511D01*
G01Y316647D02*
Y317211D01*
G01Y310348D02*
Y310912D01*
G01Y313498D02*
Y314062D01*
G01X-308969Y344882D02*
Y345670D01*
G01Y338583D02*
Y339370D01*
G01Y341733D02*
Y342520D01*
G01Y335433D02*
Y336221D01*
G01Y329134D02*
Y329922D01*
G01Y332284D02*
Y333071D01*
G01Y325985D02*
Y326772D01*
G01Y319685D02*
Y320473D01*
G01Y322835D02*
Y323622D01*
G01Y316536D02*
Y317323D01*
G01Y310237D02*
Y311024D01*
G01Y313386D02*
Y314174D01*
G01X-309003Y311024D02*
Y310237D01*
G01Y314174D02*
Y313386D01*
G01Y317323D02*
Y316536D01*
G01Y320473D02*
Y319685D01*
G01Y323622D02*
Y322835D01*
G01Y326772D02*
Y325985D01*
G01Y329922D02*
Y329134D01*
G01Y333071D02*
Y332284D01*
G01Y336221D02*
Y335433D01*
G01Y339370D02*
Y338583D01*
G01Y342520D02*
Y341733D01*
G01Y345670D02*
Y344882D01*
G01X-309016Y311015D02*
Y310246D01*
G01Y314165D02*
Y313395D01*
G01Y317314D02*
Y316545D01*
G01Y320464D02*
Y319694D01*
G01Y323613D02*
Y322844D01*
G01Y326763D02*
Y325994D01*
G01Y329913D02*
Y329143D01*
G01Y333062D02*
Y332293D01*
G01Y336212D02*
Y335442D01*
G01Y339361D02*
Y338592D01*
G01Y342511D02*
Y341742D01*
G01Y345661D02*
Y344891D01*
G01X-309055Y311024D02*
Y310237D01*
G01Y314174D02*
Y313386D01*
G01Y317323D02*
Y316536D01*
G01Y320473D02*
Y319685D01*
G01Y323622D02*
Y322835D01*
G01Y326772D02*
Y325985D01*
G01Y329922D02*
Y329134D01*
G01Y333071D02*
Y332284D01*
G01Y336221D02*
Y335433D01*
G01Y339370D02*
Y338583D01*
G01Y342520D02*
Y341733D01*
G01Y345670D02*
Y344882D01*
G01X-309076D02*
Y345670D01*
G01Y338583D02*
Y339370D01*
G01Y341733D02*
Y342520D01*
G01Y335433D02*
Y336221D01*
G01Y329134D02*
Y329922D01*
G01Y332284D02*
Y333071D01*
G01Y325985D02*
Y326772D01*
G01Y319685D02*
Y320473D01*
G01Y322835D02*
Y323622D01*
G01Y316536D02*
Y317323D01*
G01Y310237D02*
Y311024D01*
G01Y313386D02*
Y314174D01*
G01X-309114Y314272D02*
Y313288D01*
G01Y311122D02*
Y310138D01*
G01Y317422D02*
Y316437D01*
G01Y320571D02*
Y319587D01*
G01Y323721D02*
Y322737D01*
G01Y326870D02*
Y325886D01*
G01Y330020D02*
Y329036D01*
G01Y333170D02*
Y332185D01*
G01Y336319D02*
Y335335D01*
G01Y339469D02*
Y338485D01*
G01Y342618D02*
Y341634D01*
G01Y345768D02*
Y344784D01*
G01X-309370Y344882D02*
Y345670D01*
G01Y338583D02*
Y339370D01*
G01Y341733D02*
Y342520D01*
G01Y335433D02*
Y336221D01*
G01Y329134D02*
Y329922D01*
G01Y332284D02*
Y333071D01*
G01Y325985D02*
Y326772D01*
G01Y319685D02*
Y320473D01*
G01Y322835D02*
Y323622D01*
G01Y316536D02*
Y317323D01*
G01Y310237D02*
Y311024D01*
G01Y313386D02*
Y314174D01*
G01X-309429Y344784D02*
Y345768D01*
G01Y338485D02*
Y339469D01*
G01Y341634D02*
Y342618D01*
G01Y335335D02*
Y336319D01*
G01Y329036D02*
Y330020D01*
G01Y332185D02*
Y333170D01*
G01Y325886D02*
Y326870D01*
G01Y319587D02*
Y320571D01*
G01Y322737D02*
Y323721D01*
G01Y316437D02*
Y317422D01*
G01Y313288D02*
Y314272D01*
G01Y310138D02*
Y311122D01*
G01X-309449Y309607D02*
Y302363D01*
G01Y311024D02*
Y310237D01*
G01Y314174D02*
Y313386D01*
G01Y312756D02*
Y311654D01*
G01Y317323D02*
Y316536D01*
G01Y315906D02*
Y314803D01*
G01Y319055D02*
Y317953D01*
G01Y320473D02*
Y319685D01*
G01Y323622D02*
Y322835D01*
G01Y322205D02*
Y321103D01*
G01Y326772D02*
Y325985D01*
G01Y325355D02*
Y324252D01*
G01Y328504D02*
Y327402D01*
G01Y329922D02*
Y329134D01*
G01Y333071D02*
Y332284D01*
G01Y331654D02*
Y330552D01*
G01Y336221D02*
Y335433D01*
G01Y334803D02*
Y333701D01*
G01Y337953D02*
Y336851D01*
G01Y339370D02*
Y338583D01*
G01Y342520D02*
Y341733D01*
G01Y341103D02*
Y340000D01*
G01Y345670D02*
Y344882D01*
G01Y344252D02*
Y343150D01*
G01X-309685Y344882D02*
Y345670D01*
G01Y338583D02*
Y339370D01*
G01Y341733D02*
Y342520D01*
G01Y335433D02*
Y336221D01*
G01Y329134D02*
Y329922D01*
G01Y332284D02*
Y333071D01*
G01Y325985D02*
Y326772D01*
G01Y319685D02*
Y320473D01*
G01Y322835D02*
Y323622D01*
G01Y316536D02*
Y317323D01*
G01Y310237D02*
Y311024D01*
G01Y313386D02*
Y314174D01*
G01X-309722Y309449D02*
Y308662D01*
G01Y312599D02*
Y311811D01*
G01Y315748D02*
Y314961D01*
G01Y318898D02*
Y318111D01*
G01Y322048D02*
Y321260D01*
G01Y325197D02*
Y324410D01*
G01Y328347D02*
Y327559D01*
G01Y331496D02*
Y330709D01*
G01Y334646D02*
Y333859D01*
G01Y337796D02*
Y337008D01*
G01Y340945D02*
Y340158D01*
G01Y344095D02*
Y343307D01*
G01X-309862Y311024D02*
Y310237D01*
G01Y314174D02*
Y313386D01*
G01Y317323D02*
Y316536D01*
G01Y320473D02*
Y319685D01*
G01Y323622D02*
Y322835D01*
G01Y326772D02*
Y325985D01*
G01Y329922D02*
Y329134D01*
G01Y333071D02*
Y332284D01*
G01Y336221D02*
Y335433D01*
G01Y339370D02*
Y338583D01*
G01Y342520D02*
Y341733D01*
G01Y345670D02*
Y344882D01*
G01X-309960Y343307D02*
Y344095D01*
G01Y340158D02*
Y340945D01*
G01Y333859D02*
Y334646D01*
G01Y337008D02*
Y337796D01*
G01Y330709D02*
Y331496D01*
G01Y324410D02*
Y325197D01*
G01Y327559D02*
Y328347D01*
G01Y321260D02*
Y322048D01*
G01Y314961D02*
Y315748D01*
G01Y318111D02*
Y318898D01*
G01Y311811D02*
Y312599D01*
G01Y308662D02*
Y309449D01*
G01X-310000Y343307D02*
Y344095D01*
G01Y340158D02*
Y340945D01*
G01Y333859D02*
Y334646D01*
G01Y337008D02*
Y337796D01*
G01Y330709D02*
Y331496D01*
G01Y324410D02*
Y325197D01*
G01Y327559D02*
Y328347D01*
G01Y321260D02*
Y322048D01*
G01Y314961D02*
Y315748D01*
G01Y318111D02*
Y318898D01*
G01Y311811D02*
Y312599D01*
G01Y308662D02*
Y309449D01*
G01X-310040Y311024D02*
Y310237D01*
G01Y314174D02*
Y313386D01*
G01Y317323D02*
Y316536D01*
G01Y320473D02*
Y319685D01*
G01Y323622D02*
Y322835D01*
G01Y326772D02*
Y325985D01*
G01Y329922D02*
Y329134D01*
G01Y333071D02*
Y332284D01*
G01Y336221D02*
Y335433D01*
G01Y339370D02*
Y338583D01*
G01Y342520D02*
Y341733D01*
G01Y345670D02*
Y344882D01*
G01X-310276D02*
Y345670D01*
G01Y338583D02*
Y339370D01*
G01Y341733D02*
Y342520D01*
G01Y335433D02*
Y336221D01*
G01Y329134D02*
Y329922D01*
G01Y332284D02*
Y333071D01*
G01Y325985D02*
Y326772D01*
G01Y319685D02*
Y320473D01*
G01Y322835D02*
Y323622D01*
G01Y316536D02*
Y317323D01*
G01Y310237D02*
Y311024D01*
G01Y313386D02*
Y314174D01*
G01X-311378Y344882D02*
Y345670D01*
G01Y338583D02*
Y339370D01*
G01Y341733D02*
Y342520D01*
G01Y335433D02*
Y336221D01*
G01Y329134D02*
Y329922D01*
G01Y332284D02*
Y333071D01*
G01Y325985D02*
Y326772D01*
G01Y319685D02*
Y320473D01*
G01Y322835D02*
Y323622D01*
G01Y316536D02*
Y317323D01*
G01Y310237D02*
Y311024D01*
G01Y313386D02*
Y314174D01*
G01X-311418Y309843D02*
Y308268D01*
G01Y312992D02*
Y311418D01*
G01Y311024D02*
Y310237D01*
G01Y314174D02*
Y313386D01*
G01Y319292D02*
Y317717D01*
G01Y316142D02*
Y314567D01*
G01Y317323D02*
Y316536D01*
G01Y322441D02*
Y320866D01*
G01Y320473D02*
Y319685D01*
G01Y323622D02*
Y322835D01*
G01Y328740D02*
Y327166D01*
G01Y325591D02*
Y324016D01*
G01Y326772D02*
Y325985D01*
G01Y331890D02*
Y330315D01*
G01Y329922D02*
Y329134D01*
G01Y333071D02*
Y332284D01*
G01Y338189D02*
Y336615D01*
G01Y335040D02*
Y333465D01*
G01Y336221D02*
Y335433D01*
G01Y341339D02*
Y339764D01*
G01Y339370D02*
Y338583D01*
G01Y342520D02*
Y341733D01*
G01Y344489D02*
Y342914D01*
G01Y345670D02*
Y344882D01*
G01X-311792Y311024D02*
Y310237D01*
G01Y314174D02*
Y313386D01*
G01Y317323D02*
Y316536D01*
G01Y320473D02*
Y319685D01*
G01Y323622D02*
Y322835D01*
G01Y326772D02*
Y325985D01*
G01Y329922D02*
Y329134D01*
G01Y333071D02*
Y332284D01*
G01Y336221D02*
Y335433D01*
G01Y339370D02*
Y338583D01*
G01Y342520D02*
Y341733D01*
G01Y345670D02*
Y344882D01*
G01X-311890Y309449D02*
Y308662D01*
G01Y312599D02*
Y311811D01*
G01Y315748D02*
Y314961D01*
G01Y318898D02*
Y318111D01*
G01Y322048D02*
Y321260D01*
G01Y325197D02*
Y324410D01*
G01Y328347D02*
Y327559D01*
G01Y331496D02*
Y330709D01*
G01Y334646D02*
Y333859D01*
G01Y337796D02*
Y337008D01*
G01Y340945D02*
Y340158D01*
G01Y344095D02*
Y343307D01*
G01X-311969Y344882D02*
Y345670D01*
G01Y338583D02*
Y339370D01*
G01Y341733D02*
Y342520D01*
G01Y335433D02*
Y336221D01*
G01Y329134D02*
Y329922D01*
G01Y332284D02*
Y333071D01*
G01Y325985D02*
Y326772D01*
G01Y319685D02*
Y320473D01*
G01Y322835D02*
Y323622D01*
G01Y316536D02*
Y317323D01*
G01Y310237D02*
Y311024D01*
G01Y313386D02*
Y314174D01*
G01X-312008Y343307D02*
Y344095D01*
G01Y340158D02*
Y340945D01*
G01Y333859D02*
Y334646D01*
G01Y337008D02*
Y337796D01*
G01Y330709D02*
Y331496D01*
G01Y324410D02*
Y325197D01*
G01Y327559D02*
Y328347D01*
G01Y321260D02*
Y322048D01*
G01Y314961D02*
Y315748D01*
G01Y318111D02*
Y318898D01*
G01Y311811D02*
Y312599D01*
G01Y308662D02*
Y309449D01*
G01X-312205Y311024D02*
Y310237D01*
G01Y314174D02*
Y313386D01*
G01Y317323D02*
Y316536D01*
G01Y320473D02*
Y319685D01*
G01Y323622D02*
Y322835D01*
G01Y326772D02*
Y325985D01*
G01Y329922D02*
Y329134D01*
G01Y333071D02*
Y332284D01*
G01Y336221D02*
Y335433D01*
G01Y339370D02*
Y338583D01*
G01Y342520D02*
Y341733D01*
G01Y345670D02*
Y344882D01*
G01X-312284Y311122D02*
Y310138D01*
G01Y314272D02*
Y313288D01*
G01Y317422D02*
Y316437D01*
G01Y320571D02*
Y319587D01*
G01Y323721D02*
Y322737D01*
G01Y326870D02*
Y325886D01*
G01Y330020D02*
Y329036D01*
G01Y333170D02*
Y332185D01*
G01Y336319D02*
Y335335D01*
G01Y339469D02*
Y338485D01*
G01Y342618D02*
Y341634D01*
G01Y345768D02*
Y344784D01*
G01X-312796Y309449D02*
Y308662D01*
G01Y312599D02*
Y311811D01*
G01Y315748D02*
Y314961D01*
G01Y318898D02*
Y318111D01*
G01Y322048D02*
Y321260D01*
G01Y325197D02*
Y324410D01*
G01Y328347D02*
Y327559D01*
G01Y331496D02*
Y330709D01*
G01Y334646D02*
Y333859D01*
G01Y337796D02*
Y337008D01*
G01Y340945D02*
Y340158D01*
G01Y344095D02*
Y343307D01*
G01X-312815Y311654D02*
Y309607D01*
G01Y314803D02*
Y312756D01*
G01Y317953D02*
Y315906D01*
G01Y321103D02*
Y319055D01*
G01Y324252D02*
Y322205D01*
G01Y327402D02*
Y325355D01*
G01Y330552D02*
Y328504D01*
G01Y333701D02*
Y331654D01*
G01Y336851D02*
Y334803D01*
G01Y340000D02*
Y337953D01*
G01Y343150D02*
Y341103D01*
G01Y346300D02*
Y344252D01*
G01X-312992Y308563D02*
Y309548D01*
G01Y312697D02*
Y311713D01*
G01Y315847D02*
Y314863D01*
G01Y318996D02*
Y318012D01*
G01Y322146D02*
Y321162D01*
G01Y325296D02*
Y324311D01*
G01Y328445D02*
Y327461D01*
G01Y331595D02*
Y330611D01*
G01Y334744D02*
Y333760D01*
G01Y337894D02*
Y336910D01*
G01Y341044D02*
Y340059D01*
G01Y344193D02*
Y343209D01*
G01X-313110Y311024D02*
Y310237D01*
G01Y314174D02*
Y313386D01*
G01Y317323D02*
Y316536D01*
G01Y320473D02*
Y319685D01*
G01Y323622D02*
Y322835D01*
G01Y326772D02*
Y325985D01*
G01Y329922D02*
Y329134D01*
G01Y333071D02*
Y332284D01*
G01Y336221D02*
Y335433D01*
G01Y339370D02*
Y338583D01*
G01Y342520D02*
Y341733D01*
G01Y345670D02*
Y344882D01*
G01X-313386Y370866D02*
Y302363D01*
G01X-313701Y311024D02*
Y310237D01*
G01Y314174D02*
Y313386D01*
G01Y317323D02*
Y316536D01*
G01Y320473D02*
Y319685D01*
G01Y323622D02*
Y322835D01*
G01Y326772D02*
Y325985D01*
G01Y329922D02*
Y329134D01*
G01Y333071D02*
Y332284D01*
G01Y336221D02*
Y335433D01*
G01Y339370D02*
Y338583D01*
G01Y342520D02*
Y341733D01*
G01Y345670D02*
Y344882D01*
G01X-313977Y309449D02*
Y308662D01*
G01Y312599D02*
Y311811D01*
G01Y315748D02*
Y314961D01*
G01Y318898D02*
Y318111D01*
G01Y322048D02*
Y321260D01*
G01Y325197D02*
Y324410D01*
G01Y328347D02*
Y327559D01*
G01Y331496D02*
Y330709D01*
G01Y334646D02*
Y333859D01*
G01Y337796D02*
Y337008D01*
G01Y340945D02*
Y340158D01*
G01Y344095D02*
Y343307D01*
G01X-314961Y367717D02*
Y305512D01*
G01X-285698Y345670D02*
X-285697Y344882D01*
G01X-285698Y342520D02*
X-285697Y341733D01*
G01X-285698Y339370D02*
X-285697Y338583D01*
G01X-285698Y336221D02*
X-285697Y335433D01*
G01X-285698Y333071D02*
X-285697Y332284D01*
G01X-285698Y329922D02*
X-285697Y329134D01*
G01X-285698Y326772D02*
X-285697Y325985D01*
G01X-285698Y323622D02*
X-285697Y322835D01*
G01X-285698Y320473D02*
X-285697Y319685D01*
G01X-285698Y317323D02*
X-285697Y316536D01*
G01X-285698Y314174D02*
X-285697Y313386D01*
G01X-285698Y311024D02*
X-285697Y310237D01*
G01X-297028Y304292D02*
X-296841Y303325D01*
G01X-323683Y309099D02*
X-323662Y308996D01*
G01X-323808Y309078D02*
X-323787Y309017D01*
G01X-324227D02*
X-324248Y309078D01*
G01X-309449Y344252D02*
X-309669Y344784D01*
G01X-309449Y341103D02*
X-309669Y341634D01*
G01X-309449Y337953D02*
X-309669Y338485D01*
G01X-309449Y334803D02*
X-309669Y335335D01*
G01X-309449Y331654D02*
X-309669Y332185D01*
G01X-309449Y328504D02*
X-309669Y329036D01*
G01X-309449Y325355D02*
X-309669Y325886D01*
G01X-309449Y322205D02*
X-309669Y322737D01*
G01X-309449Y319055D02*
X-309669Y319587D01*
G01X-309449Y315906D02*
X-309669Y316437D01*
G01X-309449Y312756D02*
X-309669Y313288D01*
G01Y310138D02*
X-309449Y309607D01*
G01X-324185Y309181D02*
X-324164Y309140D01*
G01X-323745Y309181D02*
X-323683Y309099D01*
G01X-276772Y287953D02*
X-274803Y285591D01*
G01X-284252Y344784D02*
X-283721Y344252D01*
G01X-284252Y341634D02*
X-283721Y341103D01*
G01X-284252Y338485D02*
X-283721Y337953D01*
G01X-284252Y335335D02*
X-283721Y334803D01*
G01X-284252Y332185D02*
X-283721Y331654D01*
G01X-284252Y329036D02*
X-283721Y328504D01*
G01X-284252Y325886D02*
X-283721Y325355D01*
G01X-306142Y344891D02*
X-306244Y344994D01*
G01X-284252Y322737D02*
X-283721Y322205D01*
G01X-306142Y341742D02*
X-306244Y341844D01*
G01X-308662Y344252D02*
X-309193Y344784D01*
G01X-284252Y319587D02*
X-283721Y319055D01*
G01X-308913Y342408D02*
X-309016Y342511D01*
G01X-306142Y338592D02*
X-306244Y338694D01*
G01X-308662Y341103D02*
X-309193Y341634D01*
G01X-284252Y316437D02*
X-283721Y315906D01*
G01X-313386Y344587D02*
X-312992Y344193D01*
G01X-308913Y339259D02*
X-309016Y339361D01*
G01X-312284Y342618D02*
X-312815Y343150D01*
G01X-306142Y335442D02*
X-306244Y335545D01*
G01X-308662Y337953D02*
X-309193Y338485D01*
G01X-284252Y313288D02*
X-283721Y312756D01*
G01X-313386Y341437D02*
X-312992Y341044D01*
G01X-308913Y336109D02*
X-309016Y336212D01*
G01X-312284Y339469D02*
X-312815Y340000D01*
G01X-306142Y332293D02*
X-306244Y332395D01*
G01X-308662Y334803D02*
X-309193Y335335D01*
G01X-284252Y310138D02*
X-283721Y309607D01*
G01X-313386Y338288D02*
X-312992Y337894D01*
G01X-308913Y332959D02*
X-309016Y333062D01*
G01X-312284Y336319D02*
X-312815Y336851D01*
G01X-279528Y303347D02*
X-280512Y304331D01*
G01X-320670Y344213D02*
X-321260Y344803D01*
G01X-282225Y305512D02*
X-279528Y302815D01*
G01X-306142Y329143D02*
X-306244Y329246D01*
G01X-308662Y331654D02*
X-309193Y332185D01*
G01X-313386Y335138D02*
X-312992Y334744D01*
G01X-308913Y329810D02*
X-309016Y329913D01*
G01X-312284Y333170D02*
X-312815Y333701D01*
G01X-320670Y341063D02*
X-321260Y341654D01*
G01X-306142Y325994D02*
X-306244Y326096D01*
G01X-308662Y328504D02*
X-309193Y329036D01*
G01X-313386Y331989D02*
X-312992Y331595D01*
G01X-308913Y326660D02*
X-309016Y326763D01*
G01X-312284Y330020D02*
X-312815Y330552D01*
G01X-320670Y337914D02*
X-321260Y338504D01*
G01X-306142Y322844D02*
X-306244Y322946D01*
G01X-308662Y325355D02*
X-309193Y325886D01*
G01X-313386Y328839D02*
X-312992Y328445D01*
G01X-308913Y323511D02*
X-309016Y323613D01*
G01X-312284Y326870D02*
X-312815Y327402D01*
G01X-320670Y334764D02*
X-321260Y335355D01*
G01X-306142Y319694D02*
X-306244Y319797D01*
G01X-308662Y322205D02*
X-309193Y322737D01*
G01X-313386Y325689D02*
X-312992Y325296D01*
G01X-308913Y320361D02*
X-309016Y320464D01*
G01X-312284Y323721D02*
X-312815Y324252D01*
G01X-320670Y331615D02*
X-321260Y332205D01*
G01X-306142Y316545D02*
X-306244Y316647D01*
G01X-308662Y319055D02*
X-309193Y319587D01*
G01X-313386Y322540D02*
X-312992Y322146D01*
G01X-308913Y317211D02*
X-309016Y317314D01*
G01X-312284Y320571D02*
X-312815Y321103D01*
G01X-320670Y328465D02*
X-321260Y329055D01*
G01X-306142Y313395D02*
X-306244Y313498D01*
G01X-308662Y315906D02*
X-309193Y316437D01*
G01X-313386Y319390D02*
X-312992Y318996D01*
G01X-308913Y314062D02*
X-309016Y314165D01*
G01X-312284Y317422D02*
X-312815Y317953D01*
G01X-320670Y325315D02*
X-321260Y325906D01*
G01X-306142Y310246D02*
X-306244Y310348D01*
G01X-308662Y312756D02*
X-309193Y313288D01*
G01X-313386Y316240D02*
X-312992Y315847D01*
G01X-308913Y310912D02*
X-309016Y311015D01*
G01X-312284Y314272D02*
X-312815Y314803D01*
G01X-320670Y322166D02*
X-321260Y322756D01*
G01X-308662Y309607D02*
X-309193Y310138D01*
G01X-313386Y313091D02*
X-312992Y312697D01*
G01X-312284Y311122D02*
X-312815Y311654D01*
G01X-320670Y319016D02*
X-321260Y319607D01*
G01X-312992Y309548D02*
X-313386Y309941D01*
G01X-320670Y315866D02*
X-321260Y316457D01*
G01X-320670Y312717D02*
X-321260Y313307D01*
G01X-320670Y309567D02*
X-321260Y310158D01*
G01X-323850Y309119D02*
X-323808Y309078D01*
G01X-324248D02*
X-324290Y309119D01*
G01X-278405Y289380D02*
X-278112Y289134D01*
G01X-278447D02*
X-278740Y289380D01*
G01X-324478Y309550D02*
X-324332Y309427D01*
G01X-324499D02*
X-324646Y309550D01*
G01X-323829Y309242D02*
X-323745Y309181D01*
G01X-324269Y309242D02*
X-324185Y309181D01*
G01X-275688Y302067D02*
X-279395Y303297D01*
G01X-276148Y301183D02*
X-279403Y302263D01*
G01X-323892Y309263D02*
X-323829Y309242D01*
G01X-323913Y309140D02*
X-323850Y309119D01*
G01X-324332Y309263D02*
X-324269Y309242D01*
G01X-324290Y309119D02*
X-324353Y309140D01*
G01X-318425Y343307D02*
Y344095D01*
G01Y340158D02*
Y340945D01*
G01Y333859D02*
Y334646D01*
G01Y337008D02*
Y337796D01*
G01Y330709D02*
Y331496D01*
G01Y324410D02*
Y325197D01*
G01Y327559D02*
Y328347D01*
G01Y321260D02*
Y322048D01*
G01Y314961D02*
Y315748D01*
G01Y318111D02*
Y318898D01*
G01Y311811D02*
Y312599D01*
G01Y308662D02*
Y309449D01*
G01X-318504Y302363D02*
Y305512D01*
G01X-319016Y343189D02*
Y344213D01*
G01Y340040D02*
Y341063D01*
G01Y336890D02*
Y337914D01*
G01Y333740D02*
Y334764D01*
G01Y330591D02*
Y331615D01*
G01Y327441D02*
Y328465D01*
G01Y324292D02*
Y325315D01*
G01Y321142D02*
Y322166D01*
G01Y317992D02*
Y319016D01*
G01Y314843D02*
Y315866D01*
G01Y311693D02*
Y312717D01*
G01Y308544D02*
Y309567D01*
G01X-319292Y302363D02*
Y305512D01*
G01X-319607Y309449D02*
Y308662D01*
G01Y312599D02*
Y311811D01*
G01Y315748D02*
Y314961D01*
G01Y318898D02*
Y318111D01*
G01Y322048D02*
Y321260D01*
G01Y325197D02*
Y324410D01*
G01Y328347D02*
Y327559D01*
G01Y331496D02*
Y330709D01*
G01Y334646D02*
Y333859D01*
G01Y337796D02*
Y337008D01*
G01Y340945D02*
Y340158D01*
G01Y344095D02*
Y343307D01*
G01X-320079Y302363D02*
Y305512D01*
G01X-320473Y302363D02*
Y305512D01*
G01X-320551Y309449D02*
Y308662D01*
G01Y312599D02*
Y311811D01*
G01Y315748D02*
Y314961D01*
G01Y318898D02*
Y318111D01*
G01Y322048D02*
Y321260D01*
G01Y325197D02*
Y324410D01*
G01Y328347D02*
Y327559D01*
G01Y331496D02*
Y330709D01*
G01Y334646D02*
Y333859D01*
G01Y337796D02*
Y337008D01*
G01Y340945D02*
Y340158D01*
G01Y344095D02*
Y343307D01*
G01X-321260Y344803D02*
Y345748D01*
G01Y341654D02*
Y342599D01*
G01Y338504D02*
Y339449D01*
G01Y335355D02*
Y336300D01*
G01Y332205D02*
Y333150D01*
G01Y329055D02*
Y330000D01*
G01Y325906D02*
Y326851D01*
G01Y322756D02*
Y323701D01*
G01Y319607D02*
Y320552D01*
G01Y316457D02*
Y317402D01*
G01Y313307D02*
Y314252D01*
G01Y310158D02*
Y311103D01*
G01Y302363D02*
Y307953D01*
G01Y309449D02*
Y308662D01*
G01Y312599D02*
Y311811D01*
G01Y315748D02*
Y314961D01*
G01Y318898D02*
Y318111D01*
G01Y322048D02*
Y321260D01*
G01Y325197D02*
Y324410D01*
G01Y328347D02*
Y327559D01*
G01Y331496D02*
Y330709D01*
G01Y334646D02*
Y333859D01*
G01Y337796D02*
Y337008D01*
G01Y340945D02*
Y340158D01*
G01Y344095D02*
Y343307D01*
G01X-321851D02*
Y344095D01*
G01Y340158D02*
Y340945D01*
G01Y333859D02*
Y334646D01*
G01Y337008D02*
Y337796D01*
G01Y330709D02*
Y331496D01*
G01Y324410D02*
Y325197D01*
G01Y327559D02*
Y328347D01*
G01Y321260D02*
Y322048D01*
G01Y314961D02*
Y315748D01*
G01Y318111D02*
Y318898D01*
G01Y311811D02*
Y312599D01*
G01Y308662D02*
Y309449D01*
G01X-322756D02*
Y308662D01*
G01Y312599D02*
Y311811D01*
G01Y315748D02*
Y314961D01*
G01Y318898D02*
Y318111D01*
G01Y322048D02*
Y321260D01*
G01Y325197D02*
Y324410D01*
G01Y328347D02*
Y327559D01*
G01Y331496D02*
Y330709D01*
G01Y334646D02*
Y333859D01*
G01Y337796D02*
Y337008D01*
G01Y340945D02*
Y340158D01*
G01Y344095D02*
Y343307D01*
G01X-323347Y309449D02*
Y308662D01*
G01Y312599D02*
Y311811D01*
G01Y315748D02*
Y314961D01*
G01Y318898D02*
Y318111D01*
G01Y322048D02*
Y321260D01*
G01Y325197D02*
Y324410D01*
G01Y328347D02*
Y327559D01*
G01Y331496D02*
Y330709D01*
G01Y334646D02*
Y333859D01*
G01Y337796D02*
Y337008D01*
G01Y340945D02*
Y340158D01*
G01Y344095D02*
Y343307D01*
G01X-323662Y309673D02*
Y309550D01*
G01Y308996D02*
Y308504D01*
G01X-323787Y309017D02*
Y308627D01*
G01X-324016Y302363D02*
Y305512D01*
G01X-324101Y308627D02*
Y309017D01*
G01X-324227Y308627D02*
Y309017D01*
G01X-324520D02*
Y308627D01*
G01X-324646Y309550D02*
Y309673D01*
G01Y308504D02*
Y308996D01*
G01X-324803Y302363D02*
Y305512D01*
G01X-326811Y374016D02*
Y299213D01*
G01X-329154Y278936D02*
Y288150D01*
G01X-340636D02*
Y278936D01*
G01X-291979Y366152D02*
X-291916Y366398D01*
G01X-292042Y365890D02*
X-291979Y366152D01*
G01X-292105Y365611D02*
X-292042Y365890D01*
G01X-289847Y365884D02*
X-289785Y365611D01*
G01X-289910Y366145D02*
X-289847Y365884D01*
G01X-289974Y366398D02*
X-289910Y366145D01*
G01X-275610Y372144D02*
G03X-276148Y372046I80J-1967D01*
G01X-279705Y369882D02*
G03X-279395Y369932I0J984D01*
G01X-281398Y366142D02*
G03X-280217Y367323I0J1181D01*
G01X-288878D02*
G03X-287697Y366142I1181J0D01*
G01X-280023Y370866D02*
G03X-279403Y370966I1J1969D01*
G01X-289974Y366398D02*
G03X-291916I-971J1712D01*
G01X-289785Y365611D02*
G03X-292105I-1160J2500D01*
G01X-287874Y368111D02*
G03I-3071J0D01*
G01X-275688Y371162D02*
X-279395Y369932D01*
G01X-276148Y372046D02*
X-279403Y370966D01*
G01X-331227Y406613D02*
X-319744D01*
G01Y404100D02*
X-331227D01*
G01X-286064Y362205D02*
X-285329Y362402D01*
G01X-286064Y359055D02*
X-285329Y359252D01*
G01X-286064Y355906D02*
X-285329Y356103D01*
G01X-284252Y345768D02*
X-283721Y346300D01*
G01X-284252Y348918D02*
X-283721Y349449D01*
G01X-284252Y352067D02*
X-283721Y352599D01*
G01X-284252Y355217D02*
X-283721Y355748D01*
G01X-284252Y358366D02*
X-283721Y358898D01*
G01X-284252Y361516D02*
X-283721Y362048D01*
G01X-284252Y364666D02*
X-283721Y365197D01*
G01X-280512Y368898D02*
X-279528Y369882D01*
G01Y370414D02*
X-282225Y367717D01*
G01X-306244Y345558D02*
X-306142Y345661D01*
G01X-306244Y348707D02*
X-306142Y348810D01*
G01X-308662Y346300D02*
X-309193Y345768D01*
G01D02*
X-308662Y346300D01*
G01X-308913Y348143D02*
X-309016Y348041D01*
G01X-306244Y351857D02*
X-306142Y351960D01*
G01X-308662Y349449D02*
X-309193Y348918D01*
G01D02*
X-308662Y349449D01*
G01X-312992Y346359D02*
X-313386Y345965D01*
G01X-308913Y351293D02*
X-309016Y351190D01*
G01X-312815Y347402D02*
X-312284Y347933D01*
G01X-306244Y355007D02*
X-306142Y355109D01*
G01X-308662Y352599D02*
X-309193Y352067D01*
G01D02*
X-308662Y352599D01*
G01X-312992Y349508D02*
X-313386Y349115D01*
G01X-308913Y354442D02*
X-309016Y354340D01*
G01X-312815Y350552D02*
X-312284Y351083D01*
G01X-306244Y358156D02*
X-306142Y358259D01*
G01X-308662Y355748D02*
X-309193Y355217D01*
G01D02*
X-308662Y355748D01*
G01X-296841Y369903D02*
X-301815Y370866D01*
G01X-297028Y368937D02*
X-301910Y369882D01*
G01X-289641Y362205D02*
X-290539Y362366D01*
G01X-292794Y362992D02*
X-291637Y362878D01*
G01X-292794Y359843D02*
X-291637Y359728D01*
G01X-292794Y356693D02*
X-291637Y356579D01*
G01X-292794Y353544D02*
X-291637Y353429D01*
G01X-292794Y350394D02*
X-291637Y350279D01*
G01X-331227Y396142D02*
X-333688D01*
G01X-317284D02*
X-319744D01*
G01X-236260Y374016D02*
X-326811D01*
G01X-275610Y372146D02*
X-238996D01*
G01X-275610Y371162D02*
X-275688D01*
G01X-238996D02*
X-275610D01*
G01X-324803Y370866D02*
X-279528D01*
G01X-303603Y369882D02*
X-303504D01*
G01D02*
X-279528D01*
G01X-238996Y369685D02*
X-275610D01*
G01X-280512Y368898D02*
X-280217D01*
G01X-288977D02*
X-280512D01*
G01X-313386D02*
X-296418D01*
G01X-320079Y367717D02*
X-314961D01*
G01X-320473D02*
X-324803D01*
G01X-282225D02*
X-303622D01*
G01X-291916Y366398D02*
X-289974D01*
G01X-281398Y366142D02*
X-287697D01*
G01X-295276Y365611D02*
X-279528D01*
G01X-283721Y365197D02*
X-312815D01*
G01X-279528Y364961D02*
X-282284D01*
G01X-293898Y364666D02*
X-312284D01*
G01X-284252D02*
X-287992D01*
G01X-313701Y364567D02*
X-285546D01*
G01X-308657Y364370D02*
X-306500D01*
G01Y363977D02*
X-308657D01*
G01X-313701Y363780D02*
X-285546D01*
G01X-287992Y363681D02*
X-284252D01*
G01X-312284D02*
X-293898D01*
G01X-311418Y363386D02*
X-313386D01*
G01X-279528D02*
X-282284D01*
G01X-279528Y363229D02*
X-313130D01*
G01X-312815Y363150D02*
X-283721D01*
G01X-319016Y363111D02*
X-320670D01*
G01X-303622Y363091D02*
X-312992D01*
G01X-286064Y362992D02*
X-323347D01*
G01Y362205D02*
X-286064D01*
G01X-303622Y362107D02*
X-312992D01*
G01X-320670Y362087D02*
X-319016D01*
G01X-283721Y362048D02*
X-312815D01*
G01X-279528Y361969D02*
X-313130D01*
G01X-313386Y361811D02*
X-311418D01*
G01X-279528D02*
X-282284D01*
G01X-293898Y361516D02*
X-312284D01*
G01X-284252D02*
X-287992D01*
G01X-313701Y361418D02*
X-285546D01*
G01X-308657Y361221D02*
X-306500D01*
G01Y360827D02*
X-308657D01*
G01X-313701Y360630D02*
X-285546D01*
G01X-287992Y360532D02*
X-284252D01*
G01X-312284D02*
X-293898D01*
G01X-311418Y360237D02*
X-313386D01*
G01X-279528D02*
X-282284D01*
G01X-279528Y360079D02*
X-313130D01*
G01X-312815Y360000D02*
X-283721D01*
G01X-319016Y359961D02*
X-320670D01*
G01X-303622Y359941D02*
X-312992D01*
G01X-286064Y359843D02*
X-323347D01*
G01Y359055D02*
X-286064D01*
G01X-303622Y358957D02*
X-312992D01*
G01X-320670Y358937D02*
X-319016D01*
G01X-283721Y358898D02*
X-312815D01*
G01X-313130Y358819D02*
X-279528D01*
G01X-313386Y358662D02*
X-311418D01*
G01X-279528D02*
X-282284D01*
G01X-293898Y358366D02*
X-312284D01*
G01X-284252D02*
X-287992D01*
G01X-313701Y358268D02*
X-285546D01*
G01X-308657Y358071D02*
X-306500D01*
G01Y357677D02*
X-308657D01*
G01X-313701Y357481D02*
X-285546D01*
G01X-270689D02*
X-275610D01*
G01X-287992Y357382D02*
X-284252D01*
G01X-312284D02*
X-293898D01*
G01X-311418Y357087D02*
X-313386D01*
G01X-279528D02*
X-282284D01*
G01X-279528Y356929D02*
X-313130D01*
G01X-312815Y356851D02*
X-283721D01*
G01X-319016Y356811D02*
X-320670D01*
G01X-303622Y356792D02*
X-312992D01*
G01X-286064Y356693D02*
X-323347D01*
G01Y355906D02*
X-286064D01*
G01X-303622Y355807D02*
X-312992D01*
G01X-320670Y355788D02*
X-319016D01*
G01X-283721Y355748D02*
X-312815D01*
G01X-313130Y355670D02*
X-279528D01*
G01X-296720Y355512D02*
X-282284D01*
G01X-313386D02*
X-311418D01*
G01X-270689D02*
X-279528D01*
G01D02*
X-282284D01*
G01X-293898Y355217D02*
X-312284D01*
G01X-284252D02*
X-287992D01*
G01X-313701Y355118D02*
X-285546D01*
G01X-308657Y354922D02*
X-306500D01*
G01Y354528D02*
X-308657D01*
G01X-313701Y354331D02*
X-285546D01*
G01X-287992Y354233D02*
X-284252D01*
G01X-312284D02*
X-293898D01*
G01X-311418Y353937D02*
X-313386D01*
G01X-279528D02*
X-282284D01*
G01X-279528Y353780D02*
X-313130D01*
G01X-312815Y353701D02*
X-283721D01*
G01X-319016Y353662D02*
X-320670D01*
G01X-303622Y353642D02*
X-312992D01*
G01X-286064Y353544D02*
X-323347D01*
G01Y352756D02*
X-286064D01*
G01X-303622Y352658D02*
X-312992D01*
G01X-320670Y352638D02*
X-319016D01*
G01X-283721Y352599D02*
X-312815D01*
G01X-313130Y352520D02*
X-279528D01*
G01X-313386Y352363D02*
X-311418D01*
G01X-279528D02*
X-282284D01*
G01X-293898Y352067D02*
X-312284D01*
G01X-284252D02*
X-287992D01*
G01X-313701Y351969D02*
X-285546D01*
G01X-308657Y351772D02*
X-306500D01*
G01Y351378D02*
X-308657D01*
G01X-313701Y351181D02*
X-285546D01*
G01X-287992Y351083D02*
X-284252D01*
G01X-312284D02*
X-293898D01*
G01X-311418Y350788D02*
X-313386D01*
G01X-279528D02*
X-282284D01*
G01X-279528Y350630D02*
X-313130D01*
G01X-312815Y350552D02*
X-283721D01*
G01X-319016Y350512D02*
X-320670D01*
G01X-303622Y350492D02*
X-312992D01*
G01X-286064Y350394D02*
X-323347D01*
G01Y349607D02*
X-286064D01*
G01X-303622Y349508D02*
X-312992D01*
G01X-320670Y349489D02*
X-319016D01*
G01X-283721Y349449D02*
X-312815D01*
G01X-313130Y349370D02*
X-279528D01*
G01X-313386Y349213D02*
X-311418D01*
G01X-279528D02*
X-282284D01*
G01X-293898Y348918D02*
X-312284D01*
G01X-284252D02*
X-287992D01*
G01X-313701Y348819D02*
X-285546D01*
G01X-308657Y348622D02*
X-306500D01*
G01Y348229D02*
X-308657D01*
G01X-313701Y348032D02*
X-285546D01*
G01X-287992Y347933D02*
X-284252D01*
G01X-312284D02*
X-293898D01*
G01X-311418Y347638D02*
X-313386D01*
G01X-279528D02*
X-282284D01*
G01X-279528Y347481D02*
X-313130D01*
G01X-312815Y347402D02*
X-283721D01*
G01X-319016Y347363D02*
X-320670D01*
G01X-303622Y347343D02*
X-312992D01*
G01X-286064Y347244D02*
X-323347D01*
G01Y346457D02*
X-286064D01*
G01X-303622Y346359D02*
X-312992D01*
G01X-320670Y346339D02*
X-319016D01*
G01X-283721Y346300D02*
X-312815D01*
G01X-313130Y346221D02*
X-279528D01*
G01X-313386Y346063D02*
X-311418D01*
G01X-279528D02*
X-282284D01*
G01X-293898Y345768D02*
X-312284D01*
G01X-284252D02*
X-287992D01*
G01X-313701Y345670D02*
X-285546D01*
G01X-308657Y345473D02*
X-306500D01*
G01Y345079D02*
X-308657D01*
G01X-291637Y362320D02*
X-292794Y362205D01*
G01X-291637Y359170D02*
X-292794Y359055D01*
G01X-291637Y356020D02*
X-292794Y355906D01*
G01X-291637Y352871D02*
X-292794Y352756D01*
G01X-291637Y349721D02*
X-292794Y349607D01*
G01X-291637Y346572D02*
X-292794Y346457D01*
G01X-290539Y362831D02*
X-289641Y362992D01*
G01X-290539Y359682D02*
X-289641Y359843D01*
G01X-290539Y356532D02*
X-289641Y356693D01*
G01X-290539Y353383D02*
X-289641Y353544D01*
G01X-290539Y350233D02*
X-289641Y350394D01*
G01X-290539Y347083D02*
X-289641Y347244D01*
G01X-289491Y364567D02*
X-290085Y364453D01*
G01X-289491Y361418D02*
X-290085Y361303D01*
G01X-289491Y358268D02*
X-290085Y358153D01*
G01X-289491Y355118D02*
X-290085Y355004D01*
G01X-289491Y351969D02*
X-290085Y351854D01*
G01X-289491Y348819D02*
X-290085Y348705D01*
G01X-289491Y345670D02*
X-290085Y345555D01*
G01X-291879Y363885D02*
X-292395Y363780D01*
G01X-291879Y360736D02*
X-292395Y360630D01*
G01X-291879Y357586D02*
X-292395Y357481D01*
G01X-291879Y354437D02*
X-292395Y354331D01*
G01X-291879Y351287D02*
X-292395Y351181D01*
G01X-291879Y348137D02*
X-292395Y348032D01*
G01X-291414Y362355D02*
X-291438Y362350D01*
G01X-291414Y359205D02*
X-291438Y359200D01*
G01X-291414Y356056D02*
X-291438Y356051D01*
G01X-291414Y352906D02*
X-291438Y352901D01*
G01X-291414Y349757D02*
X-291438Y349752D01*
G01X-291414Y346607D02*
X-291438Y346602D01*
G01X-286064Y352756D02*
X-285329Y352953D01*
G01X-286064Y349607D02*
X-285329Y349803D01*
G01X-286064Y346457D02*
X-285329Y346654D01*
G01X-312992Y352658D02*
X-313386Y352264D01*
G01X-308913Y357592D02*
X-309016Y357490D01*
G01X-312815Y353701D02*
X-312284Y354233D01*
G01X-320670Y346339D02*
X-321260Y345748D01*
G01X-306244Y361306D02*
X-306142Y361409D01*
G01X-308662Y358898D02*
X-309193Y358366D01*
G01D02*
X-308662Y358898D01*
G01X-312992Y355807D02*
X-313386Y355414D01*
G01X-308913Y360742D02*
X-309016Y360639D01*
G01X-312815Y356851D02*
X-312284Y357382D01*
G01X-320670Y349489D02*
X-321260Y348898D01*
G01X-306244Y364455D02*
X-306142Y364558D01*
G01X-308662Y362048D02*
X-309193Y361516D01*
G01D02*
X-308662Y362048D01*
G01X-312992Y358957D02*
X-313386Y358563D01*
G01X-308913Y363891D02*
X-309016Y363789D01*
G01X-312815Y360000D02*
X-312284Y360532D01*
G01X-320670Y352638D02*
X-321260Y352048D01*
G01X-308662Y365197D02*
X-309193Y364666D01*
G01D02*
X-308662Y365197D01*
G01X-312992Y362107D02*
X-313386Y361713D01*
G01X-312815Y363150D02*
X-312284Y363681D01*
G01X-320670Y355788D02*
X-321260Y355197D01*
G01X-320670Y358937D02*
X-321260Y358347D01*
G01X-320670Y362087D02*
X-321260Y361496D01*
G01X-284252Y363681D02*
X-283721Y363150D01*
G01X-284252Y360532D02*
X-283721Y360000D01*
G01X-284252Y357382D02*
X-283721Y356851D01*
G01X-284252Y354233D02*
X-283721Y353701D01*
G01X-284252Y351083D02*
X-283721Y350552D01*
G01X-284252Y347933D02*
X-283721Y347402D01*
G01X-286064Y362992D02*
X-285329Y362796D01*
G01X-286064Y359843D02*
X-285329Y359646D01*
G01X-286064Y356693D02*
X-285329Y356496D01*
G01X-286064Y353544D02*
X-285329Y353347D01*
G01X-286064Y350394D02*
X-285329Y350197D01*
G01X-286064Y347244D02*
X-285329Y347048D01*
G01X-291438Y362848D02*
X-291414Y362842D01*
G01X-291438Y359698D02*
X-291414Y359693D01*
G01X-291438Y356548D02*
X-291414Y356543D01*
G01X-291438Y353399D02*
X-291414Y353394D01*
G01X-291438Y350249D02*
X-291414Y350244D01*
G01X-291438Y347100D02*
X-291414Y347094D01*
G01X-291879Y364462D02*
X-292395Y364567D01*
G01X-291879Y361312D02*
X-292395Y361418D01*
G01X-291879Y358163D02*
X-292395Y358268D01*
G01X-291879Y355013D02*
X-292395Y355118D01*
G01X-291879Y351863D02*
X-292395Y351969D01*
G01X-291879Y348714D02*
X-292395Y348819D01*
G01X-291879Y345564D02*
X-292395Y345670D01*
G01X-290085Y363894D02*
X-289491Y363780D01*
G01X-290085Y360745D02*
X-289491Y360630D01*
G01X-290085Y357595D02*
X-289491Y357481D01*
G01X-290085Y354446D02*
X-289491Y354331D01*
G01X-290085Y351296D02*
X-289491Y351181D01*
G01X-290085Y348146D02*
X-289491Y348032D01*
G01X-289641Y359055D02*
X-290539Y359216D01*
G01X-289641Y355906D02*
X-290539Y356067D01*
G01X-289641Y352756D02*
X-290539Y352917D01*
G01X-289641Y349607D02*
X-290539Y349768D01*
G01X-289641Y346457D02*
X-290539Y346618D01*
G01X-292794Y347244D02*
X-291637Y347130D01*
G01X-309669Y345768D02*
X-309449Y346300D01*
G01X-309669Y348918D02*
X-309449Y349449D01*
G01X-309669Y352067D02*
X-309449Y352599D01*
G01X-309669Y355217D02*
X-309449Y355748D01*
G01X-309669Y358366D02*
X-309449Y358898D01*
G01X-309669Y361516D02*
X-309449Y362048D01*
G01X-309669Y364666D02*
X-309449Y365197D01*
G01X-296841Y369903D02*
X-297028Y368937D01*
G01X-285338Y347050D02*
Y346652D01*
G01Y350200D02*
Y349801D01*
G01Y353349D02*
Y352951D01*
G01Y356499D02*
Y356100D01*
G01Y359648D02*
Y359250D01*
G01Y362798D02*
Y362400D01*
G01X-275610Y372146D02*
Y357481D01*
G01X-280217Y370866D02*
Y367323D01*
G01X-280512Y365611D02*
Y370866D01*
G01X-282284Y352363D02*
Y350788D01*
G01Y349213D02*
Y347638D01*
G01Y355512D02*
Y353937D01*
G01Y361811D02*
Y360237D01*
G01Y358662D02*
Y357087D01*
G01Y364961D02*
Y363386D01*
G01X-283721Y363150D02*
Y365197D01*
G01Y356851D02*
Y358898D01*
G01Y360000D02*
Y362048D01*
G01Y353701D02*
Y355748D01*
G01Y347402D02*
Y349449D01*
G01Y350552D02*
Y352599D01*
G01X-284252Y363681D02*
Y364666D01*
G01Y360532D02*
Y361516D01*
G01Y357382D02*
Y358366D01*
G01Y354233D02*
Y355217D01*
G01Y351083D02*
Y352067D01*
G01Y347933D02*
Y348918D01*
G01X-285329Y362402D02*
Y362796D01*
G01Y359252D02*
Y359646D01*
G01Y352953D02*
Y353347D01*
G01Y356103D02*
Y356496D01*
G01Y349803D02*
Y350197D01*
G01Y346654D02*
Y347048D01*
G01X-285546Y348819D02*
Y348032D01*
G01Y351969D02*
Y351181D01*
G01Y355118D02*
Y354331D01*
G01Y358268D02*
Y357481D01*
G01Y361418D02*
Y360630D01*
G01Y364567D02*
Y363780D01*
G01X-285573Y348819D02*
Y348032D01*
G01Y351969D02*
Y351181D01*
G01Y355118D02*
Y354331D01*
G01Y358268D02*
Y357481D01*
G01Y361418D02*
Y360630D01*
G01Y364567D02*
Y363780D01*
G01X-285582Y347115D02*
Y346586D01*
G01Y350265D02*
Y349736D01*
G01Y353415D02*
Y352885D01*
G01Y356564D02*
Y356035D01*
G01Y359714D02*
Y359185D01*
G01Y362863D02*
Y362334D01*
G01X-285587Y362333D02*
Y362865D01*
G01Y359183D02*
Y359715D01*
G01Y352884D02*
Y353416D01*
G01Y356034D02*
Y356565D01*
G01Y349735D02*
Y350266D01*
G01Y346585D02*
Y347116D01*
G01X-285627Y363780D02*
Y364567D01*
G01Y357481D02*
Y358268D01*
G01Y360630D02*
Y361418D01*
G01Y354331D02*
Y355118D01*
G01Y348032D02*
Y348819D01*
G01Y351181D02*
Y351969D01*
G01X-285827Y365611D02*
Y370866D01*
G01X-285850Y362263D02*
Y362935D01*
G01Y359113D02*
Y359785D01*
G01Y352814D02*
Y353486D01*
G01Y355963D02*
Y356636D01*
G01Y349664D02*
Y350337D01*
G01Y346515D02*
Y347187D01*
G01X-285877Y348819D02*
Y348032D01*
G01Y351969D02*
Y351181D01*
G01Y355118D02*
Y354331D01*
G01Y358268D02*
Y357481D01*
G01Y361418D02*
Y360630D01*
G01Y364567D02*
Y363780D01*
G01X-286614Y370866D02*
Y365611D01*
G01X-286688Y347244D02*
Y346457D01*
G01Y350394D02*
Y349607D01*
G01Y353544D02*
Y352756D01*
G01Y356693D02*
Y355906D01*
G01Y359843D02*
Y359055D01*
G01Y362992D02*
Y362205D01*
G01X-287160Y363780D02*
Y364567D01*
G01Y357481D02*
Y358268D01*
G01Y360630D02*
Y361418D01*
G01Y354331D02*
Y355118D01*
G01Y348032D02*
Y348819D01*
G01Y351181D02*
Y351969D01*
G01X-287992Y364666D02*
Y365197D01*
G01Y363150D02*
Y363681D01*
G01Y361516D02*
Y362048D01*
G01Y360000D02*
Y360532D01*
G01Y358366D02*
Y358898D01*
G01Y356851D02*
Y357382D01*
G01Y355217D02*
Y355748D01*
G01Y353701D02*
Y354233D01*
G01Y352067D02*
Y352599D01*
G01Y350552D02*
Y351083D01*
G01Y348918D02*
Y349449D01*
G01Y347402D02*
Y347933D01*
G01Y345768D02*
Y346300D01*
G01X-288878Y367323D02*
Y370866D01*
G01X-288977D02*
Y365611D01*
G01X-290085Y348705D02*
Y348146D01*
G01Y351854D02*
Y351296D01*
G01Y355004D02*
Y354446D01*
G01Y358153D02*
Y357595D01*
G01Y361303D02*
Y360745D01*
G01Y364453D02*
Y363894D01*
G01X-290510Y363780D02*
Y364567D01*
G01Y357481D02*
Y358268D01*
G01Y360630D02*
Y361418D01*
G01Y354331D02*
Y355118D01*
G01Y348032D02*
Y348819D01*
G01Y351181D02*
Y351969D01*
G01X-290539Y362366D02*
Y362831D01*
G01Y359216D02*
Y359682D01*
G01Y352917D02*
Y353383D01*
G01Y356067D02*
Y356532D01*
G01Y349768D02*
Y350233D01*
G01Y346618D02*
Y347083D01*
G01X-290840Y347244D02*
Y346457D01*
G01Y350394D02*
Y349607D01*
G01Y353544D02*
Y352756D01*
G01Y356693D02*
Y355906D01*
G01Y359843D02*
Y359055D01*
G01Y362992D02*
Y362205D01*
G01X-291057D02*
Y362992D01*
G01Y359055D02*
Y359843D01*
G01Y352756D02*
Y353544D01*
G01Y355906D02*
Y356693D01*
G01Y349607D02*
Y350394D01*
G01Y346457D02*
Y347244D01*
G01X-291197D02*
Y346457D01*
G01Y350394D02*
Y349607D01*
G01Y353544D02*
Y352756D01*
G01Y356693D02*
Y355906D01*
G01Y359843D02*
Y359055D01*
G01Y362992D02*
Y362205D01*
G01X-291380D02*
Y362992D01*
G01Y359055D02*
Y359843D01*
G01Y352756D02*
Y353544D01*
G01Y355906D02*
Y356693D01*
G01Y349607D02*
Y350394D01*
G01Y346457D02*
Y347244D01*
G01X-291414Y347094D02*
Y346607D01*
G01Y350244D02*
Y349757D01*
G01Y353394D02*
Y352906D01*
G01Y356543D02*
Y356056D01*
G01Y359693D02*
Y359205D01*
G01Y362842D02*
Y362355D01*
G01X-291438Y362350D02*
Y362848D01*
G01Y359200D02*
Y359698D01*
G01Y352901D02*
Y353399D01*
G01Y356051D02*
Y356548D01*
G01Y349752D02*
Y350249D01*
G01Y346602D02*
Y347100D01*
G01X-291535Y348819D02*
Y348032D01*
G01Y351969D02*
Y351181D01*
G01Y355118D02*
Y354331D01*
G01Y358268D02*
Y357481D01*
G01Y361418D02*
Y360630D01*
G01Y364567D02*
Y363780D01*
G01X-291637Y347130D02*
Y346572D01*
G01Y350279D02*
Y349721D01*
G01Y353429D02*
Y352871D01*
G01Y356579D02*
Y356020D01*
G01Y359728D02*
Y359170D01*
G01Y362878D02*
Y362320D01*
G01X-291879Y363885D02*
Y364462D01*
G01Y357586D02*
Y358163D01*
G01Y360736D02*
Y361312D01*
G01Y354437D02*
Y355013D01*
G01Y348137D02*
Y348714D01*
G01Y351287D02*
Y351863D01*
G01X-293898Y347933D02*
Y347402D01*
G01Y346300D02*
Y345768D01*
G01Y352599D02*
Y352067D01*
G01Y351083D02*
Y350552D01*
G01Y349449D02*
Y348918D01*
G01Y357382D02*
Y356851D01*
G01Y355748D02*
Y355217D01*
G01Y354233D02*
Y353701D01*
G01Y362048D02*
Y361516D01*
G01Y360532D02*
Y360000D01*
G01Y358898D02*
Y358366D01*
G01Y365197D02*
Y364666D01*
G01Y363681D02*
Y363150D01*
G01X-294488Y370866D02*
Y365611D01*
G01X-295276Y370866D02*
Y365611D01*
G01X-295925Y369882D02*
Y370866D01*
G01X-296418Y368898D02*
Y369882D01*
G01X-301240Y370866D02*
Y369753D01*
G01X-302028Y370866D02*
Y369882D01*
G01X-302422D02*
Y370866D01*
G01X-303504D02*
Y369882D01*
G01X-303603D02*
Y370866D01*
G01X-304331Y347244D02*
Y346457D01*
G01Y350394D02*
Y349607D01*
G01Y353544D02*
Y352756D01*
G01Y356693D02*
Y355906D01*
G01Y359843D02*
Y359055D01*
G01Y362992D02*
Y362205D01*
G01X-304799Y348819D02*
Y348032D01*
G01Y351969D02*
Y351181D01*
G01Y355118D02*
Y354331D01*
G01Y358268D02*
Y357481D01*
G01Y361418D02*
Y360630D01*
G01Y364567D02*
Y363780D01*
G01X-304922Y362205D02*
Y362992D01*
G01Y359055D02*
Y359843D01*
G01Y352756D02*
Y353544D01*
G01Y355906D02*
Y356693D01*
G01Y349607D02*
Y350394D01*
G01Y346457D02*
Y347244D01*
G01X-305233Y363780D02*
Y364567D01*
G01Y357481D02*
Y358268D01*
G01Y360630D02*
Y361418D01*
G01Y354331D02*
Y355118D01*
G01Y348032D02*
Y348819D01*
G01Y351181D02*
Y351969D01*
G01X-305457Y363780D02*
Y364567D01*
G01Y357481D02*
Y358268D01*
G01Y360630D02*
Y361418D01*
G01Y354331D02*
Y355118D01*
G01Y348032D02*
Y348819D01*
G01Y351181D02*
Y351969D01*
G01X-305473Y363681D02*
Y364666D01*
G01Y357382D02*
Y358366D01*
G01Y360532D02*
Y361516D01*
G01Y354233D02*
Y355217D01*
G01Y347933D02*
Y348918D01*
G01Y351083D02*
Y352067D01*
G01X-305512Y347244D02*
Y346457D01*
G01Y350394D02*
Y349607D01*
G01Y353544D02*
Y352756D01*
G01Y356693D02*
Y355906D01*
G01Y359843D02*
Y359055D01*
G01Y362992D02*
Y362205D01*
G01X-305788Y363681D02*
Y364666D01*
G01Y357382D02*
Y358366D01*
G01Y360532D02*
Y361516D01*
G01Y354233D02*
Y355217D01*
G01Y347933D02*
Y348918D01*
G01Y351083D02*
Y352067D01*
G01X-305890Y348819D02*
Y348032D01*
G01Y351969D02*
Y351181D01*
G01Y355118D02*
Y354331D01*
G01Y358268D02*
Y357481D01*
G01Y361418D02*
Y360630D01*
G01Y364567D02*
Y363780D01*
G01X-306103Y347244D02*
Y346457D01*
G01Y350394D02*
Y349607D01*
G01Y348918D02*
Y347933D01*
G01Y352067D02*
Y351083D01*
G01Y353544D02*
Y352756D01*
G01Y356693D02*
Y355906D01*
G01Y355217D02*
Y354233D01*
G01Y359843D02*
Y359055D01*
G01Y358366D02*
Y357382D01*
G01Y361516D02*
Y360532D01*
G01Y362992D02*
Y362205D01*
G01Y364666D02*
Y363681D01*
G01X-306142Y363789D02*
Y364558D01*
G01Y357490D02*
Y358259D01*
G01Y360639D02*
Y361409D01*
G01Y354340D02*
Y355109D01*
G01Y348041D02*
Y348810D01*
G01Y351190D02*
Y351960D01*
G01X-306244Y348707D02*
Y348143D01*
G01Y351857D02*
Y351293D01*
G01Y355007D02*
Y354442D01*
G01Y358156D02*
Y357592D01*
G01Y361306D02*
Y360742D01*
G01Y364455D02*
Y363891D01*
G01X-306500Y363977D02*
Y364370D01*
G01Y357677D02*
Y358071D01*
G01Y360827D02*
Y361221D01*
G01Y354528D02*
Y354922D01*
G01Y348229D02*
Y348622D01*
G01Y351378D02*
Y351772D01*
G01Y345079D02*
Y345473D01*
G01X-306693Y347244D02*
Y346457D01*
G01Y350394D02*
Y349607D01*
G01Y353544D02*
Y352756D01*
G01Y356693D02*
Y355906D01*
G01Y359843D02*
Y359055D01*
G01Y362992D02*
Y362205D01*
G01X-307351Y347244D02*
Y346457D01*
G01Y350394D02*
Y349607D01*
G01Y353544D02*
Y352756D01*
G01Y356693D02*
Y355906D01*
G01Y359843D02*
Y359055D01*
G01Y362992D02*
Y362205D01*
G01X-307605D02*
Y362992D01*
G01Y359055D02*
Y359843D01*
G01Y352756D02*
Y353544D01*
G01Y355906D02*
Y356693D01*
G01Y349607D02*
Y350394D01*
G01Y346457D02*
Y347244D01*
G01X-307628Y362205D02*
Y362992D01*
G01Y359055D02*
Y359843D01*
G01Y352756D02*
Y353544D01*
G01Y355906D02*
Y356693D01*
G01Y349607D02*
Y350394D01*
G01Y346457D02*
Y347244D01*
G01X-307874Y364666D02*
Y370866D01*
G01Y361516D02*
Y363681D01*
G01Y358366D02*
Y360532D01*
G01Y352067D02*
Y354233D01*
G01Y355217D02*
Y357382D01*
G01Y348918D02*
Y351083D01*
G01Y345768D02*
Y347933D01*
G01X-308657Y345473D02*
Y345079D01*
G01Y348622D02*
Y348229D01*
G01Y351772D02*
Y351378D01*
G01Y354922D02*
Y354528D01*
G01Y358071D02*
Y357677D01*
G01Y361221D02*
Y360827D01*
G01Y364370D02*
Y363977D01*
G01X-308662Y347402D02*
Y346300D01*
G01Y350552D02*
Y349449D01*
G01Y353701D02*
Y352599D01*
G01Y356851D02*
Y355748D01*
G01Y360000D02*
Y358898D01*
G01Y363150D02*
Y362048D01*
G01Y370866D02*
Y365197D01*
G01X-308783Y347244D02*
Y346457D01*
G01Y350394D02*
Y349607D01*
G01Y353544D02*
Y352756D01*
G01Y356693D02*
Y355906D01*
G01Y359843D02*
Y359055D01*
G01Y362992D02*
Y362205D01*
G01X-308888Y363780D02*
Y364567D01*
G01Y357481D02*
Y358268D01*
G01Y360630D02*
Y361418D01*
G01Y354331D02*
Y355118D01*
G01Y348032D02*
Y348819D01*
G01Y351181D02*
Y351969D01*
G01X-308901Y362205D02*
Y362992D01*
G01Y359055D02*
Y359843D01*
G01Y352756D02*
Y353544D01*
G01Y355906D02*
Y356693D01*
G01Y349607D02*
Y350394D01*
G01Y346457D02*
Y347244D01*
G01X-308913Y363891D02*
Y364455D01*
G01Y357592D02*
Y358156D01*
G01Y360742D02*
Y361306D01*
G01Y354442D02*
Y355007D01*
G01Y348143D02*
Y348707D01*
G01Y351293D02*
Y351857D01*
G01X-308969Y363780D02*
Y364567D01*
G01Y357481D02*
Y358268D01*
G01Y360630D02*
Y361418D01*
G01Y354331D02*
Y355118D01*
G01Y348032D02*
Y348819D01*
G01Y351181D02*
Y351969D01*
G01X-309003Y348819D02*
Y348032D01*
G01Y351969D02*
Y351181D01*
G01Y355118D02*
Y354331D01*
G01Y358268D02*
Y357481D01*
G01Y361418D02*
Y360630D01*
G01Y364567D02*
Y363780D01*
G01X-309016Y348810D02*
Y348041D01*
G01Y351960D02*
Y351190D01*
G01Y355109D02*
Y354340D01*
G01Y358259D02*
Y357490D01*
G01Y361409D02*
Y360639D01*
G01Y364558D02*
Y363789D01*
G01X-309055Y348819D02*
Y348032D01*
G01Y351969D02*
Y351181D01*
G01Y355118D02*
Y354331D01*
G01Y358268D02*
Y357481D01*
G01Y361418D02*
Y360630D01*
G01Y364567D02*
Y363780D01*
G01X-309076D02*
Y364567D01*
G01Y357481D02*
Y358268D01*
G01Y360630D02*
Y361418D01*
G01Y354331D02*
Y355118D01*
G01Y348032D02*
Y348819D01*
G01Y351181D02*
Y351969D01*
G01X-309114Y348918D02*
Y347933D01*
G01Y352067D02*
Y351083D01*
G01Y355217D02*
Y354233D01*
G01Y358366D02*
Y357382D01*
G01Y361516D02*
Y360532D01*
G01Y364666D02*
Y363681D01*
G01X-309370Y363780D02*
Y364567D01*
G01Y357481D02*
Y358268D01*
G01Y360630D02*
Y361418D01*
G01Y354331D02*
Y355118D01*
G01Y348032D02*
Y348819D01*
G01Y351181D02*
Y351969D01*
G01X-309429Y363681D02*
Y364666D01*
G01Y357382D02*
Y358366D01*
G01Y360532D02*
Y361516D01*
G01Y354233D02*
Y355217D01*
G01Y347933D02*
Y348918D01*
G01Y351083D02*
Y352067D01*
G01X-309449Y347402D02*
Y346300D01*
G01Y348819D02*
Y348032D01*
G01Y351969D02*
Y351181D01*
G01Y350552D02*
Y349449D01*
G01Y355118D02*
Y354331D01*
G01Y353701D02*
Y352599D01*
G01Y356851D02*
Y355748D01*
G01Y358268D02*
Y357481D01*
G01Y361418D02*
Y360630D01*
G01Y360000D02*
Y358898D01*
G01Y364567D02*
Y363780D01*
G01Y363150D02*
Y362048D01*
G01Y370866D02*
Y365197D01*
G01X-309685Y363780D02*
Y364567D01*
G01Y357481D02*
Y358268D01*
G01Y360630D02*
Y361418D01*
G01Y354331D02*
Y355118D01*
G01Y348032D02*
Y348819D01*
G01Y351181D02*
Y351969D01*
G01X-309722Y347244D02*
Y346457D01*
G01Y350394D02*
Y349607D01*
G01Y353544D02*
Y352756D01*
G01Y356693D02*
Y355906D01*
G01Y359843D02*
Y359055D01*
G01Y362992D02*
Y362205D01*
G01X-309862Y348819D02*
Y348032D01*
G01Y351969D02*
Y351181D01*
G01Y355118D02*
Y354331D01*
G01Y358268D02*
Y357481D01*
G01Y361418D02*
Y360630D01*
G01Y364567D02*
Y363780D01*
G01X-309960Y362205D02*
Y362992D01*
G01Y359055D02*
Y359843D01*
G01Y352756D02*
Y353544D01*
G01Y355906D02*
Y356693D01*
G01Y349607D02*
Y350394D01*
G01Y346457D02*
Y347244D01*
G01X-310000Y362205D02*
Y362992D01*
G01Y359055D02*
Y359843D01*
G01Y352756D02*
Y353544D01*
G01Y355906D02*
Y356693D01*
G01Y349607D02*
Y350394D01*
G01Y346457D02*
Y347244D01*
G01X-310040Y348819D02*
Y348032D01*
G01Y351969D02*
Y351181D01*
G01Y355118D02*
Y354331D01*
G01Y358268D02*
Y357481D01*
G01Y361418D02*
Y360630D01*
G01Y364567D02*
Y363780D01*
G01X-310276D02*
Y364567D01*
G01Y357481D02*
Y358268D01*
G01Y360630D02*
Y361418D01*
G01Y354331D02*
Y355118D01*
G01Y348032D02*
Y348819D01*
G01Y351181D02*
Y351969D01*
G01X-311378Y363780D02*
Y364567D01*
G01Y357481D02*
Y358268D01*
G01Y360630D02*
Y361418D01*
G01Y354331D02*
Y355118D01*
G01Y348032D02*
Y348819D01*
G01Y351181D02*
Y351969D01*
G01X-311418Y347638D02*
Y346063D01*
G01Y350788D02*
Y349213D01*
G01Y348819D02*
Y348032D01*
G01Y351969D02*
Y351181D01*
G01Y357087D02*
Y355512D01*
G01Y353937D02*
Y352363D01*
G01Y355118D02*
Y354331D01*
G01Y360237D02*
Y358662D01*
G01Y358268D02*
Y357481D01*
G01Y361418D02*
Y360630D01*
G01Y363386D02*
Y361811D01*
G01Y364567D02*
Y363780D01*
G01X-311792Y348819D02*
Y348032D01*
G01Y351969D02*
Y351181D01*
G01Y355118D02*
Y354331D01*
G01Y358268D02*
Y357481D01*
G01Y361418D02*
Y360630D01*
G01Y364567D02*
Y363780D01*
G01X-311890Y347244D02*
Y346457D01*
G01Y350394D02*
Y349607D01*
G01Y353544D02*
Y352756D01*
G01Y356693D02*
Y355906D01*
G01Y359843D02*
Y359055D01*
G01Y362992D02*
Y362205D01*
G01X-311969Y363780D02*
Y364567D01*
G01Y357481D02*
Y358268D01*
G01Y360630D02*
Y361418D01*
G01Y354331D02*
Y355118D01*
G01Y348032D02*
Y348819D01*
G01Y351181D02*
Y351969D01*
G01X-312008Y362205D02*
Y362992D01*
G01Y359055D02*
Y359843D01*
G01Y352756D02*
Y353544D01*
G01Y355906D02*
Y356693D01*
G01Y349607D02*
Y350394D01*
G01Y346457D02*
Y347244D01*
G01X-312205Y348819D02*
Y348032D01*
G01Y351969D02*
Y351181D01*
G01Y355118D02*
Y354331D01*
G01Y358268D02*
Y357481D01*
G01Y361418D02*
Y360630D01*
G01Y364567D02*
Y363780D01*
G01X-312284Y348918D02*
Y347933D01*
G01Y352067D02*
Y351083D01*
G01Y355217D02*
Y354233D01*
G01Y358366D02*
Y357382D01*
G01Y361516D02*
Y360532D01*
G01Y364666D02*
Y363681D01*
G01X-312796Y347244D02*
Y346457D01*
G01Y350394D02*
Y349607D01*
G01Y353544D02*
Y352756D01*
G01Y356693D02*
Y355906D01*
G01Y359843D02*
Y359055D01*
G01Y362992D02*
Y362205D01*
G01X-312815Y349449D02*
Y347402D01*
G01Y352599D02*
Y350552D01*
G01Y355748D02*
Y353701D01*
G01Y358898D02*
Y356851D01*
G01Y362048D02*
Y360000D01*
G01Y365197D02*
Y363150D01*
G01X-312992Y362107D02*
Y363091D01*
G01Y347343D02*
Y346359D01*
G01Y350492D02*
Y349508D01*
G01Y353642D02*
Y352658D01*
G01Y356792D02*
Y355807D01*
G01Y359941D02*
Y358957D01*
G01X-313110Y348819D02*
Y348032D01*
G01Y351969D02*
Y351181D01*
G01Y355118D02*
Y354331D01*
G01Y358268D02*
Y357481D01*
G01Y361418D02*
Y360630D01*
G01Y364567D02*
Y363780D01*
G01X-313701Y348819D02*
Y348032D01*
G01Y351969D02*
Y351181D01*
G01Y355118D02*
Y354331D01*
G01Y358268D02*
Y357481D01*
G01Y361418D02*
Y360630D01*
G01Y364567D02*
Y363780D01*
G01X-313977Y347244D02*
Y346457D01*
G01Y350394D02*
Y349607D01*
G01Y353544D02*
Y352756D01*
G01Y356693D02*
Y355906D01*
G01Y359843D02*
Y359055D01*
G01Y362992D02*
Y362205D01*
G01X-285698Y364567D02*
X-285697Y363780D01*
G01X-285698Y361418D02*
X-285697Y360630D01*
G01X-285698Y358268D02*
X-285697Y357481D01*
G01X-285698Y355118D02*
X-285697Y354331D01*
G01X-285698Y351969D02*
X-285697Y351181D01*
G01X-285698Y348819D02*
X-285697Y348032D01*
G01X-309449Y363150D02*
X-309669Y363681D01*
G01X-309449Y360000D02*
X-309669Y360532D01*
G01X-309449Y356851D02*
X-309669Y357382D01*
G01X-309449Y353701D02*
X-309669Y354233D01*
G01X-309449Y350552D02*
X-309669Y351083D01*
G01X-309449Y347402D02*
X-309669Y347933D01*
G01X-306142Y363789D02*
X-306244Y363891D01*
G01X-308913Y364455D02*
X-309016Y364558D01*
G01X-306142Y360639D02*
X-306244Y360742D01*
G01X-308662Y363150D02*
X-309193Y363681D01*
G01X-308913Y361306D02*
X-309016Y361409D01*
G01X-312284Y364666D02*
X-312815Y365197D01*
G01X-306142Y357490D02*
X-306244Y357592D01*
G01X-308662Y360000D02*
X-309193Y360532D01*
G01X-312992Y363091D02*
X-313386Y363485D01*
G01X-308913Y358156D02*
X-309016Y358259D01*
G01X-312284Y361516D02*
X-312815Y362048D01*
G01X-306142Y354340D02*
X-306244Y354442D01*
G01X-308662Y356851D02*
X-309193Y357382D01*
G01X-313386Y360335D02*
X-312992Y359941D01*
G01X-308913Y355007D02*
X-309016Y355109D01*
G01X-312284Y358366D02*
X-312815Y358898D01*
G01X-306142Y351190D02*
X-306244Y351293D01*
G01X-308662Y353701D02*
X-309193Y354233D01*
G01X-313386Y357185D02*
X-312992Y356792D01*
G01X-308913Y351857D02*
X-309016Y351960D01*
G01X-312284Y355217D02*
X-312815Y355748D01*
G01X-320670Y363111D02*
X-321260Y363701D01*
G01X-306142Y348041D02*
X-306244Y348143D01*
G01X-308662Y350552D02*
X-309193Y351083D01*
G01X-313386Y354036D02*
X-312992Y353642D01*
G01X-308913Y348707D02*
X-309016Y348810D01*
G01X-312284Y352067D02*
X-312815Y352599D01*
G01X-320670Y359961D02*
X-321260Y360552D01*
G01X-308662Y347402D02*
X-309193Y347933D01*
G01X-313386Y350886D02*
X-312992Y350492D01*
G01X-308913Y345558D02*
X-309016Y345661D01*
G01X-312284Y348918D02*
X-312815Y349449D01*
G01X-320670Y356811D02*
X-321260Y357402D01*
G01X-313386Y347737D02*
X-312992Y347343D01*
G01X-312284Y345768D02*
X-312815Y346300D01*
G01X-320670Y353662D02*
X-321260Y354252D01*
G01X-320670Y350512D02*
X-321260Y351103D01*
G01X-320670Y347363D02*
X-321260Y347953D01*
G01X-317284Y415827D02*
Y396142D01*
G01X-318425Y362205D02*
Y362992D01*
G01Y359055D02*
Y359843D01*
G01Y352756D02*
Y353544D01*
G01Y355906D02*
Y356693D01*
G01Y349607D02*
Y350394D01*
G01Y346457D02*
Y347244D01*
G01X-318504Y367717D02*
Y370866D01*
G01X-319016Y362087D02*
Y363111D01*
G01Y358937D02*
Y359961D01*
G01Y355788D02*
Y356811D01*
G01Y352638D02*
Y353662D01*
G01Y349489D02*
Y350512D01*
G01Y346339D02*
Y347363D01*
G01X-319292Y367717D02*
Y370866D01*
G01X-319607Y347244D02*
Y346457D01*
G01Y350394D02*
Y349607D01*
G01Y353544D02*
Y352756D01*
G01Y356693D02*
Y355906D01*
G01Y359843D02*
Y359055D01*
G01Y362992D02*
Y362205D01*
G01X-319744Y406613D02*
Y415827D01*
G01Y396142D02*
Y404100D01*
G01X-320079Y367717D02*
Y370866D01*
G01X-320473Y367717D02*
Y370866D01*
G01X-320551Y347244D02*
Y346457D01*
G01Y350394D02*
Y349607D01*
G01Y353544D02*
Y352756D01*
G01Y356693D02*
Y355906D01*
G01Y359843D02*
Y359055D01*
G01Y362992D02*
Y362205D01*
G01X-321260Y363701D02*
Y370866D01*
G01Y360552D02*
Y361496D01*
G01Y357402D02*
Y358347D01*
G01Y354252D02*
Y355197D01*
G01Y351103D02*
Y352048D01*
G01Y347953D02*
Y348898D01*
G01Y347244D02*
Y346457D01*
G01Y350394D02*
Y349607D01*
G01Y353544D02*
Y352756D01*
G01Y356693D02*
Y355906D01*
G01Y359843D02*
Y359055D01*
G01Y362992D02*
Y362205D01*
G01X-321851D02*
Y362992D01*
G01Y359055D02*
Y359843D01*
G01Y352756D02*
Y353544D01*
G01Y355906D02*
Y356693D01*
G01Y349607D02*
Y350394D01*
G01Y346457D02*
Y347244D01*
G01X-322756D02*
Y346457D01*
G01Y350394D02*
Y349607D01*
G01Y353544D02*
Y352756D01*
G01Y356693D02*
Y355906D01*
G01Y359843D02*
Y359055D01*
G01Y362992D02*
Y362205D01*
G01X-323347Y347244D02*
Y346457D01*
G01Y350394D02*
Y349607D01*
G01Y353544D02*
Y352756D01*
G01Y356693D02*
Y355906D01*
G01Y359843D02*
Y359055D01*
G01Y362992D02*
Y362205D01*
G01X-324016Y367717D02*
Y370866D01*
G01X-324803D02*
Y367717D01*
G01X-331227Y404100D02*
Y396142D01*
G01Y415827D02*
Y406613D01*
G01X-333688Y396142D02*
Y415827D01*
G01X-299807Y430389D02*
G03I-1378J0D01*
G01X-301185Y426452D02*
G03X-297248Y430389I0J3937D01*
G01X-316933Y442200D02*
G03X-312996Y446137I0J3937D01*
G01X-303059Y432044D02*
X-299909D01*
G01Y431650D02*
X-302523D01*
G01X-302053Y431257D02*
X-302590D01*
G01X-319744Y415827D02*
X-317284D01*
G01X-333688D02*
X-331227D01*
G01X-299909Y430338D02*
X-300713Y430076D01*
G01X-302790Y429419D02*
X-300981Y430010D01*
G01X-303059Y429682D02*
X-299909Y430732D01*
G01Y428107D02*
X-303059Y429157D01*
G01X-300713Y428763D02*
X-299909Y428501D01*
G01X-300981Y428829D02*
X-302790Y429419D01*
G01X-302523Y431650D02*
X-302053Y431257D01*
G01X-302590D02*
X-303059Y431650D01*
G01X-297248Y430389D02*
Y536688D01*
G01X-299909Y432044D02*
Y431650D01*
G01Y430732D02*
Y430338D01*
G01Y428501D02*
Y428107D01*
G01X-300713Y430076D02*
Y428763D01*
G01X-300981Y430010D02*
Y428829D01*
G01X-303059Y431650D02*
Y432044D01*
G01Y429157D02*
Y429682D01*
G01X-312996Y446137D02*
Y520940D01*
G01X-297248Y536688D02*
G03X-301185Y540625I-3937J0D01*
G01X-312996Y520940D02*
G03X-316933Y524877I-3937J0D01*
G01X-287878Y602711D02*
G03I-1890J0D01*
G01Y622711D02*
G03I-1890J0D01*
G01X-288163Y624802D02*
X-287828D01*
G01X-290240D02*
X-290106D01*
G01Y624408D02*
X-290240D01*
G01X-286233Y623971D02*
X-291028D01*
G01X-287828Y622439D02*
X-288163D01*
G01X-286233Y621452D02*
X-291028D01*
G01X-290509Y624736D02*
X-290240Y624802D01*
G01X-290106D02*
X-289838Y624736D01*
G01X-290240Y622505D02*
X-290509Y622570D01*
G01X-286233Y603971D02*
X-291028D01*
G01X-290692Y601486D02*
X-287542D01*
G01X-286233Y601452D02*
X-291028D01*
G01X-287542Y601092D02*
X-290156D01*
G01X-289686Y600699D02*
X-290223D01*
G01X-293404Y597711D02*
X-286132D01*
G01X-298705Y593774D02*
X-280831D01*
G01X-289838Y624736D02*
X-289637Y624605D01*
G01X-290441Y622964D02*
X-290240Y622833D01*
G01X-284768Y616924D02*
X-286132Y617711D01*
G01X-293404D02*
X-294768Y618499D01*
G01X-284768Y606924D02*
X-286132Y607711D01*
G01X-293404D02*
X-294768Y608499D01*
G01X-293404Y597711D02*
X-294768Y598499D01*
G01X-289838Y624277D02*
X-290106Y624408D01*
G01X-290575Y623161D02*
X-290441Y622964D01*
G01X-289637Y624605D02*
X-288163Y622964D01*
G01Y622439D02*
X-289838Y624277D01*
G01X-290509Y622570D02*
X-290777Y622833D01*
G01X-290156Y601092D02*
X-289686Y600699D01*
G01X-290223D02*
X-290692Y601092D01*
G01X-290777Y622833D02*
X-290910Y623096D01*
G01D02*
X-290977Y623555D01*
G01X-290642Y623489D02*
X-290575Y623161D01*
G01X-290977Y623817D02*
X-290910Y624211D01*
G01X-280831Y593774D02*
Y631648D01*
G01X-284768Y618499D02*
Y626924D01*
G01Y608499D02*
Y616924D01*
G01Y598499D02*
Y606924D01*
G01X-286233Y603971D02*
Y601452D01*
G01Y623971D02*
Y621452D01*
G01X-287542Y601486D02*
Y601092D01*
G01X-287828Y624802D02*
Y622439D01*
G01X-288163Y622964D02*
Y624802D01*
G01X-288508Y623971D02*
Y601452D01*
G01X-290240Y622833D02*
Y622505D01*
G01X-290642Y623752D02*
Y623489D01*
G01X-290692Y601092D02*
Y601486D01*
G01X-290977Y623555D02*
Y623817D01*
G01X-291028Y623971D02*
Y601452D01*
G01X-294768Y606924D02*
Y598499D01*
G01Y616924D02*
Y608499D01*
G01Y626924D02*
Y618499D01*
G01X-298705Y631648D02*
Y593774D01*
G01X-284768Y598499D02*
X-286132Y597711D01*
G01X-284768Y608499D02*
X-286132Y607711D01*
G01X-293404D02*
X-294768Y606924D01*
G01X-284768Y618499D02*
X-286132Y617711D01*
G01X-293404D02*
X-294768Y616924D01*
G01X-290240Y624408D02*
X-290441Y624277D01*
G01X-290777Y624474D02*
X-290509Y624736D01*
G01X-290441Y624277D02*
X-290575Y624080D01*
G01X-290910Y624211D02*
X-290777Y624474D01*
G01X-290575Y624080D02*
X-290642Y623752D01*
G01X-333865Y690552D02*
X-336325D01*
G01X-319922D02*
X-322382D01*
G01X-280831Y631648D02*
X-298705D01*
G01X-286132Y627711D02*
X-293404D01*
G01X-284768Y626924D02*
X-286132Y627711D01*
G01X-293404D02*
X-294768Y626924D01*
G01X-319922Y710237D02*
Y690552D01*
G01X-322382D02*
Y698509D01*
G01X-333865D02*
Y690552D01*
G01X-336325D02*
Y710237D01*
G01X-251969Y766339D02*
X-278740D01*
G01X-240158Y762402D02*
X-282677D01*
G01X-322382Y710237D02*
X-319922D01*
G01X-336325D02*
X-333865D01*
G01Y701022D02*
X-322382D01*
G01Y698509D02*
X-333865D01*
G01X-278740Y768544D02*
Y766339D01*
G01X-282677Y796654D02*
Y762402D01*
G01X-322382Y701022D02*
Y710237D01*
G01X-333865D02*
Y701022D01*
G01X-240158Y796654D02*
X-282677D01*
G01X-251969Y792717D02*
X-278740D01*
G01Y791103D02*
X-274803D01*
G01X-251969Y790709D02*
X-276378D01*
G01X-278347Y790512D02*
X-260118D01*
G01X-278740D02*
X-276378D01*
G01Y789961D02*
X-255906D01*
G01X-278740Y789626D02*
X-276772D01*
G01Y789380D02*
X-278405D01*
G01X-278112Y789134D02*
X-278447D01*
G01X-278740Y788544D02*
X-276378D01*
G01X-264173D02*
X-278347D01*
G01X-276772Y787953D02*
X-278740D01*
G01X-276772Y781103D02*
X-278740D01*
G01Y780512D02*
X-276378D01*
G01X-257481D02*
X-278347D01*
G01X-278740Y778544D02*
X-276378D01*
G01X-257481D02*
X-278347D01*
G01X-276772Y777953D02*
X-278740D01*
G01X-276772Y771103D02*
X-278740D01*
G01Y770512D02*
X-276378D01*
G01X-263942D02*
X-278347D01*
G01X-276378Y769095D02*
X-255906D01*
G01X-278740Y768544D02*
X-276378D01*
G01X-260197D02*
X-278347D01*
G01X-251969Y768347D02*
X-276378D01*
G01X-278740Y767953D02*
X-274803D01*
G01X-276772Y787953D02*
X-274803Y785591D01*
G01X-278405Y789380D02*
X-278112Y789134D01*
G01X-278447D02*
X-278740Y789380D01*
G01X-276772Y777953D02*
X-274803Y774410D01*
G01Y791103D02*
Y767953D01*
G01X-276378Y770512D02*
Y768544D01*
G01Y771496D02*
Y767953D01*
G01Y780512D02*
Y778544D01*
G01Y781811D02*
Y777244D01*
G01Y790512D02*
Y788544D01*
G01Y791103D02*
Y787481D01*
G01X-276772Y789626D02*
Y789380D01*
G01X-277599Y788544D02*
Y790512D01*
G01Y778544D02*
Y780512D01*
G01Y768544D02*
Y770512D01*
G01X-278347D02*
Y768544D01*
G01Y780512D02*
Y778544D01*
G01Y790512D02*
Y788544D01*
G01X-278740Y789380D02*
Y789626D01*
G01Y778544D02*
Y770512D01*
G01Y788544D02*
Y780512D01*
G01Y792717D02*
Y790512D01*
G01X-274803Y773071D02*
X-276772Y771103D01*
G01X-274803Y784646D02*
X-276772Y781103D01*
G01X-255906Y905512D02*
G03I-9842J0D01*
G01X-247047D02*
G03I-18701J0D01*
G01X-303150D02*
G03I-9842J0D01*
G01X-294292D02*
G03I-18700J0D01*
G01X-285433Y933071D02*
G03Y925197I0J-3937D01*
G01X-316142D02*
G03Y933071I0J3937D01*
G01X-285433D02*
X-224410D01*
G01X-316142Y925197D02*
X-285433D01*
G01X-242651Y-204044D02*
X-243845Y-203148D01*
X-244528Y-202380D01*
X-244869Y-201357D01*
X-244528Y-200461D01*
X-243845Y-199821D01*
X-242822Y-199309D01*
X-241627Y-199181D01*
X-240604Y-199309D01*
X-239580Y-199821D01*
X-238727Y-200589D01*
X-238386Y-201484D01*
X-238727Y-202508D01*
X-239751Y-203404D01*
X-241286Y-203916D01*
X-242992Y-204044D01*
X-245210Y-203788D01*
X-246404Y-203404D01*
X-247598Y-202764D01*
X-248451Y-201868D01*
X-248622Y-200973D01*
X-248281Y-200077D01*
X-247428Y-199437D01*
G01X-248622Y-191377D02*
X-248281Y-192400D01*
X-247428Y-193168D01*
X-246404Y-193680D01*
X-245039Y-194063D01*
X-243504Y-194191D01*
X-241968Y-194063D01*
X-240604Y-193680D01*
X-239580Y-193168D01*
X-238727Y-192400D01*
X-238386Y-191377D01*
X-238727Y-190353D01*
X-239580Y-189585D01*
X-240604Y-189073D01*
X-241968Y-188690D01*
X-243504Y-188562D01*
X-245039Y-188690D01*
X-246404Y-189073D01*
X-247428Y-189585D01*
X-248281Y-190353D01*
X-248622Y-191377D01*
G01X-238045Y-181141D02*
X-238215Y-181396D01*
X-238557D01*
X-238727Y-181141D01*
X-238557Y-180885D01*
X-238215D01*
X-238045Y-181141D01*
G01X-248622Y-170905D02*
X-248281Y-171928D01*
X-247428Y-172696D01*
X-246404Y-173208D01*
X-245039Y-173591D01*
X-243504Y-173719D01*
X-241968Y-173591D01*
X-240604Y-173208D01*
X-239580Y-172696D01*
X-238727Y-171928D01*
X-238386Y-170905D01*
X-238727Y-169881D01*
X-239580Y-169113D01*
X-240604Y-168601D01*
X-241968Y-168218D01*
X-243504Y-168090D01*
X-245039Y-168218D01*
X-246404Y-168601D01*
X-247428Y-169113D01*
X-248281Y-169881D01*
X-248622Y-170905D01*
G01Y-160669D02*
X-248281Y-161692D01*
X-247428Y-162460D01*
X-246404Y-162972D01*
X-245039Y-163355D01*
X-243504Y-163483D01*
X-241968Y-163355D01*
X-240604Y-162972D01*
X-239580Y-162460D01*
X-238727Y-161692D01*
X-238386Y-160669D01*
X-238727Y-159645D01*
X-239580Y-158877D01*
X-240604Y-158365D01*
X-241968Y-157982D01*
X-243504Y-157854D01*
X-245039Y-157982D01*
X-246404Y-158365D01*
X-247428Y-158877D01*
X-248281Y-159645D01*
X-248622Y-160669D01*
G01X-236221Y712599D02*
Y-152499D01*
G01X-270473Y125985D02*
Y35532D01*
G01X-266536Y129922D02*
G03X-270473Y125985I0J-3937D01*
G01X-260630Y129922D02*
G03Y137796I0J3937D01*
G01X-244882D02*
G03Y129922I0J-3937D01*
G01X-240158D02*
G03X-228347Y141733I0J11811D01*
G01X-260630Y129922D02*
X-266536D01*
G01X-240158D02*
X-244882D01*
G01X-242933Y203524D02*
G03X-242146Y204311I0J787D01*
G01X-245099D02*
G03X-244311Y203524I787J0D01*
G01X-250705Y185426D02*
G03X-251907Y185278I-506J-844D01*
G01X-254447Y184489D02*
G03X-253802Y184776I-51J983D01*
G01X-253071Y183465D02*
G03I-1575J0D01*
G01X-245197D02*
G03I-1575J0D01*
G01X-253957Y200788D02*
G03X-250020I1968J0D01*
G01X-254396Y183505D02*
G03X-253107Y184079I-103J1966D01*
G01X-250197Y186270D02*
G03X-252603Y185974I-1014J-1687D01*
G01X-254809Y200788D02*
G03X-249168I2820J0D01*
G01X-255662D02*
G03X-248315I3673J0D01*
G01X-257481Y158701D02*
G03X-257284Y158898I0J197D01*
G01Y160237D02*
G03X-257481Y160433I-197J-1D01*
G01Y162402D02*
G03X-257284Y162599I0J197D01*
G01Y163937D02*
G03X-257481Y164134I-197J0D01*
G01X-263583Y169843D02*
G03X-264173Y170433I-590J0D01*
G01X-263583Y164725D02*
G03X-262992Y164134I591J0D01*
G01X-243110Y155315D02*
G03Y167520I0J6102D01*
G01X-270689Y197638D02*
G03Y199607I0J984D01*
G01X-266851Y183465D02*
G03I-1574J0D01*
G01X-263942Y152402D02*
G03X-263352Y152992I0J590D01*
G01X-240158Y137796D02*
G03X-236221Y141733I0J3937D01*
G01X-240158Y137796D02*
G03X-236221Y141733I0J3937D01*
G01X-262564Y156339D02*
X-259252Y158701D01*
G01X-251907Y185278D02*
X-253107Y184079D01*
G01X-252603Y185974D02*
X-253802Y184776D01*
G01X-247579Y184696D02*
X-248086Y183853D01*
G01X-249266Y185710D02*
X-249773Y184866D01*
G01X-257284Y157126D02*
X-260197Y150433D01*
G01X-228347Y368701D02*
Y141733D01*
G01X-236221D02*
Y921260D01*
G01Y413386D02*
Y141733D01*
G01X-236240Y182973D02*
Y183957D01*
G01X-236260Y181103D02*
Y255906D01*
G01X-237028Y182973D02*
Y183957D01*
G01X-238996Y182973D02*
Y254036D01*
G01X-240158Y144292D02*
Y178544D01*
G01X-241870Y183957D02*
Y182973D01*
G01X-242461Y183957D02*
Y182973D01*
G01X-243110Y155315D02*
Y167520D01*
G01X-244036Y183957D02*
Y182973D01*
G01X-244803D02*
Y183957D01*
G01X-245985D02*
Y182973D01*
G01X-246090Y183957D02*
Y182973D01*
G01X-246385D02*
Y183957D01*
G01X-246398D02*
Y182973D01*
G01X-247749Y183957D02*
Y182973D01*
G01X-248044D02*
Y183957D01*
G01X-248150D02*
Y182973D01*
G01X-248315Y236221D02*
Y200788D01*
G01X-249168Y236221D02*
Y200788D01*
G01X-249331Y183957D02*
Y182973D01*
G01X-250020Y200788D02*
Y236221D01*
G01X-251969Y174607D02*
Y148229D01*
G01X-252559Y167520D02*
Y154559D01*
G01X-252677Y182973D02*
Y183957D01*
G01X-253347Y167520D02*
Y153975D01*
G01X-253859Y183957D02*
Y182973D01*
G01X-253957Y236221D02*
Y200788D01*
G01X-253964Y183957D02*
Y182973D01*
G01X-254259D02*
Y183957D01*
G01X-254809Y200788D02*
Y236221D01*
G01X-255623Y183957D02*
Y182973D01*
G01X-255662Y236221D02*
Y200788D01*
G01X-255906Y171851D02*
Y150985D01*
G01X-255918Y182973D02*
Y183957D01*
G01X-256024D02*
Y182973D01*
G01X-257205Y183957D02*
Y182973D01*
G01X-257284Y167520D02*
Y153975D01*
G01Y167586D02*
Y153388D01*
G01X-257481Y162402D02*
Y160433D01*
G01Y166340D02*
Y164134D01*
G01X-263352Y152992D02*
Y156339D01*
G01X-263583Y164725D02*
Y169843D01*
G01X-264587Y183957D02*
Y182973D01*
G01X-265571Y183957D02*
Y182973D01*
G01X-266457D02*
Y183957D01*
G01X-267638D02*
Y182973D01*
G01X-267744Y183957D02*
Y182973D01*
G01X-268039D02*
Y183957D01*
G01X-269403D02*
Y182973D01*
G01X-269698D02*
Y183957D01*
G01X-269803D02*
Y182973D01*
G01X-270985Y183957D02*
Y182973D01*
G01X-273622Y167586D02*
Y154405D01*
G01X-260118Y172402D02*
X-257284Y165888D01*
G01X-242933Y203524D02*
X-244311D01*
G01X-253957Y200788D02*
X-255662D01*
G01X-248315D02*
X-250020D01*
G01X-247579Y184696D02*
X-250197Y186270D01*
G01X-248086Y183853D02*
X-250705Y185426D01*
G01X-238996Y183957D02*
X-236240D01*
G01Y182973D02*
X-238996D01*
G01X-257284Y167586D02*
X-273622D01*
G01X-251969Y167559D02*
X-257284D01*
G01Y167520D02*
X-243110D01*
G01X-257481Y164134D02*
X-262992D01*
G01X-259252Y158701D02*
X-257481D01*
G01X-263352Y156339D02*
X-262564D01*
G01X-252559Y155315D02*
X-243110D01*
G01X-252559Y154528D02*
X-253347D01*
G01X-273622Y154405D02*
X-257284D01*
G01X-253347Y153937D02*
X-257284D01*
G01Y153388D02*
X-251969D01*
G01X-244882Y137796D02*
X-260630D01*
G01X-254447Y184489D02*
X-264587Y183957D01*
G01X-254396Y183505D02*
X-264561Y182973D01*
G01X-243110Y273426D02*
G03Y285630I0J6102D01*
G01X-263942Y270512D02*
G03X-263352Y271103I-1J591D01*
G01X-244311Y233485D02*
G03X-245099Y232697I0J-788D01*
G01X-242146D02*
G03X-242933Y233485I-788J0D01*
G01X-253802Y252233D02*
G03X-254447Y252520I-696J-696D01*
G01X-251907Y251730D02*
G03X-250705Y251582I696J696D01*
G01X-241260Y253544D02*
G03I-1575J0D01*
G01X-253071D02*
G03I-1575J0D01*
G01X-250020Y236221D02*
G03X-253957I-1969J0D01*
G01X-252603Y251034D02*
G03X-250197Y250739I1392J1392D01*
G01X-253107Y252929D02*
G03X-254396Y253503I-1392J-1392D01*
G01X-249168Y236221D02*
G03X-254809I-2821J0D01*
G01X-248315D02*
G03X-255662I-3674J0D01*
G01X-244311Y211910D02*
G03X-245099Y211122I0J-788D01*
G01X-242146D02*
G03X-242933Y211910I-787J1D01*
G01Y225099D02*
G03X-242146Y225886I0J787D01*
G01X-245099D02*
G03X-244311Y225099I787J0D01*
G01X-270689Y237402D02*
G03Y239370I0J984D01*
G01X-266851Y253544D02*
G03I-1574J0D01*
G01X-247268Y245811D02*
X-247590Y245702D01*
G01X-247268Y246250D02*
X-247590Y246140D01*
G01X-248987Y245811D02*
X-249309Y245702D01*
G01X-260377Y245921D02*
X-260699Y245811D01*
G01X-248987Y246250D02*
X-249202Y246140D01*
G01X-252210Y245921D02*
X-252425Y245811D01*
G01X-260592Y246360D02*
X-260807Y246250D01*
G01X-268328Y245921D02*
X-268543Y245811D01*
G01X-262096Y249103D02*
X-262525Y248884D01*
G01X-270262Y249103D02*
X-270477Y248993D01*
G01X-247579Y252312D02*
X-250197Y250739D01*
G01X-248086Y253156D02*
X-250705Y251582D01*
G01X-252103Y246579D02*
X-252425Y246360D01*
G01X-256401Y246031D02*
X-256723Y245811D01*
G01X-256401Y246470D02*
X-256723Y246250D01*
G01X-253715Y248555D02*
X-254037Y248335D01*
G01X-253930Y249103D02*
X-254252Y248884D01*
G01X-260054Y246140D02*
X-260377Y245921D01*
G01X-264567Y246031D02*
X-264889Y245811D01*
G01X-264567Y246470D02*
X-264889Y246250D01*
G01X-261988Y248664D02*
X-262310Y248445D01*
G01X-262564Y274449D02*
X-259252Y276811D01*
G01X-247053Y246031D02*
X-247268Y245811D01*
G01X-247053Y246470D02*
X-247268Y246250D01*
G01X-248665Y246140D02*
X-248987Y245811D01*
G01X-248880Y246360D02*
X-248987Y246250D01*
G01X-251996Y246140D02*
X-252210Y245921D01*
G01X-256186Y246250D02*
X-256401Y246031D01*
G01X-256186Y246689D02*
X-256401Y246470D01*
G01X-259839Y246360D02*
X-260054Y246140D01*
G01X-260269Y246689D02*
X-260592Y246360D01*
G01X-264352Y246250D02*
X-264567Y246031D01*
G01X-264352Y246689D02*
X-264567Y246470D01*
G01X-262525Y248884D02*
X-262848Y248555D01*
G01X-268113Y246140D02*
X-268328Y245921D01*
G01X-268543Y246470D02*
X-268757Y246250D01*
G01X-270047Y248664D02*
X-270262Y248445D01*
G01X-270477Y248993D02*
X-270692Y248774D01*
G01X-254252Y248884D02*
X-254682Y248335D01*
G01X-251888Y246909D02*
X-252103Y246579D01*
G01X-267898Y246470D02*
X-268113Y246140D01*
G01X-268328Y246799D02*
X-268543Y246470D01*
G01X-270262Y248445D02*
X-270477Y248116D01*
G01X-270692Y248774D02*
X-270907Y248445D01*
G01X-248772Y246579D02*
X-248880Y246360D01*
G01X-251888D02*
X-251996Y246140D01*
G01X-254037Y248335D02*
X-254145Y248116D01*
G01X-259624Y246799D02*
X-259839Y246360D01*
G01X-260162Y246909D02*
X-260269Y246689D01*
G01X-257284Y275237D02*
X-260197Y268544D01*
G01X-241359Y249213D02*
X-243077Y244055D01*
G01X-242540Y247457D02*
X-243507Y244494D01*
G01X-242003Y249213D02*
X-242433Y247896D01*
G01X-254145Y248116D02*
X-254252Y247787D01*
G01X-262310Y248445D02*
X-262418Y248116D01*
G01X-267790Y246799D02*
X-267898Y246470D01*
G01X-270907Y248445D02*
X-271122Y247677D01*
G01X-254682Y248335D02*
X-254789Y247896D01*
G01X-262848Y248555D02*
X-262955Y248116D01*
G01X-267683Y247238D02*
X-267790Y246799D01*
G01X-268220Y247238D02*
X-268328Y246799D01*
G01X-270477Y248116D02*
X-270584Y247677D01*
G01X-259517Y247457D02*
X-259624Y246799D01*
G01X-236240Y254036D02*
Y253052D01*
G01X-237028Y254036D02*
Y253052D01*
G01X-240158Y262402D02*
Y296654D01*
G01X-240866Y253052D02*
Y254036D01*
G01X-241870D02*
Y253052D01*
G01X-242047Y254036D02*
Y253052D01*
G01X-242146Y211122D02*
Y204311D01*
G01Y232697D02*
Y225886D01*
G01X-242153Y254036D02*
Y253052D01*
G01X-242448D02*
Y254036D01*
G01X-242461D02*
Y253052D01*
G01X-243110Y273426D02*
Y285630D01*
G01X-243812Y254036D02*
Y253052D01*
G01X-244036Y254036D02*
Y253052D01*
G01X-244107D02*
Y254036D01*
G01X-244213D02*
Y253052D01*
G01X-245099Y211122D02*
Y204311D01*
G01Y232697D02*
Y225886D01*
G01X-245394Y254036D02*
Y253052D01*
G01X-246398Y254036D02*
Y253052D01*
G01X-246516Y249213D02*
Y245702D01*
G01X-247053Y246470D02*
Y249213D01*
G01Y245702D02*
Y246031D01*
G01X-259624Y248116D02*
X-259517Y247457D01*
G01X-258657Y247018D02*
X-258550Y246470D01*
G01X-266286Y247128D02*
X-266179Y246579D01*
G01X-266823Y247128D02*
X-266716Y246579D01*
G01X-254789Y247018D02*
X-254682Y246579D01*
G01X-258120Y247018D02*
X-258013Y246579D01*
G01X-262955Y247018D02*
X-262848Y246579D01*
G01X-268328Y248116D02*
X-268220Y247677D01*
G01X-245012Y249213D02*
X-244582Y247896D01*
G01X-244474Y247457D02*
X-243507Y244494D01*
G01X-254252Y247128D02*
X-254145Y246799D01*
G01X-245656Y249213D02*
X-243937Y244055D01*
G01X-263352Y274449D02*
X-262564D01*
G01X-252559Y273426D02*
X-243110D01*
G01X-252559Y272638D02*
X-253347D01*
G01X-273622Y272515D02*
X-257284D01*
G01X-253347Y272048D02*
X-257284D01*
G01Y271498D02*
X-251969D01*
G01X-261344Y249213D02*
X-262096Y249103D01*
G01X-261236Y248774D02*
X-261988Y248664D01*
G01X-260699Y245811D02*
X-261344Y245702D01*
G01X-269832Y249213D02*
X-270262Y249103D01*
G01X-269617Y248774D02*
X-270047Y248664D01*
G01X-268757Y246250D02*
X-269187Y246140D01*
G01X-268543Y245811D02*
X-268972Y245702D01*
G01X-253500Y249213D02*
X-253930Y249103D01*
G01X-264889Y246250D02*
X-265319Y246140D01*
G01X-264889Y245811D02*
X-265319Y245702D01*
G01X-253285Y248664D02*
X-253715Y248555D01*
G01X-260807Y246250D02*
X-261236Y246140D01*
G01X-256723Y246250D02*
X-257153Y246140D01*
G01X-256723Y245811D02*
X-257153Y245702D01*
G01X-252425Y246360D02*
X-252855Y246250D01*
G01X-252425Y245811D02*
X-252855Y245702D01*
G01X-248235Y249213D02*
Y246579D01*
G01X-248772D02*
Y249213D01*
G01X-249954D02*
Y246579D01*
G01X-250492D02*
Y249213D01*
G01X-251351Y250968D02*
Y245702D01*
G01X-251888Y248555D02*
Y250968D01*
G01Y245702D02*
Y246360D01*
G01Y248006D02*
Y246909D01*
G01X-251969Y292717D02*
Y266339D01*
G01X-252559Y285630D02*
Y272669D01*
G01X-252677Y253052D02*
Y254036D01*
G01X-253347Y285630D02*
Y272085D01*
G01X-253859Y254036D02*
Y253052D01*
G01X-253964Y254036D02*
Y253052D01*
G01X-254252Y247128D02*
Y247787D01*
G01X-254259Y253052D02*
Y254036D01*
G01X-254789Y247018D02*
Y247896D01*
G01X-255623Y254036D02*
Y253052D01*
G01X-255649Y249213D02*
Y244055D01*
G01X-255906Y289961D02*
Y269095D01*
G01X-255918Y253052D02*
Y254036D01*
G01X-256024D02*
Y253052D01*
G01X-256186Y246689D02*
Y249213D01*
G01Y244055D02*
Y246250D01*
G01X-257205Y254036D02*
Y253052D01*
G01X-257284Y285630D02*
Y272085D01*
G01Y285696D02*
Y271498D01*
G01X-258120Y249213D02*
Y247018D01*
G01X-258657D02*
Y249213D01*
G01X-260054Y247457D02*
Y247677D01*
G01X-260162Y247018D02*
Y246909D01*
G01X-262418Y246799D02*
Y247018D01*
G01X-262955D02*
Y247457D01*
G01X-263352Y271103D02*
Y274449D01*
G01X-263815Y249213D02*
Y245702D01*
G01X-264352Y246689D02*
Y249213D01*
G01Y245702D02*
Y246250D01*
G01X-264587Y254036D02*
Y253052D01*
G01X-265571Y254036D02*
Y253052D01*
G01X-266286Y249213D02*
Y247128D01*
G01X-266457Y253052D02*
Y254036D01*
G01X-266823Y247128D02*
Y249213D01*
G01X-267638Y254036D02*
Y253052D01*
G01X-267683Y247677D02*
Y247238D01*
G01X-267744Y254036D02*
Y253052D01*
G01X-268039D02*
Y254036D01*
G01X-268220Y247677D02*
Y247238D01*
G01X-269403Y254036D02*
Y253052D01*
G01X-269698D02*
Y254036D01*
G01X-269803D02*
Y253052D01*
G01X-270584Y247238D02*
Y247677D01*
G01X-270985Y254036D02*
Y253052D01*
G01X-271122Y247238D02*
Y247677D01*
G01X-271981Y249213D02*
Y244055D01*
G01X-272518D02*
Y249213D01*
G01X-273622Y285696D02*
Y272515D01*
G01X-270584Y247238D02*
X-270477Y246799D01*
G01X-271122Y247238D02*
X-271014Y246799D01*
G01X-267898Y248445D02*
X-267683Y247677D01*
G01X-260162Y248006D02*
X-260054Y247677D01*
G01X-266716Y246579D02*
X-266609Y246250D01*
G01X-271014Y246799D02*
X-270907Y246470D01*
G01X-250492Y246579D02*
X-250277Y246031D01*
G01X-248235Y246579D02*
X-248127Y246360D01*
G01X-249954Y246579D02*
X-249847Y246360D01*
G01X-251996Y248774D02*
X-251888Y248555D01*
G01X-254682Y246579D02*
X-254574Y246360D01*
G01X-258550Y246470D02*
X-258442Y246250D01*
G01X-259839Y248555D02*
X-259624Y248116D01*
G01X-260269Y248225D02*
X-260162Y248006D01*
G01X-248086Y253156D02*
X-247579Y252312D01*
G01X-249773Y252142D02*
X-249266Y251298D01*
G01X-252103Y248335D02*
X-251888Y248006D01*
G01X-254145Y246799D02*
X-253930Y246470D01*
G01X-262418Y246799D02*
X-262203Y246470D01*
G01X-268113Y248774D02*
X-267898Y248445D01*
G01X-268543D02*
X-268328Y248116D01*
G01X-270477Y246799D02*
X-270262Y246470D01*
G01X-270907D02*
X-270692Y246140D01*
G01X-262848Y246579D02*
X-262525Y246140D01*
G01X-248020Y246250D02*
X-248127Y246360D01*
G01X-248342Y245811D02*
X-248665Y246140D01*
G01X-251996Y248774D02*
X-252210Y248993D01*
G01X-249739Y246250D02*
X-249847Y246360D01*
G01X-250062Y245811D02*
X-250277Y246031D01*
G01X-254252D02*
X-254574Y246360D01*
G01X-259839Y248555D02*
X-260054Y248774D01*
G01X-257798Y246360D02*
X-258013Y246579D01*
G01X-260269Y248225D02*
X-260592Y248555D01*
G01X-258228Y246031D02*
X-258442Y246250D01*
G01X-268113Y248774D02*
X-268328Y248993D01*
G01X-265964Y246360D02*
X-266179Y246579D01*
G01X-268543Y248445D02*
X-268757Y248664D01*
G01X-266394Y246031D02*
X-266609Y246250D01*
G01X-270047D02*
X-270262Y246470D01*
G01X-270477Y245921D02*
X-270692Y246140D01*
G01X-251907Y251730D02*
X-253107Y252929D01*
G01X-252603Y251034D02*
X-253802Y252233D01*
G01X-252103Y248335D02*
X-252425Y248555D01*
G01X-253930Y245811D02*
X-254252Y246031D01*
G01X-260054Y248774D02*
X-260377Y248993D01*
G01X-257905Y245811D02*
X-258228Y246031D01*
G01X-261881Y246250D02*
X-262203Y246470D01*
G01X-266071Y245811D02*
X-266394Y246031D01*
G01X-261988Y245811D02*
X-262525Y246140D01*
G01X-252210Y248993D02*
X-252425Y249103D01*
G01X-247805Y246140D02*
X-248020Y246250D01*
G01X-249524Y246140D02*
X-249739Y246250D01*
G01X-253500D02*
X-253930Y246470D01*
G01X-260592Y248555D02*
X-260807Y248664D01*
G01X-257583Y246250D02*
X-257798Y246360D01*
G01X-268328Y248993D02*
X-268543Y249103D01*
G01X-265749Y246250D02*
X-265964Y246360D01*
G01X-270262Y245811D02*
X-270477Y245921D01*
G01X-248020Y245702D02*
X-248342Y245811D01*
G01X-249739Y245702D02*
X-250062Y245811D01*
G01X-260377Y248993D02*
X-260699Y249103D01*
G01X-257583Y245702D02*
X-257905Y245811D01*
G01X-265749Y245702D02*
X-266071Y245811D01*
G01X-252425Y249103D02*
X-252855Y249213D01*
G01X-252425Y248555D02*
X-252855Y248664D01*
G01X-260807D02*
X-261236Y248774D01*
G01X-253500Y245702D02*
X-253930Y245811D01*
G01X-268543Y249103D02*
X-268972Y249213D01*
G01X-257153Y246140D02*
X-257583Y246250D01*
G01X-268757Y248664D02*
X-269187Y248774D01*
G01X-265319Y246140D02*
X-265749Y246250D01*
G01X-269617Y246140D02*
X-270047Y246250D01*
G01X-269832Y245702D02*
X-270262Y245811D01*
G01X-260699Y249103D02*
X-261344Y249213D01*
G01X-261236Y246140D02*
X-261881Y246250D01*
G01X-261344Y245702D02*
X-261988Y245811D01*
G01X-254396Y253503D02*
X-264561Y254036D01*
G01X-254447Y252520D02*
X-264587Y253052D01*
G01X-238996Y254036D02*
X-236240D01*
G01Y253052D02*
X-238996D01*
G01X-251888Y250968D02*
X-251351D01*
G01X-245656Y249213D02*
X-245012D01*
G01X-242003D02*
X-241359D01*
G01X-247053D02*
X-246516D01*
G01X-248772D02*
X-248235D01*
G01X-250492D02*
X-249954D01*
G01X-253500D02*
X-252855D01*
G01X-256186D02*
X-255649D01*
G01X-258657D02*
X-258120D01*
G01X-264352D02*
X-263815D01*
G01X-266823D02*
X-266286D01*
G01X-269832D02*
X-268972D01*
G01X-272518D02*
X-271981D01*
G01X-269617Y248774D02*
X-269187D01*
G01X-253285Y248664D02*
X-252855D01*
G01X-262418Y248116D02*
X-262955D01*
G01X-244582Y247896D02*
X-242433D01*
G01X-244474Y247457D02*
X-242540D01*
G01X-262955D02*
X-260054D01*
G01X-262418Y247018D02*
X-260162D01*
G01X-252855Y246250D02*
X-253500D01*
G01X-247805Y246140D02*
X-247590D01*
G01X-249524D02*
X-249202D01*
G01X-269187D02*
X-269617D01*
G01X-265319Y245702D02*
X-265749D01*
G01X-268972D02*
X-269832D01*
G01X-263815D02*
X-264352D01*
G01X-257153D02*
X-257583D01*
G01X-252855D02*
X-253500D01*
G01X-251351D02*
X-251888D01*
G01X-249309D02*
X-249739D01*
G01X-247590D02*
X-248020D01*
G01X-246516D02*
X-247053D01*
G01X-271981Y244055D02*
X-272518D01*
G01X-255649D02*
X-256186D01*
G01X-243077D02*
X-243937D01*
G01X-253957Y236221D02*
X-255662D01*
G01X-248315D02*
X-250020D01*
G01X-242933Y233485D02*
X-244311D01*
G01X-242933Y225099D02*
X-244311D01*
G01X-242933Y211910D02*
X-244311D01*
G01X-242146Y329233D02*
G03X-242933Y330020I-787J0D01*
G01Y343209D02*
G03X-242146Y343996I0J787D01*
G01X-244311Y330020D02*
G03X-245099Y329233I0J-788D01*
G01Y343996D02*
G03X-244311Y343209I788J1D01*
G01X-242933Y321634D02*
G03X-242146Y322422I0J787D01*
G01X-245099D02*
G03X-244311Y321634I788J0D01*
G01X-250705Y303536D02*
G03X-251907Y303389I-507J-843D01*
G01X-254447Y302599D02*
G03X-253802Y302886I-51J983D01*
G01X-253071Y301575D02*
G03I-1575J0D01*
G01X-245197D02*
G03I-1575J0D01*
G01X-253957Y318898D02*
G03X-250020I1968J0D01*
G01X-254396Y301616D02*
G03X-253107Y302190I-103J1965D01*
G01X-250197Y304380D02*
G03X-252603Y304085I-1014J-1687D01*
G01X-254809Y318898D02*
G03X-249168I2820J0D01*
G01X-255662D02*
G03X-248315I3673J0D01*
G01X-257481Y276811D02*
G03X-257284Y277008I0J197D01*
G01Y278347D02*
G03X-257481Y278544I-197J0D01*
G01Y280512D02*
G03X-257284Y280709I0J197D01*
G01Y282048D02*
G03X-257481Y282244I-197J-1D01*
G01X-270689Y315748D02*
G03Y317717I0J984D01*
G01X-266851Y301575D02*
G03I-1574J0D01*
G01X-263583Y287953D02*
G03X-264173Y288544I-591J0D01*
G01X-263583Y282835D02*
G03X-262992Y282244I591J0D01*
G01X-251907Y303389D02*
X-253107Y302190D01*
G01X-252603Y304085D02*
X-253802Y302886D01*
G01X-247579Y302807D02*
X-248086Y301963D01*
G01X-249266Y303820D02*
X-249773Y302977D01*
G01X-242933Y343209D02*
X-244311D01*
G01X-236240Y301083D02*
Y302067D01*
G01X-236260Y299213D02*
Y374016D01*
G01X-237028Y301083D02*
Y302067D01*
G01X-238996Y301083D02*
Y372146D01*
G01X-241870Y302067D02*
Y301083D01*
G01X-242146Y329233D02*
Y322422D01*
G01Y350807D02*
Y343996D01*
G01X-242461Y302067D02*
Y301083D01*
G01X-244036Y302067D02*
Y301083D01*
G01X-244803D02*
Y302067D01*
G01X-245099Y329233D02*
Y322422D01*
G01Y350807D02*
Y343996D01*
G01X-245985Y302067D02*
Y301083D01*
G01X-246090Y302067D02*
Y301083D01*
G01X-246385D02*
Y302067D01*
G01X-246398D02*
Y301083D01*
G01X-242933Y330020D02*
X-244311D01*
G01X-242933Y321634D02*
X-244311D01*
G01X-253957Y318898D02*
X-255662D01*
G01X-248315D02*
X-250020D01*
G01X-238996Y302067D02*
X-236240D01*
G01Y301083D02*
X-238996D01*
G01X-257284Y285696D02*
X-273622D01*
G01X-251969Y285670D02*
X-257284D01*
G01Y285630D02*
X-243110D01*
G01X-257481Y282244D02*
X-262992D01*
G01X-259252Y276811D02*
X-257481D01*
G01X-254447Y302599D02*
X-264587Y302067D01*
G01X-254396Y301616D02*
X-264561Y301083D01*
G01X-247749Y302067D02*
Y301083D01*
G01X-248044D02*
Y302067D01*
G01X-248150D02*
Y301083D01*
G01X-248315Y354331D02*
Y318898D01*
G01X-249168Y354331D02*
Y318898D01*
G01X-249331Y302067D02*
Y301083D01*
G01X-250020Y318898D02*
Y354331D01*
G01X-252677Y301083D02*
Y302067D01*
G01X-253859D02*
Y301083D01*
G01X-253957Y354331D02*
Y318898D01*
G01X-253964Y302067D02*
Y301083D01*
G01X-254259D02*
Y302067D01*
G01X-254809Y318898D02*
Y354331D01*
G01X-255623Y302067D02*
Y301083D01*
G01X-255662Y354331D02*
Y318898D01*
G01X-255918Y301083D02*
Y302067D01*
G01X-256024D02*
Y301083D01*
G01X-257205Y302067D02*
Y301083D01*
G01X-257481Y280512D02*
Y278544D01*
G01Y284451D02*
Y282244D01*
G01X-263583Y282835D02*
Y287953D01*
G01X-264587Y302067D02*
Y301083D01*
G01X-265571Y302067D02*
Y301083D01*
G01X-266457D02*
Y302067D01*
G01X-267638D02*
Y301083D01*
G01X-267744Y302067D02*
Y301083D01*
G01X-268039D02*
Y302067D01*
G01X-269403D02*
Y301083D01*
G01X-269698D02*
Y302067D01*
G01X-269803D02*
Y301083D01*
G01X-270985Y302067D02*
Y301083D01*
G01X-260118Y290512D02*
X-257284Y283998D01*
G01X-247579Y302807D02*
X-250197Y304380D01*
G01X-248086Y301963D02*
X-250705Y303536D01*
G01X-204725Y409449D02*
G03X-208662Y405512I0J-3937D01*
G01X-242520Y394922D02*
G03X-242323Y395118I0J197D01*
G01Y396457D02*
G03X-242520Y396654I-197J0D01*
G01Y398622D02*
G03X-242323Y398819I0J197D01*
G01Y400158D02*
G03X-242520Y400355I-197J0D01*
G01X-248982Y388622D02*
G03X-248391Y389213I0J591D01*
G01X-248622Y406063D02*
G03X-249213Y406654I-591J0D01*
G01X-248622Y400945D02*
G03X-248032Y400355I590J0D01*
G01X-232284Y417323D02*
G03X-236221Y413386I0J-3937D01*
G01X-232284Y417323D02*
G03X-236221Y413386I0J-3937D01*
G01X-228150Y391536D02*
G03Y403740I0J6102D01*
G01X-241260Y371654D02*
G03I-1575J0D01*
G01X-212599Y372638D02*
G03X-208662Y376575I0J3937D01*
G01X-224410Y372638D02*
G03X-228347Y368701I0J-3937D01*
G01X-242146Y350807D02*
G03X-242933Y351595I-787J1D01*
G01X-253802Y370343D02*
G03X-254447Y370630I-696J-696D01*
G01X-251907Y369840D02*
G03X-250705Y369692I696J696D01*
G01X-270689Y355512D02*
G03Y357481I0J985D01*
G01X-253071Y371654D02*
G03I-1575J0D01*
G01X-266851D02*
G03I-1574J0D01*
G01X-250020Y354331D02*
G03X-253957I-1969J0D01*
G01X-252603Y369144D02*
G03X-250197Y368849I1392J1392D01*
G01X-253107Y371039D02*
G03X-254396Y371613I-1392J-1391D01*
G01X-249168Y354331D02*
G03X-254809I-2821J0D01*
G01X-248315D02*
G03X-255662I-3674J0D01*
G01X-244311Y351595D02*
G03X-245099Y350807I0J-788D01*
G01X-247268Y363921D02*
X-247590Y363812D01*
G01X-247268Y364360D02*
X-247590Y364251D01*
G01X-248987Y363921D02*
X-249309Y363812D01*
G01X-260377Y364031D02*
X-260699Y363921D01*
G01X-248987Y364360D02*
X-249202Y364251D01*
G01X-252210Y364031D02*
X-252425Y363921D01*
G01X-260592Y364470D02*
X-260807Y364360D01*
G01X-268328Y364031D02*
X-268543Y363921D01*
G01X-262096Y367213D02*
X-262525Y366994D01*
G01X-270262Y367213D02*
X-270477Y367103D01*
G01X-247579Y370422D02*
X-250197Y368849D01*
G01X-248086Y371266D02*
X-250705Y369692D01*
G01X-225197Y414764D02*
X-267717D01*
G01X-237008Y410827D02*
X-263780D01*
G01X-181103Y409449D02*
X-204725D01*
G01X-263780Y409213D02*
X-259843D01*
G01X-237008Y408819D02*
X-261418D01*
G01X-263386Y408622D02*
X-245158D01*
G01X-263780D02*
X-261418D01*
G01Y408071D02*
X-240945D01*
G01X-263780Y407737D02*
X-261811D01*
G01Y407490D02*
X-263445D01*
G01X-263151Y407244D02*
X-263486D01*
G01X-263780Y406654D02*
X-261418D01*
G01X-249213D02*
X-263386D01*
G01X-261811Y406063D02*
X-263780D01*
G01X-242323Y403806D02*
X-258662D01*
G01X-237008Y403780D02*
X-242323D01*
G01Y403740D02*
X-228150D01*
G01X-269832Y367323D02*
X-270262Y367213D01*
G01X-269617Y366884D02*
X-270047Y366774D01*
G01X-268757Y364360D02*
X-269187Y364251D01*
G01X-268543Y363921D02*
X-268972Y363812D01*
G01X-253500Y367323D02*
X-253930Y367213D01*
G01X-264889Y364360D02*
X-265319Y364251D01*
G01X-264889Y363921D02*
X-265319Y363812D01*
G01X-253285Y366774D02*
X-253715Y366665D01*
G01X-260807Y364360D02*
X-261236Y364251D01*
G01X-252103Y364690D02*
X-252425Y364470D01*
G01X-256401Y364141D02*
X-256723Y363921D01*
G01X-256401Y364580D02*
X-256723Y364360D01*
G01X-253715Y366665D02*
X-254037Y366445D01*
G01X-253930Y367213D02*
X-254252Y366994D01*
G01X-260054Y364251D02*
X-260377Y364031D01*
G01X-264567Y364141D02*
X-264889Y363921D01*
G01X-264567Y364580D02*
X-264889Y364360D01*
G01X-261988Y366774D02*
X-262310Y366555D01*
G01X-247604Y392559D02*
X-244292Y394922D01*
G01X-259843Y391181D02*
X-261811Y389213D01*
G01X-247053Y364141D02*
X-247268Y363921D01*
G01X-247053Y364580D02*
X-247268Y364360D01*
G01X-248665Y364251D02*
X-248987Y363921D01*
G01X-248880Y364470D02*
X-248987Y364360D01*
G01X-251996Y364251D02*
X-252210Y364031D01*
G01X-256186Y364360D02*
X-256401Y364141D01*
G01X-256186Y364799D02*
X-256401Y364580D01*
G01X-259839Y364470D02*
X-260054Y364251D01*
G01X-260269Y364799D02*
X-260592Y364470D01*
G01X-264352Y364360D02*
X-264567Y364141D01*
G01X-264352Y364799D02*
X-264567Y364580D01*
G01X-262525Y366994D02*
X-262848Y366665D01*
G01X-268113Y364251D02*
X-268328Y364031D01*
G01X-268543Y364580D02*
X-268757Y364360D01*
G01X-270047Y366774D02*
X-270262Y366555D01*
G01X-270477Y367103D02*
X-270692Y366884D01*
G01X-254252Y366994D02*
X-254682Y366445D01*
G01X-251888Y365019D02*
X-252103Y364690D01*
G01X-252425Y367213D02*
X-252855Y367323D01*
G01X-252425Y366665D02*
X-252855Y366774D01*
G01X-260807D02*
X-261236Y366884D01*
G01X-253500Y363812D02*
X-253930Y363921D01*
G01X-260699Y367213D02*
X-261344Y367323D01*
G01X-261236Y364251D02*
X-261881Y364360D01*
G01X-261344Y363812D02*
X-261988Y363921D01*
G01X-254396Y371613D02*
X-264561Y372146D01*
G01X-254447Y370630D02*
X-264587Y371162D01*
G01X-242520Y400355D02*
X-248032D01*
G01X-261811Y399213D02*
X-263780D01*
G01Y398622D02*
X-261418D01*
G01X-242520D02*
X-263386D01*
G01X-263780Y396654D02*
X-261418D01*
G01X-242520D02*
X-263386D01*
G01X-261811Y396063D02*
X-263780D01*
G01X-244292Y394922D02*
X-242520D01*
G01X-248391Y392559D02*
X-247604D01*
G01X-237599Y391536D02*
X-228150D01*
G01X-237599Y390748D02*
X-238386D01*
G01X-258662Y390626D02*
X-242323D01*
G01X-238386Y390158D02*
X-242323D01*
G01Y389608D02*
X-237008D01*
G01X-261811Y389213D02*
X-263780D01*
G01Y388622D02*
X-261418D01*
G01X-248982D02*
X-263386D01*
G01X-261418Y387205D02*
X-240945D01*
G01X-263780Y386654D02*
X-261418D01*
G01X-245236D02*
X-263386D01*
G01X-237008Y386457D02*
X-261418D01*
G01X-263780Y386063D02*
X-259843D01*
G01X-237008Y384449D02*
X-263780D01*
G01X-225197Y380512D02*
X-267717D01*
G01X-212599Y372638D02*
X-224410D01*
G01X-238996Y372146D02*
X-236240D01*
G01Y371162D02*
X-238996D01*
G01X-251888Y369079D02*
X-251351D01*
G01X-245656Y367323D02*
X-245012D01*
G01X-242003D02*
X-241359D01*
G01X-247053D02*
X-246516D01*
G01X-248772D02*
X-248235D01*
G01X-250492D02*
X-249954D01*
G01X-253500D02*
X-252855D01*
G01X-256186D02*
X-255649D01*
G01X-258657D02*
X-258120D01*
G01X-264352D02*
X-263815D01*
G01X-266823D02*
X-266286D01*
G01X-269832D02*
X-268972D01*
G01X-272518D02*
X-271981D01*
G01X-269617Y366884D02*
X-269187D01*
G01X-253285Y366774D02*
X-252855D01*
G01X-262418Y366226D02*
X-262955D01*
G01X-244582Y366006D02*
X-242433D01*
G01X-244474Y365567D02*
X-242540D01*
G01X-262955D02*
X-260054D01*
G01X-262418Y365128D02*
X-260162D01*
G01X-252855Y364360D02*
X-253500D01*
G01X-247805Y364251D02*
X-247590D01*
G01X-249524D02*
X-249202D01*
G01X-269187D02*
X-269617D01*
G01X-265319Y363812D02*
X-265749D01*
G01X-268972D02*
X-269832D01*
G01X-263815D02*
X-264352D01*
G01X-257153D02*
X-257583D01*
G01X-252855D02*
X-253500D01*
G01X-251351D02*
X-251888D01*
G01X-249309D02*
X-249739D01*
G01X-247590D02*
X-248020D01*
G01X-246516D02*
X-247053D01*
G01X-271981Y362166D02*
X-272518D01*
G01X-255649D02*
X-256186D01*
G01X-243077D02*
X-243937D01*
G01X-253957Y354331D02*
X-255662D01*
G01X-248315D02*
X-250020D01*
G01X-242933Y351595D02*
X-244311D01*
G01X-261344Y367323D02*
X-262096Y367213D01*
G01X-261236Y366884D02*
X-261988Y366774D01*
G01X-260699Y363921D02*
X-261344Y363812D01*
G01X-256723Y364360D02*
X-257153Y364251D01*
G01X-256723Y363921D02*
X-257153Y363812D01*
G01X-252425Y364470D02*
X-252855Y364360D01*
G01X-252425Y363921D02*
X-252855Y363812D01*
G01X-267898Y364580D02*
X-268113Y364251D01*
G01X-268328Y364909D02*
X-268543Y364580D01*
G01X-270262Y366555D02*
X-270477Y366226D01*
G01X-270692Y366884D02*
X-270907Y366555D01*
G01X-259843Y402756D02*
X-261811Y399213D01*
G01X-248772Y364690D02*
X-248880Y364470D01*
G01X-251888D02*
X-251996Y364251D01*
G01X-254037Y366445D02*
X-254145Y366226D01*
G01X-259624Y364909D02*
X-259839Y364470D01*
G01X-260162Y365019D02*
X-260269Y364799D01*
G01X-242323Y393347D02*
X-245236Y386654D01*
G01X-241359Y367323D02*
X-243077Y362166D01*
G01X-242540Y365567D02*
X-243507Y362605D01*
G01X-242003Y367323D02*
X-242433Y366006D01*
G01X-254145Y366226D02*
X-254252Y365897D01*
G01X-262310Y366555D02*
X-262418Y366226D01*
G01X-267790Y364909D02*
X-267898Y364580D01*
G01X-270907Y366555D02*
X-271122Y365787D01*
G01X-254682Y366445D02*
X-254789Y366006D01*
G01X-262848Y366665D02*
X-262955Y366226D01*
G01X-267683Y365348D02*
X-267790Y364909D01*
G01X-268220Y365348D02*
X-268328Y364909D01*
G01X-270477Y366226D02*
X-270584Y365787D01*
G01X-259517Y365567D02*
X-259624Y364909D01*
G01X-208662Y405512D02*
Y376575D01*
G01X-225197Y380512D02*
Y414764D01*
G01X-228150Y391536D02*
Y403740D01*
G01X-236240Y372146D02*
Y371162D01*
G01X-237008Y410827D02*
Y384449D01*
G01X-237028Y372146D02*
Y371162D01*
G01X-237599Y403740D02*
Y390779D01*
G01X-238386Y403740D02*
Y390195D01*
G01X-240866Y371162D02*
Y372146D01*
G01X-240945Y408071D02*
Y387205D01*
G01X-241870Y372146D02*
Y371162D01*
G01X-242047Y372146D02*
Y371162D01*
G01X-242153Y372146D02*
Y371162D01*
G01X-242323Y403740D02*
Y390195D01*
G01Y403806D02*
Y389608D01*
G01X-242448Y371162D02*
Y372146D01*
G01X-242461D02*
Y371162D01*
G01X-242520Y398622D02*
Y396654D01*
G01Y402561D02*
Y400355D01*
G01X-243812Y372146D02*
Y371162D01*
G01X-244036Y372146D02*
Y371162D01*
G01X-244107D02*
Y372146D01*
G01X-244213D02*
Y371162D01*
G01X-245394Y372146D02*
Y371162D01*
G01X-246398Y372146D02*
Y371162D01*
G01X-246516Y367323D02*
Y363812D01*
G01X-247053Y364580D02*
Y367323D01*
G01Y363812D02*
Y364141D01*
G01X-259624Y366226D02*
X-259517Y365567D01*
G01X-258657Y365128D02*
X-258550Y364580D01*
G01X-266286Y365238D02*
X-266179Y364690D01*
G01X-266823Y365238D02*
X-266716Y364690D01*
G01X-254789Y365128D02*
X-254682Y364690D01*
G01X-258120Y365128D02*
X-258013Y364690D01*
G01X-262955Y365128D02*
X-262848Y364690D01*
G01X-268328Y366226D02*
X-268220Y365787D01*
G01X-270584Y365348D02*
X-270477Y364909D01*
G01X-271122Y365348D02*
X-271014Y364909D01*
G01X-267898Y366555D02*
X-267683Y365787D01*
G01X-245012Y367323D02*
X-244582Y366006D01*
G01X-244474Y365567D02*
X-243507Y362605D01*
G01X-254252Y365238D02*
X-254145Y364909D01*
G01X-260162Y366116D02*
X-260054Y365787D01*
G01X-266716Y364690D02*
X-266609Y364360D01*
G01X-271014Y364909D02*
X-270907Y364580D01*
G01X-245656Y367323D02*
X-243937Y362166D01*
G01X-250492Y364690D02*
X-250277Y364141D01*
G01X-245158Y408622D02*
X-242323Y402109D01*
G01X-248235Y364690D02*
X-248127Y364470D01*
G01X-249954Y364690D02*
X-249847Y364470D01*
G01X-251996Y366884D02*
X-251888Y366665D01*
G01X-254682Y364690D02*
X-254574Y364470D01*
G01X-258550Y364580D02*
X-258442Y364360D01*
G01X-259839Y366665D02*
X-259624Y366226D01*
G01X-260269Y366335D02*
X-260162Y366116D01*
G01X-261811Y396063D02*
X-259843Y392520D01*
G01X-248086Y371266D02*
X-247579Y370422D01*
G01X-249773Y370252D02*
X-249266Y369409D01*
G01X-252103Y366445D02*
X-251888Y366116D01*
G01X-254145Y364909D02*
X-253930Y364580D01*
G01X-262418Y364909D02*
X-262203Y364580D01*
G01X-268113Y366884D02*
X-267898Y366555D01*
G01X-268543D02*
X-268328Y366226D01*
G01X-270477Y364909D02*
X-270262Y364580D01*
G01X-270907D02*
X-270692Y364251D01*
G01X-262848Y364690D02*
X-262525Y364251D01*
G01X-261811Y406063D02*
X-259843Y403701D01*
G01X-248020Y364360D02*
X-248127Y364470D01*
G01X-248342Y363921D02*
X-248665Y364251D01*
G01X-251996Y366884D02*
X-252210Y367103D01*
G01X-249739Y364360D02*
X-249847Y364470D01*
G01X-250062Y363921D02*
X-250277Y364141D01*
G01X-254252D02*
X-254574Y364470D01*
G01X-259839Y366665D02*
X-260054Y366884D01*
G01X-257798Y364470D02*
X-258013Y364690D01*
G01X-260269Y366335D02*
X-260592Y366665D01*
G01X-258228Y364141D02*
X-258442Y364360D01*
G01X-268113Y366884D02*
X-268328Y367103D01*
G01X-265964Y364470D02*
X-266179Y364690D01*
G01X-268543Y366555D02*
X-268757Y366774D01*
G01X-266394Y364141D02*
X-266609Y364360D01*
G01X-270047D02*
X-270262Y364580D01*
G01X-270477Y364031D02*
X-270692Y364251D01*
G01X-251907Y369840D02*
X-253107Y371039D01*
G01X-252603Y369144D02*
X-253802Y370343D01*
G01X-263445Y407490D02*
X-263151Y407244D01*
G01X-263486D02*
X-263780Y407490D01*
G01X-252103Y366445D02*
X-252425Y366665D01*
G01X-253930Y363921D02*
X-254252Y364141D01*
G01X-260054Y366884D02*
X-260377Y367103D01*
G01X-257905Y363921D02*
X-258228Y364141D01*
G01X-261881Y364360D02*
X-262203Y364580D01*
G01X-266071Y363921D02*
X-266394Y364141D01*
G01X-261988Y363921D02*
X-262525Y364251D01*
G01X-252210Y367103D02*
X-252425Y367213D01*
G01X-247805Y364251D02*
X-248020Y364360D01*
G01X-249524Y364251D02*
X-249739Y364360D01*
G01X-253500D02*
X-253930Y364580D01*
G01X-260592Y366665D02*
X-260807Y366774D01*
G01X-257583Y364360D02*
X-257798Y364470D01*
G01X-268328Y367103D02*
X-268543Y367213D01*
G01X-265749Y364360D02*
X-265964Y364470D01*
G01X-270262Y363921D02*
X-270477Y364031D01*
G01X-248020Y363812D02*
X-248342Y363921D01*
G01X-249739Y363812D02*
X-250062Y363921D01*
G01X-260377Y367103D02*
X-260699Y367213D01*
G01X-257583Y363812D02*
X-257905Y363921D01*
G01X-265749Y363812D02*
X-266071Y363921D01*
G01X-268543Y367213D02*
X-268972Y367323D01*
G01X-257153Y364251D02*
X-257583Y364360D01*
G01X-268757Y366774D02*
X-269187Y366884D01*
G01X-265319Y364251D02*
X-265749Y364360D01*
G01X-269617Y364251D02*
X-270047Y364360D01*
G01X-269832Y363812D02*
X-270262Y363921D01*
G01X-248235Y367323D02*
Y364690D01*
G01X-248391Y389213D02*
Y392559D01*
G01X-248622Y400945D02*
Y406063D01*
G01X-248772Y364690D02*
Y367323D01*
G01X-249954D02*
Y364690D01*
G01X-250492D02*
Y367323D01*
G01X-251351Y369079D02*
Y363812D01*
G01X-251888Y366665D02*
Y369079D01*
G01Y363812D02*
Y364470D01*
G01Y366116D02*
Y365019D01*
G01X-252677Y371162D02*
Y372146D01*
G01X-253859D02*
Y371162D01*
G01X-253964Y372146D02*
Y371162D01*
G01X-254252Y365238D02*
Y365897D01*
G01X-254259Y371162D02*
Y372146D01*
G01X-254789Y365128D02*
Y366006D01*
G01X-255623Y372146D02*
Y371162D01*
G01X-255649Y367323D02*
Y362166D01*
G01X-255918Y371162D02*
Y372146D01*
G01X-256024D02*
Y371162D01*
G01X-256186Y364799D02*
Y367323D01*
G01Y362166D02*
Y364360D01*
G01X-257205Y372146D02*
Y371162D01*
G01X-258120Y367323D02*
Y365128D01*
G01X-258657D02*
Y367323D01*
G01X-258662Y403806D02*
Y390626D01*
G01X-259843Y409213D02*
Y386063D01*
G01X-260054Y365567D02*
Y365787D01*
G01X-260162Y365128D02*
Y365019D01*
G01X-261418Y388622D02*
Y386654D01*
G01Y389607D02*
Y386063D01*
G01Y398622D02*
Y396654D01*
G01Y399922D02*
Y395355D01*
G01Y408622D02*
Y406654D01*
G01Y409213D02*
Y405591D01*
G01X-261811Y407737D02*
Y407490D01*
G01X-262418Y364909D02*
Y365128D01*
G01X-262638Y406654D02*
Y408622D01*
G01Y396654D02*
Y398622D01*
G01Y386654D02*
Y388622D01*
G01X-262955Y365128D02*
Y365567D01*
G01X-263386Y388622D02*
Y386654D01*
G01Y398622D02*
Y396654D01*
G01Y408622D02*
Y406654D01*
G01X-263780Y407490D02*
Y407737D01*
G01Y386654D02*
Y384449D01*
G01Y396654D02*
Y388622D01*
G01Y406654D02*
Y398622D01*
G01Y410827D02*
Y408622D01*
G01X-263815Y367323D02*
Y363812D01*
G01X-264352Y364799D02*
Y367323D01*
G01Y363812D02*
Y364360D01*
G01X-264587Y372146D02*
Y371162D01*
G01X-265571Y372146D02*
Y371162D01*
G01X-266286Y367323D02*
Y365238D01*
G01X-266457Y371162D02*
Y372146D01*
G01X-266823Y365238D02*
Y367323D01*
G01X-267638Y372146D02*
Y371162D01*
G01X-267683Y365787D02*
Y365348D01*
G01X-267717Y414764D02*
Y380512D01*
G01X-267744Y372146D02*
Y371162D01*
G01X-268039D02*
Y372146D01*
G01X-268220Y365787D02*
Y365348D01*
G01X-269403Y372146D02*
Y371162D01*
G01X-269698D02*
Y372146D01*
G01X-269803D02*
Y371162D01*
G01X-270584Y365348D02*
Y365787D01*
G01X-270985Y372146D02*
Y371162D01*
G01X-271122Y365348D02*
Y365787D01*
G01X-271654Y589882D02*
Y385158D01*
G01X-271981Y367323D02*
Y362166D01*
G01X-272518D02*
Y367323D01*
G01X-232284Y417323D02*
X-181103D01*
G01X-232284D02*
X-181103D01*
G01X-204557Y619100D02*
X-203327D01*
G01X-203737Y617424D02*
X-205377D01*
G01Y619519D02*
X-204557Y619100D01*
G01X-205377Y617424D02*
X-206608Y617843D01*
G01X-205788Y619937D02*
X-205377Y619519D01*
G01X-206608Y617843D02*
X-207428Y618681D01*
G01D02*
X-208248Y620775D01*
G01X-206197D02*
X-205788Y619937D01*
G01X-206197Y630827D02*
Y620775D01*
G01X-208248D02*
Y630827D01*
G01X-202507Y617843D02*
X-203737Y617424D01*
G01X-198780Y655512D02*
G03I-3937J0D01*
G01X-220433Y647638D02*
G03I-7874J0D01*
G01X-208248Y630827D02*
X-206197D01*
G01X-236221Y716536D02*
G03X-232284Y712599I3937J0D01*
G01X-224410Y724410D02*
G03X-220473Y720473I3937J0D01*
G01X-236221Y716536D02*
G03X-232284Y712599I3937J0D01*
G01X-220473Y720473D02*
X-96418D01*
G01Y712599D02*
X-232284D01*
G01X-96418D02*
X-232284D01*
G01X-224410Y933071D02*
Y724410D01*
G01X-236221Y921260D02*
Y716536D01*
G01X-240158Y762402D02*
Y796654D01*
G01X-251969Y792717D02*
Y766339D01*
G01X-257607Y826772D02*
G03I-1594J0D01*
G01Y834646D02*
G03I-1594J0D01*
G01X-265481Y826772D02*
G03I-1594J0D01*
G01Y834646D02*
G03I-1594J0D01*
G01X-257481Y776811D02*
G03X-257284Y777008I0J197D01*
G01Y778347D02*
G03X-257481Y778544I-197J0D01*
G01Y780512D02*
G03X-257284Y780709I0J197D01*
G01Y782048D02*
G03X-257481Y782244I-197J-1D01*
G01X-263942Y770512D02*
G03X-263352Y771103I-1J591D01*
G01X-263583Y787953D02*
G03X-264173Y788544I-591J0D01*
G01X-263583Y782835D02*
G03X-262992Y782244I591J0D01*
G01X-257607Y818898D02*
G03I-1594J0D01*
G01X-265481D02*
G03I-1594J0D01*
G01X-243110Y773426D02*
G03Y785630I0J6102D01*
G01X-234201Y837520D02*
X-247701D01*
G01X-268075Y835645D02*
X-251701D01*
G01X-235301D02*
X-246701D01*
G01Y835520D02*
X-234201D01*
G01X-267475Y835045D02*
X-266675D01*
G01X-258801D02*
X-259601D01*
G01X-266675Y834245D02*
X-267475D01*
G01X-258801D02*
X-259601D01*
G01X-246701Y833645D02*
X-235301D01*
G01X-251701D02*
X-268075D01*
G01Y827771D02*
X-251701D01*
G01X-235301D02*
X-246701D01*
G01X-267475Y827171D02*
X-266675D01*
G01X-258801D02*
X-259601D01*
G01X-266675Y826371D02*
X-267475D01*
G01X-258801D02*
X-259601D01*
G01X-246701Y825771D02*
X-235301D01*
G01X-251701D02*
X-268075D01*
G01X-258474Y820670D02*
X-257938D01*
G01X-266387D02*
X-265851D01*
G01X-260618Y820276D02*
X-258005D01*
G01X-268532D02*
X-265918D01*
G01X-268075Y819897D02*
X-251701D01*
G01X-235301D02*
X-246701D01*
G01X-265382Y819882D02*
X-268532D01*
G01X-257469D02*
X-260618D01*
G01X-259680Y819357D02*
X-259278D01*
G01X-267475Y819297D02*
X-266675D01*
G01X-258801D02*
X-259601D01*
G01X-267259Y817061D02*
X-267526Y816995D01*
G01X-265851Y817126D02*
X-266119Y817061D01*
G01X-267794Y816995D02*
X-267996Y817061D01*
G01X-266119Y819292D02*
X-265851Y819226D01*
G01X-266253Y817061D02*
X-266521Y817126D01*
G01X-266675Y818497D02*
X-267475D01*
G01X-258801D02*
X-259601D01*
G01X-267057Y818307D02*
X-266789D01*
G01X-246701Y817897D02*
X-235301D01*
G01X-251701D02*
X-268075D01*
G01X-260618Y817783D02*
X-259680D01*
G01X-258005D02*
X-259278D01*
G01X-266253Y817389D02*
X-266119D01*
G01X-257469D02*
X-259278D01*
G01X-259680D02*
X-260618D01*
G01X-267794Y817323D02*
X-267526D01*
G01X-266119Y817061D02*
X-266253D01*
G01X-267526Y816995D02*
X-267794D01*
G01X-259278Y816733D02*
X-259680D01*
G01X-253201Y813771D02*
X-234201D01*
G01Y810271D02*
X-253201D01*
G01X-234201Y808302D02*
X-270044D01*
G01X-257284Y785696D02*
X-273622D01*
G01X-251969Y785670D02*
X-257284D01*
G01Y785630D02*
X-243110D01*
G01X-257481Y782244D02*
X-262992D01*
G01X-259252Y776811D02*
X-257481D01*
G01X-263352Y774449D02*
X-262564D01*
G01X-252559Y773426D02*
X-243110D01*
G01X-252559Y772638D02*
X-253347D01*
G01X-273622Y772515D02*
X-257284D01*
G01X-253347Y772048D02*
X-257284D01*
G01Y771498D02*
X-251969D01*
G01X-265918Y818832D02*
X-266119Y818964D01*
G01X-237665Y813771D02*
X-234201Y811771D01*
G01X-266521Y817520D02*
X-266253Y817389D01*
G01X-267929D02*
X-267794Y817323D01*
G01X-234701Y835045D02*
X-235301Y835645D01*
G01X-234701Y827171D02*
X-235301Y827771D01*
G01X-234701Y819297D02*
X-235301Y819897D01*
G01X-259601Y835045D02*
X-260201Y835645D01*
G01X-258201Y833645D02*
X-258801Y834245D01*
G01X-266075Y833645D02*
X-266675Y834245D01*
G01X-259601Y827171D02*
X-260201Y827771D01*
G01X-258201Y825771D02*
X-258801Y826371D01*
G01X-268075Y835645D02*
X-267475Y835045D01*
G01X-266075Y825771D02*
X-266675Y826371D01*
G01X-259601Y819297D02*
X-260201Y819897D01*
G01X-258201Y817897D02*
X-258801Y818497D01*
G01X-268075Y827771D02*
X-267475Y827171D01*
G01X-265851Y819226D02*
X-265583Y818964D01*
G01X-266655Y817651D02*
X-266521Y817520D01*
G01X-268062D02*
X-267929Y817389D01*
G01X-259278Y818898D02*
X-258005Y817783D01*
G01X-259278Y819357D02*
X-257469Y817783D01*
G01X-257938Y820670D02*
X-257469Y820276D01*
G01X-258005D02*
X-258474Y820670D01*
G01X-265851D02*
X-265382Y820276D01*
G01X-265918D02*
X-266387Y820670D01*
G01X-266521Y817126D02*
X-266722Y817257D01*
G01X-267996Y817061D02*
X-268197Y817192D01*
G01X-266722Y817257D02*
X-266923Y817520D01*
G01X-266075Y817897D02*
X-266675Y818497D01*
G01X-268075Y819897D02*
X-267475Y819297D01*
G01X-265583Y818964D02*
X-265449Y818701D01*
G01X-268129Y817651D02*
X-268062Y817520D01*
G01X-268331Y817389D02*
X-268464Y817651D01*
G01X-265784Y818635D02*
X-265918Y818832D01*
G01X-268197Y817192D02*
X-268331Y817389D01*
G01X-268464Y817651D02*
X-268532Y817914D01*
G01X-266789Y818045D02*
X-266655Y817651D01*
G01X-260118Y790512D02*
X-257284Y783998D01*
G01X-265449Y818701D02*
X-265382Y818242D01*
G01X-265717Y818307D02*
X-265784Y818635D01*
G01X-268197Y817979D02*
X-268129Y817651D01*
G01X-234201Y808302D02*
Y876737D01*
G01Y810271D02*
Y874769D01*
G01X-234701Y834245D02*
Y835045D01*
G01Y826371D02*
Y827171D01*
G01Y818497D02*
Y819297D01*
G01X-235301Y819897D02*
Y817897D01*
G01Y827771D02*
Y825771D01*
G01Y835645D02*
Y833645D01*
G01X-237665Y813771D02*
Y871269D01*
G01X-243110Y773426D02*
Y785630D01*
G01X-245701Y837520D02*
Y847520D01*
G01X-246701Y871269D02*
Y813771D01*
G01X-265382Y818111D02*
X-265449Y817651D01*
G01X-247701Y813771D02*
Y871269D01*
G01X-251701D02*
Y813771D01*
G01X-252559Y785630D02*
Y772669D01*
G01X-253201Y810271D02*
Y813771D01*
G01X-253347Y785630D02*
Y772085D01*
G01X-255906Y789961D02*
Y769095D01*
G01X-256201Y819897D02*
Y817897D01*
G01Y827771D02*
Y825771D01*
G01Y835645D02*
Y833645D01*
G01X-257284Y785630D02*
Y772085D01*
G01Y785696D02*
Y771498D01*
G01X-257469Y817783D02*
Y817389D01*
G01Y820276D02*
Y819882D01*
G01X-257481Y780512D02*
Y778544D01*
G01Y784451D02*
Y782244D01*
G01X-258201Y819897D02*
Y817897D01*
G01Y827771D02*
Y825771D01*
G01Y835645D02*
Y833645D01*
G01X-258801Y819297D02*
Y818497D01*
G01Y827171D02*
Y826371D01*
G01Y835045D02*
Y834245D01*
G01X-259278Y817783D02*
Y818898D01*
G01Y817389D02*
Y816733D01*
G01X-259601Y819297D02*
Y818497D01*
G01Y827171D02*
Y826371D01*
G01Y835045D02*
Y834245D01*
G01X-259680Y816733D02*
Y817389D01*
G01Y817783D02*
Y819357D01*
G01X-260201Y833645D02*
Y835645D01*
G01Y825771D02*
Y827771D01*
G01Y817897D02*
Y819897D01*
G01X-260618Y817389D02*
Y817783D01*
G01Y819882D02*
Y820276D01*
G01X-263352Y771103D02*
Y774449D01*
G01X-263583Y782835D02*
Y787953D01*
G01X-264075Y819897D02*
Y817897D01*
G01Y827771D02*
Y825771D01*
G01Y835645D02*
Y833645D01*
G01X-265382Y818242D02*
Y818111D01*
G01Y820276D02*
Y819882D01*
G01X-265717Y818045D02*
Y818307D01*
G01X-266075Y819897D02*
Y817897D01*
G01Y827771D02*
Y825771D01*
G01Y835645D02*
Y833645D01*
G01X-266119Y818964D02*
Y819292D01*
G01X-266675Y819297D02*
Y818497D01*
G01Y827171D02*
Y826371D01*
G01Y835045D02*
Y834245D01*
G01X-266789Y818307D02*
Y818045D01*
G01X-267057D02*
Y818307D01*
G01X-267475Y819297D02*
Y818497D01*
G01Y827171D02*
Y826371D01*
G01Y835045D02*
Y834245D01*
G01X-267794Y819357D02*
Y819029D01*
G01X-268075Y833645D02*
Y835645D01*
G01Y825771D02*
Y827771D01*
G01Y817897D02*
Y819897D01*
G01X-268197Y818373D02*
Y817979D01*
G01X-268532Y817914D02*
Y818439D01*
G01Y819882D02*
Y820276D01*
G01X-270044Y808302D02*
Y876737D01*
G01X-273622Y785696D02*
Y772515D01*
G01X-257284Y775237D02*
X-260197Y768544D01*
G01X-268532Y818439D02*
X-268464Y818701D01*
G01X-265784Y817717D02*
X-265717Y818045D01*
G01X-268129Y818701D02*
X-268197Y818373D01*
G01X-267124Y817651D02*
X-267057Y818045D01*
G01X-235301Y817897D02*
X-234701Y818497D01*
G01X-265918Y817520D02*
X-265784Y817717D01*
G01X-267259Y817454D02*
X-267124Y817651D01*
G01X-268331Y818964D02*
X-268197Y819161D01*
G01X-265449Y817651D02*
X-265583Y817389D01*
G01X-268062Y818832D02*
X-268129Y818701D01*
G01X-268464D02*
X-268331Y818964D01*
G01X-266923Y817520D02*
X-267057Y817192D01*
G01X-267996Y819292D02*
X-267794Y819357D01*
G01X-267526Y817323D02*
X-267259Y817454D01*
G01X-267794Y819029D02*
X-267929Y818964D01*
G01X-266119Y817389D02*
X-265918Y817520D01*
G01X-267057Y817192D02*
X-267259Y817061D01*
G01X-268197Y819161D02*
X-267996Y819292D01*
G01X-262564Y774449D02*
X-259252Y776811D01*
G01X-265583Y817389D02*
X-265851Y817126D01*
G01X-267929Y818964D02*
X-268062Y818832D01*
G01X-235301Y825771D02*
X-234701Y826371D01*
G01X-235301Y833645D02*
X-234701Y834245D01*
G01X-258201Y819897D02*
X-258801Y819297D01*
G01X-259601Y818497D02*
X-260201Y817897D01*
G01X-266675Y819297D02*
X-266075Y819897D01*
G01X-267475Y818497D02*
X-268075Y817897D01*
G01X-258201Y827771D02*
X-258801Y827171D01*
G01X-259601Y826371D02*
X-260201Y825771D01*
G01X-266675Y827171D02*
X-266075Y827771D01*
G01X-267475Y826371D02*
X-268075Y825771D01*
G01X-258201Y835645D02*
X-258801Y835045D01*
G01X-259601Y834245D02*
X-260201Y833645D01*
G01X-266675Y835045D02*
X-266075Y835645D01*
G01X-267475Y834245D02*
X-268075Y833645D01*
G01X-257607Y842520D02*
G03I-1594J0D01*
G01Y850394D02*
G03I-1594J0D01*
G01Y858268D02*
G03I-1594J0D01*
G01Y866142D02*
G03I-1594J0D01*
G01X-265481Y842520D02*
G03I-1594J0D01*
G01Y850394D02*
G03I-1594J0D01*
G01Y858268D02*
G03I-1594J0D01*
G01Y866142D02*
G03I-1594J0D01*
G01X-267298Y868150D02*
X-267633Y868084D01*
G01X-258009Y865512D02*
X-257741Y865446D01*
G01X-258210Y868399D02*
X-258545Y868465D01*
G01X-266360Y868084D02*
X-266695Y868150D01*
G01X-259483Y866168D02*
X-259148Y866103D01*
G01X-267633Y865853D02*
X-267298Y865788D01*
G01X-258210Y868071D02*
X-258612Y868137D01*
G01X-266360Y867756D02*
X-266762Y867822D01*
G01X-259483Y866496D02*
X-259081Y866431D01*
G01X-267633Y866181D02*
X-267231Y866116D01*
G01X-234201Y876737D02*
X-270044D01*
G01X-234201Y874769D02*
X-253201D01*
G01X-234201Y871269D02*
X-253201D01*
G01X-258545Y868465D02*
X-259148D01*
G01X-266695Y868150D02*
X-267298D01*
G01X-258612Y868137D02*
X-259081D01*
G01X-266762Y867822D02*
X-267231D01*
G01X-268075Y867141D02*
X-251701D01*
G01X-235301D02*
X-246701D01*
G01X-267475Y866541D02*
X-266675D01*
G01X-258801D02*
X-259601D01*
G01X-259081Y866431D02*
X-258612D01*
G01X-267231Y866116D02*
X-266762D01*
G01X-259148Y866103D02*
X-258545D01*
G01X-267298Y865788D02*
X-266695D01*
G01X-266675Y865741D02*
X-267475D01*
G01X-258801D02*
X-259601D01*
G01X-260422Y865578D02*
X-260086D01*
G01X-266427Y865263D02*
X-265890D01*
G01X-246701Y865141D02*
X-235301D01*
G01X-251701D02*
X-268075D01*
G01X-268571Y864869D02*
X-265957D01*
G01X-265422Y864476D02*
X-268571D01*
G01X-258143Y863609D02*
X-258009D01*
G01Y863216D02*
X-258143D01*
G01X-260086D02*
X-260422D01*
G01X-268075Y859267D02*
X-251701D01*
G01X-235301D02*
X-246701D01*
G01X-267475Y858667D02*
X-266675D01*
G01X-258801D02*
X-259601D01*
G01X-266675Y857867D02*
X-267475D01*
G01X-258801D02*
X-259601D01*
G01X-246701Y857267D02*
X-235301D01*
G01X-251701D02*
X-268075D01*
G01Y851393D02*
X-251701D01*
G01X-235301D02*
X-246701D01*
G01X-267475Y850793D02*
X-266675D01*
G01X-258801D02*
X-259601D01*
G01X-266675Y849993D02*
X-267475D01*
G01X-258801D02*
X-259601D01*
G01X-234201Y849520D02*
X-246701D01*
G01Y849393D02*
X-235301D01*
G01X-251701D02*
X-268075D01*
G01X-247701Y847520D02*
X-234201D01*
G01X-268075Y843519D02*
X-251701D01*
G01X-235301D02*
X-246701D01*
G01X-267475Y842919D02*
X-266675D01*
G01X-258801D02*
X-259601D01*
G01X-266675Y842119D02*
X-267475D01*
G01X-258801D02*
X-259601D01*
G01X-246701Y841519D02*
X-235301D01*
G01X-260201D02*
X-266075D01*
G01X-251701D02*
X-268075D01*
G01X-267231Y867822D02*
X-267633Y867756D01*
G01X-259081Y868137D02*
X-259483Y868071D01*
G01X-266762Y866116D02*
X-266360Y866181D01*
G01X-258612Y866431D02*
X-258210Y866496D01*
G01X-259148Y868465D02*
X-259483Y868399D01*
G01X-266695Y865788D02*
X-266360Y865853D01*
G01X-258545Y866103D02*
X-258210Y866168D01*
G01X-257741Y863281D02*
X-258009Y863216D01*
G01X-257741Y868202D02*
X-258009Y868334D01*
G01X-259952Y866365D02*
X-259684Y866234D01*
G01X-265890Y867887D02*
X-266159Y868019D01*
G01X-258411Y863740D02*
X-258143Y863609D01*
G01X-268102Y866050D02*
X-267834Y865919D01*
G01X-234201Y863641D02*
X-240236Y866141D01*
G01X-258009Y868334D02*
X-258210Y868399D01*
G01X-259684Y866234D02*
X-259483Y866168D01*
G01X-266159Y868019D02*
X-266360Y868084D01*
G01X-267834Y865919D02*
X-267633Y865853D01*
G01X-258143Y863216D02*
X-258411Y863281D01*
G01X-257808Y867809D02*
X-258210Y868071D01*
G01X-259885Y866759D02*
X-259483Y866496D01*
G01X-257808Y865053D02*
X-258009Y865184D01*
G01X-258411Y863281D02*
X-258612Y863413D01*
G01X-265957Y867494D02*
X-266360Y867756D01*
G01X-268035Y866444D02*
X-267633Y866181D01*
G01X-258612Y863413D02*
X-260086Y865053D01*
G01Y865578D02*
X-258411Y863740D01*
G01X-234701Y866541D02*
X-235301Y867141D01*
G01X-234701Y858667D02*
X-235301Y859267D01*
G01X-234701Y850793D02*
X-235301Y851393D01*
G01X-234701Y842919D02*
X-235301Y843519D01*
G01X-259601Y866541D02*
X-260201Y867141D01*
G01X-258201Y865141D02*
X-258801Y865741D01*
G01X-266075Y865141D02*
X-266675Y865741D01*
G01X-259601Y858667D02*
X-260201Y859267D01*
G01X-258201Y857267D02*
X-258801Y857867D01*
G01X-268075Y867141D02*
X-267475Y866541D01*
G01X-266075Y857267D02*
X-266675Y857867D01*
G01X-259601Y850793D02*
X-260201Y851393D01*
G01X-258201Y849393D02*
X-258801Y849993D01*
G01X-268075Y859267D02*
X-267475Y858667D01*
G01X-266075Y849393D02*
X-266675Y849993D01*
G01X-259601Y842919D02*
X-260201Y843519D01*
G01X-258201Y841519D02*
X-258801Y842119D01*
G01X-268075Y851393D02*
X-267475Y850793D01*
G01X-266075Y841519D02*
X-266675Y842119D01*
G01X-268075Y843519D02*
X-267475Y842919D01*
G01X-257540Y868005D02*
X-257741Y868202D01*
G01Y865446D02*
X-257473Y865184D01*
G01X-260153Y866562D02*
X-259952Y866365D01*
G01X-265689Y867690D02*
X-265890Y867887D01*
G01X-268303Y866247D02*
X-268102Y866050D01*
G01X-265890Y865263D02*
X-265422Y864869D01*
G01X-265957D02*
X-266427Y865263D01*
G01X-257339Y867677D02*
X-257540Y868005D01*
G01X-260354Y866890D02*
X-260153Y866562D01*
G01X-265488Y867363D02*
X-265689Y867690D01*
G01X-268504Y866575D02*
X-268303Y866247D01*
G01X-257674Y867612D02*
X-257808Y867809D01*
G01X-257674Y864856D02*
X-257808Y865053D01*
G01X-260019Y866956D02*
X-259885Y866759D01*
G01X-265823Y867297D02*
X-265957Y867494D01*
G01X-268169Y866641D02*
X-268035Y866444D01*
G01X-257473Y865184D02*
X-257339Y864922D01*
G01X-257607Y867284D02*
X-257674Y867612D01*
G01X-257607Y864528D02*
X-257674Y864856D01*
G01X-260086Y867284D02*
X-260019Y866956D01*
G01X-257339Y864922D02*
X-257272Y864462D01*
G01Y867284D02*
X-257339Y867677D01*
G01X-260422Y867284D02*
X-260354Y866890D01*
G01X-265422Y866969D02*
X-265488Y867363D01*
G01X-268571Y866969D02*
X-268504Y866575D01*
G01X-265757Y866969D02*
X-265823Y867297D01*
G01X-268236Y866969D02*
X-268169Y866641D01*
G01X-234701Y865741D02*
Y866541D01*
G01Y857867D02*
Y858667D01*
G01Y849993D02*
Y850793D01*
G01Y842119D02*
Y842919D01*
G01X-235301Y843519D02*
Y841519D01*
G01Y851393D02*
Y849393D01*
G01Y859267D02*
Y857267D01*
G01Y867141D02*
Y865141D01*
G01X-253201Y874769D02*
Y871269D01*
G01X-256201Y843519D02*
Y841519D01*
G01Y851393D02*
Y849393D01*
G01Y859267D02*
Y857267D01*
G01Y867141D02*
Y865141D01*
G01X-257272Y864462D02*
Y864200D01*
G01X-257607Y864265D02*
Y864528D01*
G01X-258009Y865184D02*
Y865512D01*
G01X-258201Y843519D02*
Y841519D01*
G01Y851393D02*
Y849393D01*
G01Y859267D02*
Y857267D01*
G01Y867141D02*
Y865141D01*
G01X-258801Y842919D02*
Y842119D01*
G01Y850793D02*
Y849993D01*
G01Y858667D02*
Y857867D01*
G01Y866541D02*
Y865741D01*
G01X-259601Y842919D02*
Y842119D01*
G01Y850793D02*
Y849993D01*
G01Y858667D02*
Y857867D01*
G01Y866541D02*
Y865741D01*
G01X-260086Y865053D02*
Y863216D01*
G01X-260201Y865141D02*
Y867141D01*
G01Y857267D02*
Y859267D01*
G01Y849393D02*
Y851393D01*
G01Y841519D02*
Y843519D01*
G01X-260422Y863216D02*
Y865578D01*
G01X-264075Y843519D02*
Y841519D01*
G01Y851393D02*
Y849393D01*
G01Y859267D02*
Y857267D01*
G01Y867141D02*
Y865141D01*
G01X-265422Y864869D02*
Y864476D01*
G01X-266075Y843519D02*
Y841519D01*
G01Y851393D02*
Y849393D01*
G01Y859267D02*
Y857267D01*
G01Y867141D02*
Y865141D01*
G01X-266675Y842919D02*
Y842119D01*
G01Y850793D02*
Y849993D01*
G01Y858667D02*
Y857867D01*
G01Y866541D02*
Y865741D01*
G01X-267475Y842919D02*
Y842119D01*
G01Y850793D02*
Y849993D01*
G01Y858667D02*
Y857867D01*
G01Y866541D02*
Y865741D01*
G01X-268075Y865141D02*
Y867141D01*
G01Y857267D02*
Y859267D01*
G01Y849393D02*
Y851393D01*
G01Y841519D02*
Y843519D01*
G01X-268571Y864476D02*
Y864869D01*
G01X-257674Y863937D02*
X-257607Y864265D01*
G01X-257674Y866956D02*
X-257607Y867284D01*
G01X-260019Y867612D02*
X-260086Y867284D01*
G01X-265823Y866641D02*
X-265757Y866969D01*
G01X-268169Y867297D02*
X-268236Y866969D01*
G01X-257272Y864200D02*
X-257339Y863806D01*
G01Y866890D02*
X-257272Y867284D01*
G01X-260354Y867677D02*
X-260422Y867284D01*
G01X-265488Y866575D02*
X-265422Y866969D01*
G01X-268504Y867363D02*
X-268571Y866969D01*
G01X-257540Y866562D02*
X-257339Y866890D01*
G01X-260153Y868005D02*
X-260354Y867677D01*
G01X-265689Y866247D02*
X-265488Y866575D01*
G01X-257339Y863806D02*
X-257473Y863544D01*
G01D02*
X-257741Y863281D01*
G01Y866365D02*
X-257540Y866562D01*
G01X-259952Y868202D02*
X-260153Y868005D01*
G01X-265890Y866050D02*
X-265689Y866247D01*
G01X-268102Y867887D02*
X-268303Y867690D01*
G01X-235301Y841519D02*
X-234701Y842119D01*
G01X-235301Y849393D02*
X-234701Y849993D01*
G01X-235301Y857267D02*
X-234701Y857867D01*
G01X-235301Y865141D02*
X-234701Y865741D01*
G01X-259601Y842119D02*
X-260201Y841519D01*
G01X-258201Y843519D02*
X-258801Y842919D01*
G01X-266675D02*
X-266075Y843519D01*
G01X-267475Y842119D02*
X-268075Y841519D01*
G01X-259601Y849993D02*
X-260201Y849393D01*
G01X-258201Y851393D02*
X-258801Y850793D01*
G01X-266675D02*
X-266075Y851393D01*
G01X-267475Y849993D02*
X-268075Y849393D01*
G01X-258201Y859267D02*
X-258801Y858667D01*
G01X-259601Y857867D02*
X-260201Y857267D01*
G01X-266675Y858667D02*
X-266075Y859267D01*
G01X-267475Y857867D02*
X-268075Y857267D01*
G01X-258201Y867141D02*
X-258801Y866541D01*
G01X-259601Y865741D02*
X-260201Y865141D01*
G01X-266675Y866541D02*
X-266075Y867141D01*
G01X-267475Y865741D02*
X-268075Y865141D01*
G01X-257808Y863740D02*
X-257674Y863937D01*
G01X-257808Y866759D02*
X-257674Y866956D01*
G01X-259885Y867809D02*
X-260019Y867612D01*
G01X-265957Y866444D02*
X-265823Y866641D01*
G01X-268035Y867494D02*
X-268169Y867297D01*
G01X-268303Y867690D02*
X-268504Y867363D01*
G01X-258210Y866168D02*
X-258009Y866234D01*
G01X-266360Y865853D02*
X-266159Y865919D01*
G01X-259483Y868399D02*
X-259684Y868334D01*
G01X-267633Y868084D02*
X-267834Y868019D01*
G01X-234201Y868641D02*
X-240236Y866141D01*
G01X-258009Y866234D02*
X-257741Y866365D01*
G01X-259684Y868334D02*
X-259952Y868202D01*
G01X-266159Y865919D02*
X-265890Y866050D01*
G01X-267834Y868019D02*
X-268102Y867887D01*
G01X-237665Y871269D02*
X-234201Y873269D01*
G01X-258009Y863609D02*
X-257808Y863740D01*
G01X-258210Y866496D02*
X-257808Y866759D01*
G01X-259483Y868071D02*
X-259885Y867809D01*
G01X-266360Y866181D02*
X-265957Y866444D01*
G01X-267633Y867756D02*
X-268035Y867494D01*
G01X-224410Y937008D02*
Y1015079D01*
G01X-236221Y921260D02*
G03X-240158Y925197I-3937J0D01*
G01X-236221Y921260D02*
G03X-240158Y925197I-3937J0D01*
G01X-228110Y1020434D02*
X-227257Y1021201D01*
X-226746Y1022097D01*
X-226575Y1023248D01*
X-226916Y1024400D01*
X-227598Y1025296D01*
X-228793Y1025935D01*
X-230157Y1026063D01*
X-231522Y1025808D01*
X-232375Y1025168D01*
X-233058Y1024272D01*
X-233228Y1023377D01*
X-233058Y1022481D01*
X-232375Y1021329D01*
X-236811Y1021713D01*
Y1025168D01*
G01X-226575Y1033229D02*
X-228793Y1033484D01*
X-230669Y1033868D01*
X-232375Y1034380D01*
X-234252Y1035020D01*
X-236811Y1036044D01*
Y1030925D01*
G01X-226234Y1043720D02*
X-226404Y1043465D01*
X-226746D01*
X-226916Y1043720D01*
X-226746Y1043976D01*
X-226404D01*
X-226234Y1043720D01*
G01X-236811Y1053956D02*
X-236470Y1052933D01*
X-235617Y1052165D01*
X-234593Y1051653D01*
X-233228Y1051270D01*
X-231693Y1051142D01*
X-230157Y1051270D01*
X-228793Y1051653D01*
X-227769Y1052165D01*
X-226916Y1052933D01*
X-226575Y1053956D01*
X-226916Y1054980D01*
X-227769Y1055748D01*
X-228793Y1056260D01*
X-230157Y1056643D01*
X-231693Y1056771D01*
X-233228Y1056643D01*
X-234593Y1056260D01*
X-235617Y1055748D01*
X-236470Y1054980D01*
X-236811Y1053956D01*
G01Y1064192D02*
X-236470Y1063169D01*
X-235617Y1062401D01*
X-234593Y1061889D01*
X-233228Y1061506D01*
X-231693Y1061378D01*
X-230157Y1061506D01*
X-228793Y1061889D01*
X-227769Y1062401D01*
X-226916Y1063169D01*
X-226575Y1064192D01*
X-226916Y1065216D01*
X-227769Y1065984D01*
X-228793Y1066496D01*
X-230157Y1066879D01*
X-231693Y1067007D01*
X-233228Y1066879D01*
X-234593Y1066496D01*
X-235617Y1065984D01*
X-236470Y1065216D01*
X-236811Y1064192D01*
G01X-169295Y-448597D02*
Y-425762D01*
G01Y-428912D02*
Y-448597D01*
G01X-171460Y-388404D02*
X-181696D01*
X-179649Y-389939D01*
G01X-171460D02*
Y-386868D01*
G01X-171119Y-378168D02*
X-171289Y-378423D01*
X-171631D01*
X-171801Y-378168D01*
X-171631Y-377912D01*
X-171289D01*
X-171119Y-378168D01*
G01X-175725Y-370363D02*
X-176919Y-369467D01*
X-177602Y-368699D01*
X-177943Y-367676D01*
X-177602Y-366780D01*
X-176919Y-366140D01*
X-175896Y-365628D01*
X-174701Y-365500D01*
X-173678Y-365628D01*
X-172654Y-366140D01*
X-171801Y-366908D01*
X-171460Y-367803D01*
X-171801Y-368827D01*
X-172825Y-369723D01*
X-174360Y-370235D01*
X-176066Y-370363D01*
X-178284Y-370107D01*
X-179478Y-369723D01*
X-180672Y-369083D01*
X-181525Y-368187D01*
X-181696Y-367292D01*
X-181355Y-366396D01*
X-180502Y-365756D01*
G01X-181696Y-357696D02*
X-181355Y-358719D01*
X-180502Y-359487D01*
X-179478Y-359999D01*
X-178113Y-360382D01*
X-176578Y-360510D01*
X-175042Y-360382D01*
X-173678Y-359999D01*
X-172654Y-359487D01*
X-171801Y-358719D01*
X-171460Y-357696D01*
X-171801Y-356672D01*
X-172654Y-355904D01*
X-173678Y-355392D01*
X-175042Y-355009D01*
X-176578Y-354881D01*
X-178113Y-355009D01*
X-179478Y-355392D01*
X-180502Y-355904D01*
X-181355Y-356672D01*
X-181696Y-357696D01*
G01X-169295Y-361061D02*
Y-425762D01*
G01Y-422612D02*
Y-361061D01*
G01X4759Y-428912D02*
X-173232D01*
G01X4759Y-422612D02*
X-173232D01*
G01X-138982D02*
X2739D01*
G01X-138982D02*
X2739D01*
G01X-138982Y-428912D02*
X794522D01*
G01X-135045Y-422612D02*
Y-428912D01*
G01X-138982Y-422612D02*
Y-428912D01*
G01X-134238Y-266729D02*
Y-256493D01*
X-135773Y-258540D01*
G01Y-266729D02*
X-132702D01*
G01X-124002Y-267070D02*
X-124257Y-266900D01*
Y-266558D01*
X-124002Y-266388D01*
X-123746Y-266558D01*
Y-266900D01*
X-124002Y-267070D01*
G01X-113766Y-256493D02*
X-114789Y-256834D01*
X-115557Y-257687D01*
X-116069Y-258711D01*
X-116452Y-260076D01*
X-116580Y-261611D01*
X-116452Y-263147D01*
X-116069Y-264511D01*
X-115557Y-265535D01*
X-114789Y-266388D01*
X-113766Y-266729D01*
X-112742Y-266388D01*
X-111974Y-265535D01*
X-111462Y-264511D01*
X-111079Y-263147D01*
X-110951Y-261611D01*
X-111079Y-260076D01*
X-111462Y-258711D01*
X-111974Y-257687D01*
X-112742Y-256834D01*
X-113766Y-256493D01*
G01X-103530D02*
X-104553Y-256834D01*
X-105321Y-257687D01*
X-105833Y-258711D01*
X-106216Y-260076D01*
X-106344Y-261611D01*
X-106216Y-263147D01*
X-105833Y-264511D01*
X-105321Y-265535D01*
X-104553Y-266388D01*
X-103530Y-266729D01*
X-102506Y-266388D01*
X-101738Y-265535D01*
X-101226Y-264511D01*
X-100843Y-263147D01*
X-100715Y-261611D01*
X-100843Y-260076D01*
X-101226Y-258711D01*
X-101738Y-257687D01*
X-102506Y-256834D01*
X-103530Y-256493D01*
G01X-93294D02*
X-94317Y-256834D01*
X-95085Y-257687D01*
X-95597Y-258711D01*
X-95980Y-260076D01*
X-96108Y-261611D01*
X-95980Y-263147D01*
X-95597Y-264511D01*
X-95085Y-265535D01*
X-94317Y-266388D01*
X-93294Y-266729D01*
X-92270Y-266388D01*
X-91502Y-265535D01*
X-90990Y-264511D01*
X-90607Y-263147D01*
X-90479Y-261611D01*
X-90607Y-260076D01*
X-90990Y-258711D01*
X-91502Y-257687D01*
X-92270Y-256834D01*
X-93294Y-256493D01*
G01X-175901Y-265364D02*
X-174878Y-266217D01*
X-173726Y-266729D01*
X-172703D01*
X-171679Y-266217D01*
X-170911Y-265364D01*
X-170528Y-264170D01*
X-170783Y-262976D01*
X-171423Y-261952D01*
X-172575Y-261270D01*
X-174110Y-260929D01*
X-175006Y-260246D01*
X-175390Y-259052D01*
X-175134Y-257858D01*
X-174494Y-257005D01*
X-173598Y-256493D01*
X-172703D01*
X-171807Y-256834D01*
X-171039Y-257687D01*
G01X-160164Y-257346D02*
X-160931Y-256834D01*
X-161827Y-256493D01*
X-162850D01*
X-164002Y-257005D01*
X-164898Y-257858D01*
X-165538Y-258882D01*
X-166049Y-260587D01*
X-166177Y-262123D01*
X-165921Y-263658D01*
X-165538Y-264682D01*
X-164770Y-265706D01*
X-163874Y-266388D01*
X-162979Y-266729D01*
X-162083D01*
X-161187Y-266388D01*
X-160419Y-265876D01*
X-159780Y-265194D01*
G01X-155941Y-266729D02*
X-152743Y-256493D01*
X-149544Y-266729D01*
G01X-150695Y-263147D02*
X-154790D01*
G01X-145066Y-256493D02*
Y-266729D01*
X-139947D01*
G01X-129711D02*
X-134830D01*
Y-256493D01*
X-129711D01*
G01X-131759Y-261440D02*
X-134830D01*
G01X-171457Y-200077D02*
X-181693D01*
X-174357Y-204811D01*
Y-198414D01*
G01X-173504Y-194191D02*
X-172310Y-193424D01*
X-171628Y-192400D01*
X-171457Y-191248D01*
X-171628Y-190225D01*
X-172480Y-189201D01*
X-173504Y-188562D01*
X-174528Y-188434D01*
X-175722Y-188690D01*
X-176575Y-189585D01*
X-176916Y-190481D01*
Y-191632D01*
G01Y-190481D02*
X-177428Y-189713D01*
X-178281Y-189073D01*
X-179304Y-188817D01*
X-180328Y-189073D01*
X-181181Y-189713D01*
X-181693Y-190865D01*
X-181522Y-192016D01*
X-180840Y-193168D01*
G01X-171116Y-181141D02*
X-171286Y-181396D01*
X-171628D01*
X-171798Y-181141D01*
X-171628Y-180885D01*
X-171286D01*
X-171116Y-181141D01*
G01X-181693Y-170905D02*
X-181352Y-171928D01*
X-180499Y-172696D01*
X-179475Y-173208D01*
X-178110Y-173591D01*
X-176575Y-173719D01*
X-175039Y-173591D01*
X-173675Y-173208D01*
X-172651Y-172696D01*
X-171798Y-171928D01*
X-171457Y-170905D01*
X-171798Y-169881D01*
X-172651Y-169113D01*
X-173675Y-168601D01*
X-175039Y-168218D01*
X-176575Y-168090D01*
X-178110Y-168218D01*
X-179475Y-168601D01*
X-180499Y-169113D01*
X-181352Y-169881D01*
X-181693Y-170905D01*
G01Y-160669D02*
X-181352Y-161692D01*
X-180499Y-162460D01*
X-179475Y-162972D01*
X-178110Y-163355D01*
X-176575Y-163483D01*
X-175039Y-163355D01*
X-173675Y-162972D01*
X-172651Y-162460D01*
X-171798Y-161692D01*
X-171457Y-160669D01*
X-171798Y-159645D01*
X-172651Y-158877D01*
X-173675Y-158365D01*
X-175039Y-157982D01*
X-176575Y-157854D01*
X-178110Y-157982D01*
X-179475Y-158365D01*
X-180499Y-158877D01*
X-181352Y-159645D01*
X-181693Y-160669D01*
G01X-155827Y-204427D02*
X-154633Y-203660D01*
X-153951Y-202636D01*
X-153780Y-201484D01*
X-153951Y-200461D01*
X-154803Y-199437D01*
X-155827Y-198798D01*
X-156851Y-198670D01*
X-158045Y-198926D01*
X-158898Y-199821D01*
X-159239Y-200717D01*
Y-201868D01*
G01Y-200717D02*
X-159751Y-199949D01*
X-160604Y-199309D01*
X-161627Y-199053D01*
X-162651Y-199309D01*
X-163504Y-199949D01*
X-164016Y-201101D01*
X-163845Y-202252D01*
X-163163Y-203404D01*
G01X-153780Y-191377D02*
X-153951Y-190481D01*
X-154462Y-189457D01*
X-155315Y-188817D01*
X-156510Y-188562D01*
X-157704Y-188817D01*
X-158727Y-189585D01*
X-159239Y-190737D01*
Y-192016D01*
X-159580Y-192784D01*
X-160433Y-193424D01*
X-161627Y-193680D01*
X-162822Y-193296D01*
X-163675Y-192400D01*
X-164016Y-191377D01*
X-163675Y-190353D01*
X-162822Y-189457D01*
X-161627Y-189073D01*
X-160433Y-189329D01*
X-159580Y-189969D01*
X-159239Y-190737D01*
Y-192016D01*
X-158727Y-193168D01*
X-157704Y-193936D01*
X-156510Y-194191D01*
X-155315Y-193936D01*
X-154462Y-193296D01*
X-153951Y-192272D01*
X-153780Y-191377D01*
G01X-153439Y-181141D02*
X-153609Y-181396D01*
X-153951D01*
X-154121Y-181141D01*
X-153951Y-180885D01*
X-153609D01*
X-153439Y-181141D01*
G01X-155315Y-173719D02*
X-154462Y-172952D01*
X-153951Y-172056D01*
X-153780Y-170905D01*
X-154121Y-169753D01*
X-154803Y-168857D01*
X-155998Y-168218D01*
X-157362Y-168090D01*
X-158727Y-168345D01*
X-159580Y-168985D01*
X-160263Y-169881D01*
X-160433Y-170776D01*
X-160263Y-171672D01*
X-159580Y-172824D01*
X-164016Y-172440D01*
Y-168985D01*
G01X-153780Y-160669D02*
X-164016D01*
X-161969Y-162204D01*
G01X-153780D02*
Y-159133D01*
G01X-169292Y417323D02*
Y-152499D01*
G01X-151614Y212599D02*
Y-152499D01*
G01X-143740Y216536D02*
G03X-139803Y212599I3937J0D01*
G01X-143740Y262205D02*
G03X-151614I-3937J0D01*
G01X-143740Y216536D02*
G03X-139803Y212599I3937J0D01*
G01X-151614Y216536D02*
G03X-139803Y204725I11811J0D01*
G01X-143740Y262205D02*
Y292914D01*
G01Y338583D02*
Y216536D01*
G01Y338583D02*
Y216536D01*
G01X-151614D02*
Y262205D01*
G01X-139803Y212599D02*
X-3937D01*
G01X-139803D02*
X-3937D01*
G01X-15748Y204725D02*
X-139803D01*
G01Y342520D02*
G03X-143740Y338583I0J-3937D01*
G01X-139803Y342520D02*
G03X-143740Y338583I0J-3937D01*
G01X-139803Y350394D02*
G03X-151614Y338583I0J-11811D01*
G01Y292914D02*
G03X-143740I3937J0D01*
G01X-151614D02*
Y338583D01*
G01X-62992Y342520D02*
X-139803D01*
G01X-62992D02*
X-139803D01*
G01X-181103Y409449D02*
G03X-169292Y421260I0J11811D01*
G01X-139803Y350394D02*
X-70866D01*
G01X-177166Y467717D02*
G03X-169292I3937J0D01*
G01X-181103Y417323D02*
G03X-177166Y421260I0J3937D01*
G01X-169292Y437008D02*
G03X-177166I-3937J0D01*
G01X-181103Y417323D02*
G03X-177166Y421260I0J3937D01*
G01X-169292Y437008D02*
Y421260D01*
G01Y570866D02*
Y467717D01*
G01X-177166Y421260D02*
Y578740D01*
G01Y421260D02*
Y578740D01*
G01Y467717D02*
Y437008D01*
G01X-173229Y582677D02*
G03X-177166Y578740I0J-3937D01*
G01X-165355Y574803D02*
G03X-169292Y570866I0J-3937D01*
G01X-173229Y582677D02*
G03X-177166Y578740I0J-3937D01*
G01X-153294Y624126D02*
X-146733D01*
G01Y622450D02*
X-153294D01*
G01X-140991Y621613D02*
X-129508D01*
G01X-153294Y619100D02*
X-146733D01*
G01X-179541D02*
X-178721D01*
G01X-186103D02*
X-184872D01*
G01X-197996D02*
X-197175D01*
G01X-129508D02*
X-140991D01*
G01X-197175Y617424D02*
X-198816D01*
G01X-193074D02*
X-195125D01*
G01X-185282D02*
X-186923D01*
G01X-174620D02*
X-176670D01*
G01X-178721D02*
X-180361D01*
G01X-146733D02*
X-153294D01*
G01X-140991Y611142D02*
X-143451D01*
G01X-163957D02*
X-161496Y611561D01*
G01X-163957Y613236D02*
X-161906Y613655D01*
G01X-167238Y614493D02*
X-166007Y613655D01*
G01X-168468Y612817D02*
X-166418Y611561D01*
G01X-180361Y619519D02*
X-179541Y619100D01*
G01X-186923Y619519D02*
X-186103Y619100D01*
G01X-198816Y619519D02*
X-197996Y619100D01*
G01X-180361Y617424D02*
X-181591Y617843D01*
G01X-186923Y617424D02*
X-188153Y617843D01*
G01X-198816Y617424D02*
X-200046Y617843D01*
G01X-166007Y613655D02*
X-163957Y613236D01*
G01X-166418Y611561D02*
X-163957Y611142D01*
G01X-173229Y582677D02*
X-96418D01*
G01X-173229D02*
X-96418D01*
G01Y574803D02*
X-165355D01*
G01X-156985Y624963D02*
X-157395Y626220D01*
G01D02*
X-158215Y627895D01*
G01X-170518Y615749D02*
X-169698Y614074D01*
G01X-181181Y620775D02*
X-180771Y619937D01*
G01X-159036Y624963D02*
X-160676Y627476D01*
G01X-168878Y617006D02*
X-167238Y614493D01*
G01X-169698Y614074D02*
X-168468Y612817D01*
G01X-180771Y619937D02*
X-180361Y619519D01*
G01X-181591Y617843D02*
X-182822Y619100D01*
G01X-187333Y619937D02*
X-186923Y619519D01*
G01X-188153Y617843D02*
X-188973Y618681D01*
G01X-199226Y619937D02*
X-198816Y619519D01*
G01X-200046Y617843D02*
X-201276Y619100D01*
G01X-158625Y622450D02*
X-159036Y624963D01*
G01X-169288Y619519D02*
X-168878Y617006D01*
G01X-156575Y622869D02*
X-156985Y624963D01*
G01X-171339Y619100D02*
X-170929Y617006D01*
G01D02*
X-170518Y615749D01*
G01X-188973Y618681D02*
X-189794Y620775D01*
G01X-187743D02*
X-187333Y619937D01*
G01X-199636Y620775D02*
X-199226Y619937D01*
G01X-140991Y619100D02*
Y611142D01*
G01Y630827D02*
Y621613D01*
G01X-143451Y611142D02*
Y630827D01*
G01X-146733Y619100D02*
Y617424D01*
G01Y624126D02*
Y622450D01*
G01X-153294D02*
Y624126D01*
G01Y617424D02*
Y619100D01*
G01X-156575D02*
Y622869D01*
G01X-158625Y619519D02*
Y622450D01*
G01X-169288D02*
Y619519D01*
G01X-171339Y622869D02*
Y619100D01*
G01X-174620Y630827D02*
Y617424D01*
G01X-176670Y620356D02*
Y630827D01*
G01Y617424D02*
Y618681D01*
G01X-160676Y614493D02*
X-159036Y617006D01*
G01X-158215Y614074D02*
X-157395Y615749D01*
G01X-169698Y627895D02*
X-170518Y626220D01*
G01X-183642Y619937D02*
X-183232Y620775D01*
G01X-157395Y615749D02*
X-156985Y617006D01*
G01X-170518Y626220D02*
X-170929Y624963D01*
G01X-156985Y617006D02*
X-156575Y619100D01*
G01X-170929Y624963D02*
X-171339Y622869D01*
G01X-159036Y617006D02*
X-158625Y619519D01*
G01X-168878Y624963D02*
X-169288Y622450D01*
G01X-181181Y630827D02*
Y620775D01*
G01X-183232D02*
Y630827D01*
G01X-187743D02*
Y620775D01*
G01X-189794D02*
Y630827D01*
G01X-193074D02*
Y617424D01*
G01X-195125Y620356D02*
Y630827D01*
G01Y617424D02*
Y618681D01*
G01X-199636Y630827D02*
Y620775D01*
G01X-201686D02*
Y630827D01*
G01X-177490Y617843D02*
X-178721Y617424D01*
G01Y619100D02*
X-177490Y619519D01*
G01X-184052Y617843D02*
X-185282Y617424D01*
G01X-195945Y617843D02*
X-197175Y617424D01*
G01Y619100D02*
X-195945Y619519D01*
G01X-184872Y619100D02*
X-184052Y619519D01*
G01X-203327Y619100D02*
X-202507Y619519D01*
G01X-161496Y611561D02*
X-159446Y612817D01*
G01X-161906Y613655D02*
X-160676Y614493D01*
G01X-159446Y612817D02*
X-158215Y614074D01*
G01X-176670Y618681D02*
X-177490Y617843D01*
G01Y619519D02*
X-176670Y620356D01*
G01X-182822Y619100D02*
X-184052Y617843D01*
G01Y619519D02*
X-183642Y619937D01*
G01X-195125Y618681D02*
X-195945Y617843D01*
G01Y619519D02*
X-195125Y620356D01*
G01X-201276Y619100D02*
X-202507Y617843D01*
G01Y619519D02*
X-202097Y619937D01*
G01X-167238Y627476D02*
X-168878Y624963D01*
G01X-202097Y619937D02*
X-201686Y620775D01*
G01X-169252Y647638D02*
G03I-7874J0D01*
G01X-161906Y628314D02*
X-163957Y628733D01*
G01X-161496Y630408D02*
X-163957Y630827D01*
G01X-143451D02*
X-140991D01*
G01X-176670D02*
X-174620D01*
G01X-183232D02*
X-181181D01*
G01X-189794D02*
X-187743D01*
G01X-195125D02*
X-193074D01*
G01X-201686D02*
X-199636D01*
G01X-163957D02*
X-166418Y630408D01*
G01X-163957Y628733D02*
X-166007Y628314D01*
G01X-158215Y627895D02*
X-159446Y629152D01*
G01X-160676Y627476D02*
X-161906Y628314D01*
G01X-159446Y629152D02*
X-161496Y630408D01*
G01X-166418D02*
X-168468Y629152D01*
G01X-166007Y628314D02*
X-167238Y627476D01*
G01X-168468Y629152D02*
X-169698Y627895D01*
G01X-51221Y277559D02*
G03I-7874J0D01*
G01X-62992Y342520D02*
G03X-59055Y346457I0J3937D01*
G01X-62992Y342520D02*
G03X-59055Y346457I0J3937D01*
G01X-69803Y294789D02*
X-67753Y296046D01*
G01X-74725Y313637D02*
X-76775Y312380D01*
G01X-70213Y296883D02*
X-68983Y297721D01*
G01X-74314Y311542D02*
X-75545Y310705D01*
G01X-67753Y296046D02*
X-66522Y297302D01*
G01X-76775Y312380D02*
X-78005Y311124D01*
G01X-68983Y297721D02*
X-67343Y300234D01*
G01X-75545Y310705D02*
X-77185Y308192D01*
G01X-66522Y297302D02*
X-65702Y298977D01*
G01X-78005Y311124D02*
X-78825Y309448D01*
G01X-65702Y298977D02*
X-65292Y300234D01*
G01X-78825Y309448D02*
X-79236Y308192D01*
G01X-65292Y300234D02*
X-64882Y302328D01*
G01X-66933Y305679D02*
X-67343Y308192D01*
G01X-77595Y302747D02*
X-77185Y300234D01*
G01X-64882Y306098D02*
X-65292Y308192D01*
G01X-79236D02*
X-79646Y306098D01*
G01X-67343Y300234D02*
X-66933Y302747D01*
G01X-77185Y308192D02*
X-77595Y305679D01*
G01X-64882Y302328D02*
Y306098D01*
G01X-66933Y302747D02*
Y305679D01*
G01X-77595D02*
Y302747D01*
G01X-79646Y306098D02*
Y302328D01*
G01X-82927Y302747D02*
Y301072D01*
G01Y307773D02*
Y306098D01*
G01X-89488D02*
Y307773D01*
G01Y301072D02*
Y302747D01*
G01X-92769Y314055D02*
Y294370D01*
G01X-95230Y306098D02*
Y314055D01*
G01Y294370D02*
Y303585D01*
G01X-106713D02*
Y294370D01*
G01Y314055D02*
Y306098D01*
G01X-79646Y302328D02*
X-79236Y300234D01*
G01X-65292Y308192D02*
X-65702Y309448D01*
G01X-79236Y300234D02*
X-78825Y298977D01*
G01X-65702Y309448D02*
X-66522Y311124D01*
G01X-78825Y298977D02*
X-78005Y297302D01*
G01X-67343Y308192D02*
X-68983Y310705D01*
G01X-77185Y300234D02*
X-75545Y297721D01*
G01X-109173Y294370D02*
Y314055D01*
G01X-66522Y311124D02*
X-67753Y312380D01*
G01X-78005Y297302D02*
X-76775Y296046D01*
G01X-68983Y310705D02*
X-70213Y311542D01*
G01X-75545Y297721D02*
X-74314Y296883D01*
G01X-67753Y312380D02*
X-69803Y313637D01*
G01X-76775Y296046D02*
X-74725Y294789D01*
G01X-70213Y311542D02*
X-72264Y311961D01*
G01X-74314Y296883D02*
X-72264Y296465D01*
G01X-69803Y313637D02*
X-72264Y314055D01*
G01X-74725Y294789D02*
X-72264Y294370D01*
G01X-95230Y314055D02*
X-92769D01*
G01X-109173D02*
X-106713D01*
G01X-89488Y307773D02*
X-82927D01*
G01X-106713Y306098D02*
X-95230D01*
G01X-82927D02*
X-89488D01*
G01X-95230Y303585D02*
X-106713D01*
G01X-89488Y302747D02*
X-82927D01*
G01Y301072D02*
X-89488D01*
G01X-106713Y294370D02*
X-109173D01*
G01X-92769D02*
X-95230D01*
G01X-72264Y314055D02*
X-74725Y313637D01*
G01X-72264Y294370D02*
X-69803Y294789D01*
G01X-72264Y311961D02*
X-74314Y311542D01*
G01X-72264Y296465D02*
X-70213Y296883D01*
G01X-70866Y350394D02*
G03X-66929Y354331I0J3937D01*
G01D02*
Y457481D01*
G01Y461418D02*
Y1015079D01*
G01Y488189D02*
G03X-59055I3937J0D01*
G01Y457481D02*
G03X-66929I-3937J0D01*
G01X-55118Y515748D02*
G03X-66929Y503937I0J-11811D01*
G01Y488189D02*
Y503937D01*
G01X-96418Y582677D02*
G03X-92481Y586615I0J3937D01*
G01X-96418Y582677D02*
G03X-92481Y586615I0J3937D01*
G01X-96418Y574803D02*
G03X-84607Y586615I0J11811D01*
G01X-127047Y611142D02*
X-129508D01*
G01X-84607Y632284D02*
Y586615D01*
G01X-92481D02*
Y708662D01*
G01Y586615D02*
Y708662D01*
G01X-127047Y630827D02*
Y611142D01*
G01X-129508Y621613D02*
Y630827D01*
G01Y611142D02*
Y619100D01*
G01X-84607Y636221D02*
Y1015079D01*
G01X-92481Y662992D02*
G03X-84607I3937J0D01*
G01Y632284D02*
G03X-92481I-3937J0D01*
G01X-129508Y630827D02*
X-127047D01*
G01X-84607Y708662D02*
Y662992D01*
G01X-92481D02*
Y632284D01*
G01Y708662D02*
G03X-96418Y712599I-3937J0D01*
G01X-92481Y708662D02*
G03X-96418Y712599I-3937J0D01*
G01X-84607Y708662D02*
G03X-96418Y720473I-11811J0D01*
G01X-69095Y1023248D02*
X-79331D01*
X-77284Y1021713D01*
G01X-69095D02*
Y1024784D01*
G01Y1033229D02*
X-71313Y1033484D01*
X-73189Y1033868D01*
X-74895Y1034380D01*
X-76772Y1035020D01*
X-79331Y1036044D01*
Y1030925D01*
G01X-68754Y1043720D02*
X-68924Y1043465D01*
X-69266D01*
X-69436Y1043720D01*
X-69266Y1043976D01*
X-68924D01*
X-68754Y1043720D01*
G01X-79331Y1053956D02*
X-78990Y1052933D01*
X-78137Y1052165D01*
X-77113Y1051653D01*
X-75748Y1051270D01*
X-74213Y1051142D01*
X-72677Y1051270D01*
X-71313Y1051653D01*
X-70289Y1052165D01*
X-69436Y1052933D01*
X-69095Y1053956D01*
X-69436Y1054980D01*
X-70289Y1055748D01*
X-71313Y1056260D01*
X-72677Y1056643D01*
X-74213Y1056771D01*
X-75748Y1056643D01*
X-77113Y1056260D01*
X-78137Y1055748D01*
X-78990Y1054980D01*
X-79331Y1053956D01*
G01Y1064192D02*
X-78990Y1063169D01*
X-78137Y1062401D01*
X-77113Y1061889D01*
X-75748Y1061506D01*
X-74213Y1061378D01*
X-72677Y1061506D01*
X-71313Y1061889D01*
X-70289Y1062401D01*
X-69436Y1063169D01*
X-69095Y1064192D01*
X-69436Y1065216D01*
X-70289Y1065984D01*
X-71313Y1066496D01*
X-72677Y1066879D01*
X-74213Y1067007D01*
X-75748Y1066879D01*
X-77113Y1066496D01*
X-78137Y1065984D01*
X-78990Y1065216D01*
X-79331Y1064192D01*
G01X-95302Y1020817D02*
X-96325Y1021585D01*
X-96837Y1022481D01*
X-97008Y1023504D01*
X-96667Y1024784D01*
X-95814Y1025680D01*
X-94790Y1025935D01*
X-93766Y1025808D01*
X-92914Y1025296D01*
X-91208Y1022737D01*
X-90013Y1021585D01*
X-88307Y1020817D01*
X-86772Y1020562D01*
Y1025935D01*
G01Y1033484D02*
X-97008D01*
X-94961Y1031949D01*
G01X-86772D02*
Y1035020D01*
G01X-86431Y1043720D02*
X-86601Y1043465D01*
X-86943D01*
X-87113Y1043720D01*
X-86943Y1043976D01*
X-86601D01*
X-86431Y1043720D01*
G01X-86772Y1055492D02*
X-97008D01*
X-89672Y1050758D01*
Y1057155D01*
G01X-87966Y1062017D02*
X-87113Y1062913D01*
X-86772Y1063937D01*
X-87113Y1064960D01*
X-88137Y1065856D01*
X-89672Y1066496D01*
X-91208Y1066752D01*
X-93084D01*
X-94619Y1066496D01*
X-95984Y1065856D01*
X-96667Y1065088D01*
X-97008Y1064192D01*
X-96667Y1063169D01*
X-95984Y1062401D01*
X-94961Y1061889D01*
X-93596Y1061633D01*
X-92402Y1061889D01*
X-91208Y1062529D01*
X-90525Y1063297D01*
X-90354Y1064192D01*
X-90696Y1065216D01*
X-91549Y1065984D01*
X-93084Y1066752D01*
G01X-3312Y-396825D02*
G03Y-409030I0J-6102D01*
G01X7534Y-389069D02*
X44148D01*
G01X20507Y-391116D02*
X5546D01*
G01Y-392219D02*
X4778D01*
G01X5546Y-396825D02*
X-3312D01*
G01X2739Y-396873D02*
X21739D01*
G01X2739Y-409030D02*
X-3312D01*
G01X4759Y-422612D02*
X794522D01*
G01X4759D02*
X764601D01*
G01X2739D02*
X4759D01*
G01X7534Y-389069D02*
Y-391116D01*
G01X5546Y-396873D02*
Y-391117D01*
G01X4778Y-392219D02*
Y-396825D01*
G01X4759Y-428912D02*
Y-422612D01*
G01X2739Y-396873D02*
Y-422612D01*
G01X822Y-428912D02*
Y-422612D01*
G01X-3312Y-409030D02*
Y-396825D01*
G01X-12402Y-191377D02*
X-12061Y-192400D01*
X-11208Y-193168D01*
X-10184Y-193680D01*
X-8819Y-194063D01*
X-7284Y-194191D01*
X-5748Y-194063D01*
X-4384Y-193680D01*
X-3360Y-193168D01*
X-2507Y-192400D01*
X-2166Y-191377D01*
X-2507Y-190353D01*
X-3360Y-189585D01*
X-4384Y-189073D01*
X-5748Y-188690D01*
X-7284Y-188562D01*
X-8819Y-188690D01*
X-10184Y-189073D01*
X-11208Y-189585D01*
X-12061Y-190353D01*
X-12402Y-191377D01*
G01X-1825Y-181141D02*
X-1995Y-181396D01*
X-2337D01*
X-2507Y-181141D01*
X-2337Y-180885D01*
X-1995D01*
X-1825Y-181141D01*
G01X-12402Y-170905D02*
X-12061Y-171928D01*
X-11208Y-172696D01*
X-10184Y-173208D01*
X-8819Y-173591D01*
X-7284Y-173719D01*
X-5748Y-173591D01*
X-4384Y-173208D01*
X-3360Y-172696D01*
X-2507Y-171928D01*
X-2166Y-170905D01*
X-2507Y-169881D01*
X-3360Y-169113D01*
X-4384Y-168601D01*
X-5748Y-168218D01*
X-7284Y-168090D01*
X-8819Y-168218D01*
X-10184Y-168601D01*
X-11208Y-169113D01*
X-12061Y-169881D01*
X-12402Y-170905D01*
G01Y-160669D02*
X-12061Y-161692D01*
X-11208Y-162460D01*
X-10184Y-162972D01*
X-8819Y-163355D01*
X-7284Y-163483D01*
X-5748Y-163355D01*
X-4384Y-162972D01*
X-3360Y-162460D01*
X-2507Y-161692D01*
X-2166Y-160669D01*
X-2507Y-159645D01*
X-3360Y-158877D01*
X-4384Y-158365D01*
X-5748Y-157982D01*
X-7284Y-157854D01*
X-8819Y-157982D01*
X-10184Y-158365D01*
X-11208Y-158877D01*
X-12061Y-159645D01*
X-12402Y-160669D01*
G01X-34682Y-194191D02*
X-33488Y-193424D01*
X-32806Y-192400D01*
X-32635Y-191248D01*
X-32806Y-190225D01*
X-33658Y-189201D01*
X-34682Y-188562D01*
X-35706Y-188434D01*
X-36900Y-188690D01*
X-37753Y-189585D01*
X-38094Y-190481D01*
Y-191632D01*
G01Y-190481D02*
X-38606Y-189713D01*
X-39459Y-189073D01*
X-40482Y-188817D01*
X-41506Y-189073D01*
X-42359Y-189713D01*
X-42871Y-190865D01*
X-42700Y-192016D01*
X-42018Y-193168D01*
G01X-32294Y-181141D02*
X-32464Y-181396D01*
X-32806D01*
X-32976Y-181141D01*
X-32806Y-180885D01*
X-32464D01*
X-32294Y-181141D01*
G01X-42871Y-170905D02*
X-42530Y-171928D01*
X-41677Y-172696D01*
X-40653Y-173208D01*
X-39288Y-173591D01*
X-37753Y-173719D01*
X-36217Y-173591D01*
X-34853Y-173208D01*
X-33829Y-172696D01*
X-32976Y-171928D01*
X-32635Y-170905D01*
X-32976Y-169881D01*
X-33829Y-169113D01*
X-34853Y-168601D01*
X-36217Y-168218D01*
X-37753Y-168090D01*
X-39288Y-168218D01*
X-40653Y-168601D01*
X-41677Y-169113D01*
X-42530Y-169881D01*
X-42871Y-170905D01*
G01Y-160669D02*
X-42530Y-161692D01*
X-41677Y-162460D01*
X-40653Y-162972D01*
X-39288Y-163355D01*
X-37753Y-163483D01*
X-36217Y-163355D01*
X-34853Y-162972D01*
X-33829Y-162460D01*
X-32976Y-161692D01*
X-32635Y-160669D01*
X-32976Y-159645D01*
X-33829Y-158877D01*
X-34853Y-158365D01*
X-36217Y-157982D01*
X-37753Y-157854D01*
X-39288Y-157982D01*
X-40653Y-158365D01*
X-41677Y-158877D01*
X-42530Y-159645D01*
X-42871Y-160669D01*
G01X0Y0D02*
Y-152499D01*
G01X-30470Y-138501D02*
Y-152499D01*
G01X-11811Y-115743D02*
X-30470Y-138501D01*
G01X-11811Y-7874D02*
Y-115743D01*
G01Y-3937D02*
G03X-7874Y-7874I3937J0D01*
G01X31496D02*
X-7874D01*
G01X0Y3937D02*
G03X3937Y0I3937J0D01*
G01X0Y3937D02*
G03X3937Y0I3937J0D01*
G01X4016Y59057D02*
X-2020Y56557D01*
G01X1444Y53928D02*
X-2020Y51928D01*
G01X-920Y60057D02*
X-1520Y59457D01*
G01X1444Y111426D02*
Y53928D01*
G01X0Y3937D02*
Y783465D01*
G01Y3937D02*
Y208662D01*
G01X-920Y60057D02*
Y58057D01*
G01X-1520Y59457D02*
Y58657D01*
G01X-2020Y114926D02*
Y50428D01*
G01Y116895D02*
Y48460D01*
G01X-11811Y-3937D02*
Y200788D01*
G01X-1520Y58657D02*
X-920Y58057D01*
G01X4016Y59057D02*
X-2020Y61557D01*
G01X10480Y60057D02*
X-920D01*
G01Y58057D02*
X10480D01*
G01X-2020Y53928D02*
X16980D01*
G01X-2020Y50428D02*
X16980D01*
G01X-2020Y48460D02*
X33823D01*
G01X0Y45276D02*
X200787D01*
G01X755905Y0D02*
X3937D01*
G01X755905D02*
X3937D01*
G01X-920Y67931D02*
X-1520Y67331D01*
G01X-920Y75805D02*
X-1520Y75205D01*
G01X-920Y83678D02*
X-1520Y83078D01*
G01X-920Y91552D02*
X-1520Y90952D01*
G01X-920Y99426D02*
X-1520Y98826D01*
G01X-920Y107300D02*
X-1520Y106700D01*
G01X3937Y162796D02*
Y128544D01*
G01X-920Y67931D02*
Y65931D01*
G01Y75805D02*
Y73805D01*
G01Y83678D02*
Y81678D01*
G01Y91552D02*
Y89552D01*
G01Y99426D02*
Y97426D01*
G01Y107300D02*
Y105300D01*
G01X-1520Y67331D02*
Y66531D01*
G01Y75205D02*
Y74405D01*
G01Y83078D02*
Y82278D01*
G01Y90952D02*
Y90152D01*
G01Y98826D02*
Y98026D01*
G01Y106700D02*
Y105900D01*
G01D02*
X-920Y105300D01*
G01X-1520Y98026D02*
X-920Y97426D01*
G01X-1520Y90152D02*
X-920Y89552D01*
G01X-1520Y82278D02*
X-920Y81678D01*
G01X-1520Y74405D02*
X-920Y73805D01*
G01X-1520Y66531D02*
X-920Y65931D01*
G01X1444Y111426D02*
X-2020Y113426D01*
G01X3937Y128544D02*
X46456D01*
G01X-2020Y116895D02*
X33823D01*
G01X16980Y114926D02*
X-2020D01*
G01X16980Y111426D02*
X-2020D01*
G01X10480Y107300D02*
X-920D01*
G01Y105300D02*
X10480D01*
G01Y99426D02*
X-920D01*
G01Y97426D02*
X10480D01*
G01Y91552D02*
X-920D01*
G01X10480Y89677D02*
X-2020D01*
G01X-920Y89552D02*
X10480D01*
G01X11480Y87677D02*
X-2020D01*
G01X10480Y83678D02*
X-920D01*
G01Y81678D02*
X10480D01*
G01X11480Y77677D02*
X-2020D01*
G01X10480Y75805D02*
X-920D01*
G01X-2020Y75677D02*
X10480D01*
G01X-920Y73805D02*
X10480D01*
G01Y67931D02*
X-920D01*
G01Y65931D02*
X10480D01*
G01X-11811Y200788D02*
G03X-15748Y204725I-3937J0D01*
G01X6890Y151772D02*
G03Y139567I0J-6102D01*
G01D02*
Y151772D01*
G01X3937Y162796D02*
X46456D01*
G01X16338Y151772D02*
X6890D01*
G01Y139567D02*
X21063D01*
G01X0Y212599D02*
Y1015079D01*
G01X-29567Y269685D02*
G03I-3937J0D01*
G01X-40Y277559D02*
G03I-7874J0D01*
G01X0Y208662D02*
G03X-3937Y212599I-3937J0D01*
G01X0Y208662D02*
G03X-3937Y212599I-3937J0D01*
G01X-33714Y307354D02*
X-32484Y307773D01*
G01X-39046Y306098D02*
X-40276Y305679D01*
G01Y307354D02*
X-39046Y307773D01*
G01X-52169Y307354D02*
X-50938Y307773D01*
G01X-57500Y306098D02*
X-58731Y305679D01*
G01Y307354D02*
X-57500Y307773D01*
G01X-32894Y306098D02*
X-33714Y305679D01*
G01X-51349Y306098D02*
X-52169Y305679D01*
G01X-33714D02*
X-34124Y305260D01*
G01X-34944Y306098D02*
X-33714Y307354D01*
G01X-40276Y305679D02*
X-41096Y304841D01*
G01Y306516D02*
X-40276Y307354D01*
G01X-52169Y305679D02*
X-52579Y305260D01*
G01X-53399Y306098D02*
X-52169Y307354D01*
G01X-58731Y305679D02*
X-59551Y304841D01*
G01Y306516D02*
X-58731Y307354D01*
G01X-34124Y305260D02*
X-34534Y304422D01*
G01X-52579Y305260D02*
X-52989Y304422D01*
G01X-27973D02*
Y294370D01*
G01X-30023D02*
Y304422D01*
G01X-34534D02*
Y294370D01*
G01X-36585D02*
Y304422D01*
G01X-28793Y306516D02*
X-27973Y304422D01*
G01X-30023D02*
X-30433Y305260D01*
G01X-41096Y304841D02*
Y294370D01*
G01Y307773D02*
Y306516D01*
G01X-43146Y294370D02*
Y307773D01*
G01X-46427Y304422D02*
Y294370D01*
G01X-48478D02*
Y304422D01*
G01X-52989D02*
Y294370D01*
G01X-55040D02*
Y304422D01*
G01X-59551Y304841D02*
Y294370D01*
G01Y307773D02*
Y306516D01*
G01X-61601Y294370D02*
Y307773D01*
G01X-47247Y306516D02*
X-46427Y304422D01*
G01X-36585D02*
X-36995Y305260D01*
G01X-48478Y304422D02*
X-48888Y305260D01*
G01X-55040Y304422D02*
X-55449Y305260D01*
G01X-29613Y307354D02*
X-28793Y306516D01*
G01X-30433Y305260D02*
X-30843Y305679D01*
G01X-36175Y307354D02*
X-34944Y306098D01*
G01X-36995Y305260D02*
X-37405Y305679D01*
G01X-48068Y307354D02*
X-47247Y306516D01*
G01X-48888Y305260D02*
X-49298Y305679D01*
G01X-54629Y307354D02*
X-53399Y306098D01*
G01X-55449Y305260D02*
X-55860Y305679D01*
G01X-30843D02*
X-31664Y306098D01*
G01X-37405Y305679D02*
X-38225Y306098D01*
G01X-49298Y305679D02*
X-50118Y306098D01*
G01X-55860Y305679D02*
X-56680Y306098D01*
G01X-30843Y307773D02*
X-29613Y307354D01*
G01X-37405Y307773D02*
X-36175Y307354D01*
G01X-49298Y307773D02*
X-48068Y307354D01*
G01X-55860Y307773D02*
X-54629Y307354D01*
G01X-32484Y307773D02*
X-30843D01*
G01X-39046D02*
X-37405D01*
G01X-43146D02*
X-41096D01*
G01X-50938D02*
X-49298D01*
G01X-57500D02*
X-55860D01*
G01X-61601D02*
X-59551D01*
G01X-56680Y306098D02*
X-57500D01*
G01X-50118D02*
X-51349D01*
G01X-38225D02*
X-39046D01*
G01X-31664D02*
X-32894D01*
G01X-59551Y294370D02*
X-61601D01*
G01X-52989D02*
X-55040D01*
G01X-46427D02*
X-48478D01*
G01X-41096D02*
X-43146D01*
G01X-34534D02*
X-36585D01*
G01X-27973D02*
X-30023D01*
G01X-59055Y503937D02*
Y346457D01*
G01Y503937D02*
Y346457D01*
G01Y488189D02*
Y457481D01*
G01X8189Y553544D02*
G03I-1575J0D01*
G01X-23622Y552559D02*
G03X-27559Y548622I0J-3937D01*
G01X-11811Y552559D02*
G03X-7874Y556496I0J3937D01*
G01X6299Y530276D02*
G03X6102Y530079I0J-197D01*
G01Y528740D02*
G03X6299Y528544I197J1D01*
G01Y526575D02*
G03X6102Y526378I0J-197D01*
G01Y525040D02*
G03X6299Y524843I197J0D01*
G01X-3937Y507874D02*
G03X0Y511811I0J3937D01*
G01X-3937Y507874D02*
G03X0Y511811I0J3937D01*
G01X-8071Y533662D02*
G03Y521457I0J-6102D01*
G01X-55118Y507874D02*
G03X-59055Y503937I0J-3937D01*
G01X-31496Y515748D02*
G03X-27559Y519685I0J3937D01*
G01X-55118Y507874D02*
G03X-59055Y503937I0J-3937D01*
G01X8937Y516575D02*
X6102Y523089D01*
G01X39390Y555512D02*
X2775D01*
G01X19Y554036D02*
X2775D01*
G01D02*
X39390D01*
G01X2775Y553052D02*
X19D01*
G01X39390D02*
X2775D01*
G01X-23622Y552559D02*
X-11811D01*
G01X39Y551181D02*
X90590D01*
G01X-11024Y544685D02*
X31496D01*
G01X6102Y531851D02*
X9015Y538544D01*
G01X7591Y553052D02*
Y554036D01*
G01X6299Y524843D02*
Y522637D01*
G01Y528544D02*
Y526575D01*
G01X6240Y554036D02*
Y553052D01*
G01X6227Y554036D02*
Y553052D01*
G01X6102Y521457D02*
Y535002D01*
G01Y535589D02*
Y521391D01*
G01X5932Y553052D02*
Y554036D01*
G01X5827D02*
Y553052D01*
G01X5649Y554036D02*
Y553052D01*
G01X4724Y537992D02*
Y517126D01*
G01X4645Y554036D02*
Y553052D01*
G01X2775Y624115D02*
Y553052D01*
G01X2165Y521457D02*
Y535002D01*
G01X1378Y521457D02*
Y534418D01*
G01X807Y553052D02*
Y554036D01*
G01X787Y540748D02*
Y514370D01*
G01X39Y625985D02*
Y551181D01*
G01X19Y554036D02*
Y553052D01*
G01X0Y511811D02*
Y783465D01*
G01X-8071Y521457D02*
Y533662D01*
G01X-11024Y544685D02*
Y510433D01*
G01X-27559Y519685D02*
Y548622D01*
G01X787Y540748D02*
X27559D01*
G01X787Y538740D02*
X25197D01*
G01Y537992D02*
X4724D01*
G01X6102Y535589D02*
X787D01*
G01X2165Y535040D02*
X6102D01*
G01X22441Y534572D02*
X6102D01*
G01X1378Y534449D02*
X2165D01*
G01X1378Y533662D02*
X-8071D01*
G01X8071Y530276D02*
X6299D01*
G01Y528544D02*
X27165D01*
G01Y526575D02*
X6299D01*
G01Y524843D02*
X11811D01*
G01X-8071Y521457D02*
X6102D01*
G01Y521418D02*
X787D01*
G01X22441Y521391D02*
X6102D01*
G01X25197Y517126D02*
X4724D01*
G01X787Y516378D02*
X25197D01*
G01X-55118Y515748D02*
X-31496D01*
G01X787Y514370D02*
X27559D01*
G01X-11024Y510433D02*
X31496D01*
G01X-3937Y507874D02*
X-55118D01*
G01X-3937D02*
X-55118D01*
G01X6712Y603563D02*
G03X5925Y602776I0J-787D01*
G01Y595965D02*
G03X6712Y595177I788J0D01*
G01X5925Y574390D02*
G03X6712Y573603I787J0D01*
G01Y581989D02*
G03X5925Y581201I1J-788D01*
G01X7287Y562593D02*
X8254Y559630D01*
G01X90590Y625985D02*
X39D01*
G01X19Y624115D02*
X2775D01*
G01D02*
X39390D01*
G01X2775Y623130D02*
X19D01*
G01X39390D02*
X2775D01*
G01X39390Y621654D02*
X2775D01*
G01X8090Y603563D02*
X6712D01*
G01X8090Y595177D02*
X6712D01*
G01X8090Y581989D02*
X6712D01*
G01X8090Y573603D02*
X6712D01*
G01X6857Y563032D02*
X7716D01*
G01X8254Y559630D02*
X6319D01*
G01X8361Y559191D02*
X6212D01*
G01X5782Y557874D02*
X5138D01*
G01X6857Y563032D02*
X5138Y557874D01*
G01X6212Y559191D02*
X5782Y557874D01*
G01X7287Y562593D02*
X6319Y559630D01*
G01X6240Y624115D02*
Y623130D01*
G01X5925Y581201D02*
Y574390D01*
G01Y602776D02*
Y595965D01*
G01X5649Y624115D02*
Y623130D01*
G01X807Y624115D02*
Y623130D01*
G01X19Y624115D02*
Y623130D01*
G01X-7874Y556496D02*
Y783465D01*
G01X5925Y692500D02*
G03X6712Y691713I787J0D01*
G01X8189Y671654D02*
G03I-1575J0D01*
G01X6890Y651772D02*
G03Y639567I0J-6103D01*
G01X8090Y691713D02*
X6712D01*
G01X6857Y681142D02*
X7716D01*
G01X7287Y680703D02*
X8254Y677740D01*
G01D02*
X6319D01*
G01X8361Y677302D02*
X6212D01*
G01X5782Y675985D02*
X5138D01*
G01X39390Y673622D02*
X2775D01*
G01X19Y672146D02*
X2775D01*
G01D02*
X39390D01*
G01X2775Y671162D02*
X19D01*
G01X39390D02*
X2775D01*
G01X39Y669292D02*
X90590D01*
G01X3937Y662796D02*
X46456D01*
G01X16338Y651772D02*
X6890D01*
G01Y639567D02*
X21063D01*
G01X3937Y628544D02*
X46456D01*
G01X7591Y671162D02*
Y672146D01*
G01X6890Y639567D02*
Y651772D01*
G01X6240Y672146D02*
Y671162D01*
G01X6227Y672146D02*
Y671162D01*
G01X5932D02*
Y672146D01*
G01X5925Y699311D02*
Y692500D01*
G01X5827Y672146D02*
Y671162D01*
G01X5649Y672146D02*
Y671162D01*
G01X4645Y672146D02*
Y671162D01*
G01X3937Y662796D02*
Y628544D01*
G01X2775Y742225D02*
Y671162D01*
G01X807D02*
Y672146D01*
G01X39Y744095D02*
Y669292D01*
G01X19Y672146D02*
Y671162D01*
G01X6857Y681142D02*
X5138Y675985D01*
G01X6212Y677302D02*
X5782Y675985D01*
G01X7287Y680703D02*
X6319Y677740D01*
G01X6890Y769882D02*
G03Y757677I0J-6102D01*
G01X6712Y721674D02*
G03X5925Y720886I1J-788D01*
G01Y714075D02*
G03X6712Y713288I787J0D01*
G01Y700099D02*
G03X5925Y699311I0J-787D01*
G01X6890Y757677D02*
X21063D01*
G01X3937Y746654D02*
X46456D01*
G01X90590Y744095D02*
X39D01*
G01X19Y742225D02*
X2775D01*
G01D02*
X39390D01*
G01X2775Y741240D02*
X19D01*
G01X39390D02*
X2775D01*
G01X39390Y739764D02*
X2775D01*
G01X8090Y721674D02*
X6712D01*
G01X8090Y713288D02*
X6712D01*
G01X8090Y700099D02*
X6712D01*
G01X6890Y757677D02*
Y769882D01*
G01X6240Y742225D02*
Y741240D01*
G01X5925Y720886D02*
Y714075D01*
G01X5649Y742225D02*
Y741240D01*
G01X3937Y780906D02*
Y746654D01*
G01X807Y742225D02*
Y741240D01*
G01X19Y742225D02*
Y741240D01*
G01X3937Y787402D02*
G03X0Y783465I0J-3937D01*
G01X3937Y787402D02*
G03X0Y783465I0J-3937D01*
G01X3937Y795276D02*
G03X-7874Y783465I0J-11811D01*
G01X3937Y795276D02*
X8661D01*
G01X3937Y787402D02*
X74803D01*
G01X3937D02*
X74803D01*
G01X3937Y780906D02*
X46456D01*
G01X16338Y769882D02*
X6890D01*
G01X-12402Y1023248D02*
X-12061Y1022225D01*
X-11208Y1021457D01*
X-10184Y1020945D01*
X-8819Y1020562D01*
X-7284Y1020434D01*
X-5748Y1020562D01*
X-4384Y1020945D01*
X-3360Y1021457D01*
X-2507Y1022225D01*
X-2166Y1023248D01*
X-2507Y1024272D01*
X-3360Y1025040D01*
X-4384Y1025552D01*
X-5748Y1025935D01*
X-7284Y1026063D01*
X-8819Y1025935D01*
X-10184Y1025552D01*
X-11208Y1025040D01*
X-12061Y1024272D01*
X-12402Y1023248D01*
G01X-1825Y1033484D02*
X-1995Y1033229D01*
X-2337D01*
X-2507Y1033484D01*
X-2337Y1033740D01*
X-1995D01*
X-1825Y1033484D01*
G01X-12402Y1043720D02*
X-12061Y1042697D01*
X-11208Y1041929D01*
X-10184Y1041417D01*
X-8819Y1041034D01*
X-7284Y1040906D01*
X-5748Y1041034D01*
X-4384Y1041417D01*
X-3360Y1041929D01*
X-2507Y1042697D01*
X-2166Y1043720D01*
X-2507Y1044744D01*
X-3360Y1045512D01*
X-4384Y1046024D01*
X-5748Y1046407D01*
X-7284Y1046535D01*
X-8819Y1046407D01*
X-10184Y1046024D01*
X-11208Y1045512D01*
X-12061Y1044744D01*
X-12402Y1043720D01*
G01Y1053956D02*
X-12061Y1052933D01*
X-11208Y1052165D01*
X-10184Y1051653D01*
X-8819Y1051270D01*
X-7284Y1051142D01*
X-5748Y1051270D01*
X-4384Y1051653D01*
X-3360Y1052165D01*
X-2507Y1052933D01*
X-2166Y1053956D01*
X-2507Y1054980D01*
X-3360Y1055748D01*
X-4384Y1056260D01*
X-5748Y1056643D01*
X-7284Y1056771D01*
X-8819Y1056643D01*
X-10184Y1056260D01*
X-11208Y1055748D01*
X-12061Y1054980D01*
X-12402Y1053956D01*
G01X16582Y-432731D02*
G03X16688Y-432337I-681J395D01*
G01X14923Y-433242D02*
G03X16287I682J393D01*
G01X14522Y-432337D02*
G03X14628Y-432731I787J1D01*
G01X10986Y-433242D02*
G03X12350I682J393D01*
G01X10585Y-432337D02*
G03X10691Y-432731I787J1D01*
G01X38236D02*
G03X38341Y-432337I-682J393D01*
G01X36577Y-433242D02*
G03X37941I682J393D01*
G01X36176Y-432337D02*
G03X36281Y-432731I787J-1D01*
G01X24456D02*
G03X24562Y-432337I-681J395D01*
G01X22797Y-433242D02*
G03X24161I682J393D01*
G01X22396Y-432337D02*
G03X22502Y-432731I787J1D01*
G01X12645D02*
G03X12751Y-432337I-681J395D01*
G01X28739Y-431012D02*
X34613D01*
G01X28739D02*
X26739D01*
G01X36613D02*
X34613D01*
G01X27339Y-431612D02*
X28139D01*
G01X36013D02*
X35213D01*
G01X44916Y-436392D02*
X46885D01*
G01X29955D02*
X31924D01*
G01X54771Y-436039D02*
X57046Y-436786D01*
G01X36613Y-431012D02*
X36013Y-431612D01*
G01X28139D02*
X28739Y-431012D01*
G01X35213Y-431612D02*
X34613Y-431012D01*
G01X26739D02*
X27339Y-431612D01*
G01X38236Y-432731D02*
X37941Y-433242D01*
G01X36577D02*
X36281Y-432731D01*
G01X24456D02*
X24161Y-433242D01*
G01X16582Y-432731D02*
X16287Y-433242D01*
G01X12645Y-432731D02*
X12350Y-433242D01*
G01X57046Y-436786D02*
X59566Y-429108D01*
G01X57046D02*
X54771Y-436039D01*
G01X22797Y-433242D02*
X22502Y-432731D01*
G01X14923Y-433242D02*
X14628Y-432731D01*
G01X10986Y-433242D02*
X10691Y-432731D01*
G01X46885Y-428912D02*
Y-436392D01*
G01X44916Y-428912D02*
Y-436392D01*
G01X38341Y-432337D02*
Y-428912D01*
G01X36613D02*
Y-431012D01*
G01X36176Y-431449D02*
Y-432337D01*
G01X34613Y-431012D02*
Y-428912D01*
G01X31924D02*
Y-436392D01*
G01X29955Y-428912D02*
Y-436392D01*
G01X28739Y-431012D02*
Y-428912D01*
G01X26739D02*
Y-431012D01*
G01X24562Y-432337D02*
Y-428912D01*
G01X22396D02*
Y-432337D01*
G01X16688D02*
Y-428912D01*
G01X14522D02*
Y-432337D01*
G01X12751D02*
Y-428912D01*
G01X10585D02*
Y-432337D01*
G01X69778Y-408242D02*
G03Y-406667I0J787D01*
G01X64487Y-395171D02*
G03X63994Y-395303I-1J-984D01*
G01X55963Y-395356D02*
G03X55472Y-395224I-492J-852D01*
G01X18558Y-388085D02*
G03X17705Y-388577I-1J-984D01*
G01X23347D02*
G03X24200Y-389069I852J492D01*
G01X16880D02*
G03X17705Y-388577I-28J984D01*
G01X23347D02*
G03X22495Y-388085I-852J-492D01*
G01X64434Y-394187D02*
G03X63548Y-394425I1J-1771D01*
G01X56409Y-394477D02*
G03X55524Y-394240I-885J-1535D01*
G01X34613Y-407805D02*
G03X32613Y-405805I-2000J0D01*
G01X59563Y-396088D02*
G03X61215Y-395772I372J2532D01*
G01X59563Y-397108D02*
G03X61608Y-396681I373J3325D01*
G01X36613Y-407805D02*
G03X32613Y-403805I-4000J0D01*
G01X11648Y-396825D02*
G03X10985Y-396861I-1J-6102D01*
G01X69778Y-412573D02*
G03Y-410998I0J788D01*
G01X63814Y-415919D02*
G03X63301Y-416109I0J-787D01*
G01X26739Y-415679D02*
G03X24739Y-413679I-2000J0D01*
G01X28739Y-415679D02*
G03X24739Y-411679I-4000J0D01*
G01X22495Y-388085D02*
X18558D01*
G01X23347Y-388577D02*
X17705D01*
G01X44148Y-389069D02*
X46550D01*
G01X46277Y-390053D02*
X44148D01*
G01X44916Y-391116D02*
X20507D01*
G01X47278Y-391210D02*
X45310D01*
G01X59566Y-391786D02*
X57046D01*
G01X52502Y-393793D02*
X52003D01*
G01X57046D02*
X54413D01*
G01X78381D02*
X59566D01*
G01X47278Y-394134D02*
X45310D01*
G01X65258Y-394187D02*
X64434D01*
G01X55524Y-394240D02*
X55155D01*
G01X64487Y-395171D02*
X65258D01*
G01X54882Y-395224D02*
X55472D01*
G01X20507Y-396825D02*
X11648D01*
G01X47278Y-397897D02*
X44916D01*
G01X59566Y-398715D02*
X78381D01*
G01X50822D02*
X57046D01*
G01Y-401353D02*
X48066D01*
G01X81924D02*
X59566D01*
G01X21739Y-402927D02*
X47278D01*
G01X57046Y-403045D02*
X59566D01*
G01X32613Y-403805D02*
X21739D01*
G01X57046Y-404699D02*
X48066D01*
G01X72042D02*
X59566D01*
G01X57046Y-404797D02*
X47278D01*
G01X70959D02*
X59566D01*
G01X32613Y-405805D02*
X21739D01*
G01X64463Y-406667D02*
X69778D01*
G01X64955Y-407455D02*
X70566D01*
G01X81924D02*
X72042D01*
G01X69778Y-408242D02*
X65379D01*
G01Y-410998D02*
X69778D01*
G01X64955Y-411392D02*
X70458D01*
G01X81924D02*
X72042D01*
G01X24739Y-411679D02*
X21739D01*
G01X53306Y-411982D02*
X63306D01*
G01X69778Y-412573D02*
X64463D01*
G01X21739Y-413679D02*
X24739D01*
G01X63306Y-414443D02*
X70959D01*
G01X47278D02*
X48755D01*
G01X72042Y-414541D02*
X63306D01*
G01X65786Y-415329D02*
X179959D01*
G01X65786Y-415919D02*
X63814D01*
G01X48755Y-416215D02*
X53306D01*
G01X48066D02*
X48755D01*
G01X65786Y-417573D02*
X63306D01*
G01X49050Y-418183D02*
X48755D01*
G01X53306D02*
X49050D01*
G01X46550Y-389069D02*
X55155Y-394240D01*
G01X54882Y-395224D02*
X46277Y-390053D01*
G01X56409Y-394477D02*
X57046Y-394844D01*
G01Y-395980D02*
X55963Y-395356D01*
G01X63994Y-395303D02*
X61608Y-396681D01*
G01X61215Y-395772D02*
X63548Y-394425D01*
G01X70959Y-404797D02*
X72141Y-405978D01*
G01Y-413262D02*
X70959Y-414443D01*
G01X48755Y-416904D02*
X48066Y-416215D01*
G01Y-419167D02*
X49050Y-418183D01*
G01X50822Y-394975D02*
X52003Y-393793D01*
G01X72141Y-413262D02*
Y-405978D01*
G01X72042Y-407455D02*
Y-404699D01*
G01Y-411392D02*
Y-414541D01*
G01X70353Y-407993D02*
Y-411248D01*
G01X69723Y-422612D02*
Y-415329D01*
G01X65786D02*
Y-422612D01*
G01X65379Y-408242D02*
Y-410998D01*
G01X65258Y-395171D02*
Y-394187D01*
G01X64955Y-411392D02*
Y-407455D01*
G01X64463Y-412573D02*
Y-406667D01*
G01X63306Y-422612D02*
Y-411982D01*
G01X61942D02*
Y-422612D01*
G01X59566Y-411982D02*
Y-391786D01*
G01X57046Y-411982D02*
Y-391786D01*
G01X54670Y-422612D02*
Y-411982D01*
G01X53306D02*
Y-422612D01*
G01X52003Y-401353D02*
Y-393793D01*
G01X50822Y-401353D02*
Y-394975D01*
G01X48755Y-418183D02*
Y-414443D01*
G01X48597Y-404699D02*
Y-404797D01*
G01X48561D02*
Y-414443D01*
G01X48066Y-416215D02*
Y-414443D01*
G01Y-419167D02*
Y-422612D01*
G01Y-401353D02*
Y-404699D01*
G01X47941Y-414443D02*
Y-404797D01*
G01X47278Y-422612D02*
Y-391210D01*
G01X45310Y-397897D02*
Y-394134D01*
G01X44916Y-391314D02*
Y-391116D01*
G01Y-397897D02*
Y-393764D01*
G01X44148Y-391116D02*
Y-389069D01*
G01X36613Y-407805D02*
Y-422612D01*
G01X34613D02*
Y-407805D01*
G01X28739Y-422612D02*
Y-415679D01*
G01X26739D02*
Y-422612D01*
G01X21739D02*
Y-396873D01*
G01X20507D02*
Y-391117D01*
G01X11648Y-396873D02*
Y-396825D01*
G01X8696Y-428912D02*
Y-422612D01*
G01X62204Y0D02*
G03Y-7874I0J-3937D01*
G01X31496D02*
G03Y0I0J3937D01*
G01X267716Y-7874D02*
X62204D01*
G01X86614Y19685D02*
G03I-9843J0D01*
G01X95472D02*
G03I-18701J0D01*
G01X24575Y59055D02*
G03I-1595J0D01*
G01X32449D02*
G03I-1595J0D01*
G01X39370Y19685D02*
G03I-9843J0D01*
G01X48228D02*
G03I-18701J0D01*
G01X31412Y57113D02*
X31613Y57179D01*
G01X23262Y56798D02*
X23464Y56864D01*
G01X30139Y59344D02*
X29938Y59279D01*
G01X21989Y59029D02*
X21788Y58964D01*
G01X31613Y57179D02*
X31881Y57310D01*
G01X29938Y59279D02*
X29670Y59147D01*
G01X23464Y56864D02*
X23732Y56995D01*
G01X21788Y58964D02*
X21520Y58832D01*
G01X31412Y57441D02*
X31814Y57704D01*
G01X30139Y59016D02*
X29737Y58753D01*
G01X23262Y57126D02*
X23665Y57389D01*
G01X21989Y58701D02*
X21587Y58439D01*
G01X21788Y61588D02*
X21587Y61457D01*
G01X31881Y57310D02*
X32082Y57507D01*
G01X29670Y59147D02*
X29469Y58950D01*
G01X23732Y56995D02*
X23932Y57192D01*
G01X21520Y58832D02*
X21319Y58635D01*
G01X21252Y61654D02*
X21520Y61916D01*
G01X31254Y59457D02*
X31854Y60057D01*
G01X30454Y58657D02*
X29854Y58057D01*
G01X23380Y59457D02*
X23980Y60057D01*
G01X21980Y58057D02*
X22580Y58657D01*
G01X31814Y57704D02*
X31948Y57901D01*
G01X29737Y58753D02*
X29603Y58557D01*
G01X23665Y57389D02*
X23799Y57586D01*
G01X21587Y58439D02*
X21453Y58242D01*
G01X21587Y61457D02*
X21453Y61260D01*
G01X32082Y57507D02*
X32283Y57835D01*
G01X29469Y58950D02*
X29268Y58622D01*
G01X23932Y57192D02*
X24134Y57520D01*
G01X21319Y58635D02*
X21118Y58307D01*
G01Y61391D02*
X21252Y61654D01*
G01X31948Y57901D02*
X32015Y58229D01*
G01X29603Y58557D02*
X29536Y58229D01*
G01X23799Y57586D02*
X23865Y57914D01*
G01X21453Y58242D02*
X21386Y57914D01*
G01X21453Y61260D02*
X21386Y60932D01*
G01X32283Y57835D02*
X32350Y58229D01*
G01X29268Y58622D02*
X29201Y58229D01*
G01X24134Y57520D02*
X24201Y57914D01*
G01X21118Y58307D02*
X21051Y57914D01*
G01Y60998D02*
X21118Y61391D01*
G01X33823Y116895D02*
Y48460D01*
G01X32350Y60722D02*
Y60328D01*
G01X31854Y60057D02*
Y58057D01*
G01X31254Y58657D02*
Y59457D01*
G01X30454Y58657D02*
Y59457D01*
G01X21118Y60276D02*
X21051Y60735D01*
G01X32350Y58229D02*
X32283Y58622D01*
G01X29854Y60057D02*
Y58057D01*
G01X29201Y60328D02*
Y60722D01*
G01X27854Y60057D02*
Y58057D01*
G01X24201Y61982D02*
Y59620D01*
G01X23980Y60057D02*
Y58057D01*
G01X23865Y60145D02*
Y61982D01*
G01X23380Y58657D02*
Y59457D01*
G01X22580Y58657D02*
Y59457D01*
G01X21980Y60057D02*
Y58057D01*
G01X21788Y60013D02*
Y59685D01*
G01X21386Y60932D02*
Y60670D01*
G01X21051Y60735D02*
Y60998D01*
G01X19980Y60057D02*
Y58057D01*
G01X16980Y53928D02*
Y50428D01*
G01X15480Y53928D02*
Y111426D01*
G01X11480D02*
Y53928D01*
G01X10480D02*
Y111426D01*
G01X29201Y58229D02*
X29268Y57835D01*
G01X24201Y57914D02*
X24134Y58307D01*
G01X21051Y57914D02*
X21118Y57520D01*
G01X32015Y58229D02*
X31948Y58557D01*
G01X29536Y58229D02*
X29603Y57901D01*
G01X23865Y57914D02*
X23799Y58242D01*
G01X21386Y60670D02*
X21453Y60342D01*
G01X21386Y57914D02*
X21453Y57586D01*
G01X21252Y60013D02*
X21118Y60276D01*
G01X32283Y58622D02*
X32082Y58950D01*
G01X29268Y57835D02*
X29469Y57507D01*
G01X24134Y58307D02*
X23932Y58635D01*
G01X21118Y57520D02*
X21319Y57192D01*
G01X31948Y58557D02*
X31814Y58753D01*
G01X29603Y57901D02*
X29737Y57704D01*
G01X23799Y58242D02*
X23665Y58439D01*
G01X21453Y60342D02*
X21587Y60145D01*
G01X21453Y57586D02*
X21587Y57389D01*
G01X22391Y61785D02*
X23865Y60145D01*
G01Y59620D02*
X22190Y61457D01*
G01X29854Y60057D02*
X30454Y59457D01*
G01X31854Y58057D02*
X31254Y58657D01*
G01X23380D02*
X23980Y58057D01*
G01X21980Y60057D02*
X22580Y59457D01*
G01X32082Y58950D02*
X31881Y59147D01*
G01X29469Y57507D02*
X29670Y57310D01*
G01X23932Y58635D02*
X23732Y58832D01*
G01X21520Y59751D02*
X21252Y60013D01*
G01X21319Y57192D02*
X21520Y56995D01*
G01X29737Y60328D02*
X30206Y59935D01*
G01X29670D02*
X29201Y60328D01*
G01X31814Y58753D02*
X31412Y59016D01*
G01X29737Y57704D02*
X30139Y57441D01*
G01X22190Y61916D02*
X22391Y61785D01*
G01X21587Y60145D02*
X21788Y60013D01*
G01X23665Y58439D02*
X23262Y58701D01*
G01X21587Y57389D02*
X21989Y57126D01*
G01X31881Y59147D02*
X31613Y59279D01*
G01X22190Y61457D02*
X21922Y61588D01*
G01X29670Y57310D02*
X29938Y57179D01*
G01X23732Y58832D02*
X23464Y58964D01*
G01X21520Y56995D02*
X21788Y56864D01*
G01X31613Y59279D02*
X31412Y59344D01*
G01X29938Y57179D02*
X30139Y57113D01*
G01X23464Y58964D02*
X23262Y59029D01*
G01X21788Y56864D02*
X21989Y56798D01*
G01X21922Y61982D02*
X22190Y61916D01*
G01X21788Y59685D02*
X21520Y59751D01*
G01X31412Y59344D02*
X31077Y59410D01*
G01X23262Y59029D02*
X22927Y59095D01*
G01X30139Y57113D02*
X30474Y57048D01*
G01X21989Y56798D02*
X22324Y56733D01*
G01X31412Y59016D02*
X31010Y59082D01*
G01X23262Y58701D02*
X22860Y58767D01*
G01X30139Y57441D02*
X30541Y57376D01*
G01X21989Y57126D02*
X22391Y57061D01*
G01X21788Y61982D02*
X21922D01*
G01X23865D02*
X24201D01*
G01X21922Y61588D02*
X21788D01*
G01X29201Y60722D02*
X32350D01*
G01Y60328D02*
X29737D01*
G01X15480Y60057D02*
X31854D01*
G01X30206Y59935D02*
X29670D01*
G01X24201Y59620D02*
X23865D01*
G01X30454Y59457D02*
X31254D01*
G01X22580D02*
X23380D01*
G01X31077Y59410D02*
X30474D01*
G01X22927Y59095D02*
X22324D01*
G01X31010Y59082D02*
X30541D01*
G01X22860Y58767D02*
X22391D01*
G01X22580Y58657D02*
X23380D01*
G01X31254D02*
X30454D01*
G01X31854Y58057D02*
X15480D01*
G01X30541Y57376D02*
X31010D01*
G01X22391Y57061D02*
X22860D01*
G01X30474Y57048D02*
X31077D01*
G01X22324Y56733D02*
X22927D01*
G01X62204Y0D02*
X31496D01*
G01X22391Y58767D02*
X21989Y58701D01*
G01X30541Y59082D02*
X30139Y59016D01*
G01X22860Y57061D02*
X23262Y57126D01*
G01X31010Y57376D02*
X31412Y57441D01*
G01X22324Y59095D02*
X21989Y59029D01*
G01X30474Y59410D02*
X30139Y59344D01*
G01X22927Y56733D02*
X23262Y56798D01*
G01X31077Y57048D02*
X31412Y57113D01*
G01X21520Y61916D02*
X21788Y61982D01*
G01X24575Y106300D02*
G03I-1595J0D01*
G01X32449D02*
G03I-1595J0D01*
G01X24575Y98426D02*
G03I-1595J0D01*
G01Y90552D02*
G03I-1595J0D01*
G01Y82677D02*
G03I-1595J0D01*
G01Y74803D02*
G03I-1595J0D01*
G01Y66929D02*
G03I-1595J0D01*
G01X32449Y98426D02*
G03I-1595J0D01*
G01Y90552D02*
G03I-1595J0D01*
G01Y82677D02*
G03I-1595J0D01*
G01Y74803D02*
G03I-1595J0D01*
G01Y66929D02*
G03I-1595J0D01*
G01X31775Y105906D02*
X31574Y105840D01*
G01Y106168D02*
X31708Y106234D01*
G01X31306Y107874D02*
X31038Y107743D01*
G01X31976Y106037D02*
X31775Y105906D01*
G01X30837Y108005D02*
X31038Y108137D01*
G01X29899Y107809D02*
X29697Y107677D01*
G01X31708Y106234D02*
X31842Y106365D01*
G01X29362Y107809D02*
X29630Y108071D01*
G01X31254Y67331D02*
X31854Y67931D01*
G01X30454Y66531D02*
X29854Y65931D01*
G01X31254Y75205D02*
X31854Y75805D01*
G01X21980Y65931D02*
X22580Y66531D01*
G01X23380Y67331D02*
X23980Y67931D01*
G01X30454Y74405D02*
X29854Y73805D01*
G01X31254Y83078D02*
X31854Y83678D01*
G01X21980Y73805D02*
X22580Y74405D01*
G01X23380Y75205D02*
X23980Y75805D01*
G01X30454Y82278D02*
X29854Y81678D01*
G01X31254Y90952D02*
X31854Y91552D01*
G01X21980Y81678D02*
X22580Y82278D01*
G01X23380Y83078D02*
X23980Y83678D01*
G01X30454Y90152D02*
X29854Y89552D01*
G01X31254Y98826D02*
X31854Y99426D01*
G01X23380Y90952D02*
X23980Y91552D01*
G01X21980Y89552D02*
X22580Y90152D01*
G01X30454Y98026D02*
X29854Y97426D01*
G01X31254Y106700D02*
X31854Y107300D01*
G01X23380Y98826D02*
X23980Y99426D01*
G01X21980Y97426D02*
X22580Y98026D01*
G01X30454Y105900D02*
X29854Y105300D01*
G01X21980D02*
X22580Y105900D01*
G01X23380Y106700D02*
X23980Y107300D01*
G01X32110Y106234D02*
X31976Y106037D01*
G01X31038Y107743D02*
X30904Y107546D01*
G01X29697Y107677D02*
X29564Y107481D01*
G01X32244Y106496D02*
X32110Y106234D01*
G01X31842Y106365D02*
X31909Y106496D01*
G01X29228Y107546D02*
X29362Y107809D01*
G01X30703Y107677D02*
X30837Y108005D01*
G01X32311Y106759D02*
X32244Y106496D01*
G01X31909D02*
X31976Y106824D01*
G01X29564Y107481D02*
X29496Y107153D01*
G01X30904Y107546D02*
X30837Y107153D01*
G01X29161Y107087D02*
X29228Y107546D01*
G01X46456Y128544D02*
Y162796D01*
G01X42519Y132481D02*
Y134685D01*
G01X32311Y107284D02*
Y106759D01*
G01Y105315D02*
Y104922D01*
G01X31976Y106824D02*
Y107218D01*
G01X31854Y67931D02*
Y65931D01*
G01Y75805D02*
Y73805D01*
G01Y83678D02*
Y81678D01*
G01Y91552D02*
Y89552D01*
G01Y99426D02*
Y97426D01*
G01Y107300D02*
Y105300D01*
G01X31574Y105840D02*
Y106168D01*
G01X31254Y105900D02*
Y106700D01*
G01Y98026D02*
Y98826D01*
G01Y90152D02*
Y90952D01*
G01Y82278D02*
Y83078D01*
G01Y74405D02*
Y75205D01*
G01Y66531D02*
Y67331D01*
G01X30837Y107153D02*
Y106890D01*
G01X30569D02*
Y107153D01*
G01X30454Y105900D02*
Y106700D01*
G01Y98026D02*
Y98826D01*
G01Y90152D02*
Y90952D01*
G01Y82278D02*
Y83078D01*
G01Y74405D02*
Y75205D01*
G01Y66531D02*
Y67331D01*
G01X29228Y106496D02*
X29161Y106956D01*
G01X29899Y106234D02*
Y105906D01*
G01X29854Y67931D02*
Y65931D01*
G01Y75805D02*
Y73805D01*
G01Y83678D02*
Y81678D01*
G01Y91552D02*
Y89552D01*
G01Y99426D02*
Y97426D01*
G01Y107300D02*
Y105300D01*
G01X29496Y107153D02*
Y106890D01*
G01X29161Y106956D02*
Y107087D01*
G01Y104922D02*
Y105315D01*
G01X27854Y67931D02*
Y65931D01*
G01Y75805D02*
Y73805D01*
G01Y83678D02*
Y81678D01*
G01Y91552D02*
Y89552D01*
G01Y99426D02*
Y97426D01*
G01Y107300D02*
Y105300D01*
G01X24397Y107809D02*
Y107415D01*
G01Y105315D02*
Y104922D01*
G01X23980Y67931D02*
Y65931D01*
G01Y75805D02*
Y73805D01*
G01Y83678D02*
Y81678D01*
G01Y91552D02*
Y89552D01*
G01Y99426D02*
Y97426D01*
G01Y107300D02*
Y105300D01*
G01X23459Y108465D02*
Y107809D01*
G01Y107415D02*
Y105840D01*
G01X23380Y105900D02*
Y106700D01*
G01Y98026D02*
Y98826D01*
G01Y90152D02*
Y90952D01*
G01Y82278D02*
Y83078D01*
G01Y74405D02*
Y75205D01*
G01Y66531D02*
Y67331D01*
G01X23057Y107809D02*
Y108465D01*
G01Y107415D02*
Y106300D01*
G01X22580Y105900D02*
Y106700D01*
G01Y98026D02*
Y98826D01*
G01Y90152D02*
Y90952D01*
G01Y82278D02*
Y83078D01*
G01Y74405D02*
Y75205D01*
G01Y66531D02*
Y67331D01*
G01X21980Y67931D02*
Y65931D01*
G01Y75805D02*
Y73805D01*
G01Y83678D02*
Y81678D01*
G01Y91552D02*
Y89552D01*
G01Y99426D02*
Y97426D01*
G01Y107300D02*
Y105300D01*
G01X21248Y107415D02*
Y107809D01*
G01Y104922D02*
Y105315D01*
G01X19980Y67931D02*
Y65931D01*
G01Y75805D02*
Y73805D01*
G01Y83678D02*
Y81678D01*
G01Y91552D02*
Y89552D01*
G01Y99426D02*
Y97426D01*
G01Y107300D02*
Y105300D01*
G01X16980Y114926D02*
Y111426D01*
G01X15748Y158859D02*
Y132481D01*
G01X9480Y87677D02*
Y77677D01*
G01X31976Y107218D02*
X31909Y107546D01*
G01X29496Y106890D02*
X29564Y106562D01*
G01X32244Y107546D02*
X32311Y107284D01*
G01X30569Y107153D02*
X30434Y107546D01*
G01X32110Y107809D02*
X32244Y107546D01*
G01X31909D02*
X31842Y107677D01*
G01X29362Y106234D02*
X29228Y106496D01*
G01X31976Y108005D02*
X32110Y107809D01*
G01X29564Y106562D02*
X29697Y106365D01*
G01X30502Y107940D02*
X30703Y107677D01*
G01X29854Y107300D02*
X30454Y106700D01*
G01X31854Y105300D02*
X31254Y105900D01*
G01X29854Y99426D02*
X30454Y98826D01*
G01X23380Y105900D02*
X23980Y105300D01*
G01X21980Y107300D02*
X22580Y106700D01*
G01X31854Y97426D02*
X31254Y98026D01*
G01X29854Y91552D02*
X30454Y90952D01*
G01X23380Y98026D02*
X23980Y97426D01*
G01X21980Y99426D02*
X22580Y98826D01*
G01X31854Y89552D02*
X31254Y90152D01*
G01X29854Y83678D02*
X30454Y83078D01*
G01X23380Y90152D02*
X23980Y89552D01*
G01X21980Y91552D02*
X22580Y90952D01*
G01X31854Y81678D02*
X31254Y82278D01*
G01X29854Y75805D02*
X30454Y75205D01*
G01X23380Y82278D02*
X23980Y81678D01*
G01X21980Y83678D02*
X22580Y83078D01*
G01X31854Y73805D02*
X31254Y74405D01*
G01X29854Y67931D02*
X30454Y67331D01*
G01X23380Y74405D02*
X23980Y73805D01*
G01X21980Y75805D02*
X22580Y75205D01*
G01X31854Y65931D02*
X31254Y66531D01*
G01X23380D02*
X23980Y65931D01*
G01X21980Y67931D02*
X22580Y67331D01*
G01X31842Y107677D02*
X31708Y107809D01*
G01X30434Y107546D02*
X30301Y107677D01*
G01X29630Y105972D02*
X29362Y106234D01*
G01X23057Y106300D02*
X21784Y107415D01*
G01X23057Y105840D02*
X21248Y107415D01*
G01X29697Y104922D02*
X30167Y104528D01*
G01X29630D02*
X29161Y104922D01*
G01X21784D02*
X22253Y104528D01*
G01X21717D02*
X21248Y104922D01*
G01X31775Y108137D02*
X31976Y108005D01*
G01X30301Y108071D02*
X30502Y107940D01*
G01X29697Y106365D02*
X29899Y106234D01*
G01X31708Y107809D02*
X31574Y107874D01*
G01X30301Y107677D02*
X30032Y107809D01*
G01X31574Y108202D02*
X31775Y108137D01*
G01X30032D02*
X30301Y108071D01*
G01X29899Y105906D02*
X29630Y105972D01*
G01X15748Y132481D02*
X42519D01*
G01X23057Y108465D02*
X23459D01*
G01X31306Y108202D02*
X31574D01*
G01X29899Y108137D02*
X30032D01*
G01X31574Y107874D02*
X31306D01*
G01X21248Y107809D02*
X23057D01*
G01X23459D02*
X24397D01*
G01X30032D02*
X29899D01*
G01X21784Y107415D02*
X23057D01*
G01X24397D02*
X23459D01*
G01X15480Y107300D02*
X31854D01*
G01X30837Y106890D02*
X30569D01*
G01X30454Y106700D02*
X31254D01*
G01X22580D02*
X23380D01*
G01X22580Y105900D02*
X23380D01*
G01X31254D02*
X30454D01*
G01X23459Y105840D02*
X23057D01*
G01X29161Y105315D02*
X32311D01*
G01X21248D02*
X24397D01*
G01X31854Y105300D02*
X15480D01*
G01X24397Y104922D02*
X21784D01*
G01X32311D02*
X29697D01*
G01X22253Y104528D02*
X21717D01*
G01X30167D02*
X29630D01*
G01X15480Y99426D02*
X31854D01*
G01X30454Y98826D02*
X31254D01*
G01X22580D02*
X23380D01*
G01X22580Y98026D02*
X23380D01*
G01X31254D02*
X30454D01*
G01X31854Y97426D02*
X15480D01*
G01Y91552D02*
X31854D01*
G01X30454Y90952D02*
X31254D01*
G01X22580D02*
X23380D01*
G01X22580Y90152D02*
X23380D01*
G01X31254D02*
X30454D01*
G01X31854Y89552D02*
X15480D01*
G01Y83678D02*
X31854D01*
G01X23980D02*
X29854D01*
G01X30454Y83078D02*
X31254D01*
G01X22580D02*
X23380D01*
G01X22580Y82278D02*
X23380D01*
G01X31254D02*
X30454D01*
G01X31854Y81678D02*
X15480D01*
G01Y75805D02*
X31854D01*
G01X30454Y75205D02*
X31254D01*
G01X22580D02*
X23380D01*
G01X22580Y74405D02*
X23380D01*
G01X31254D02*
X30454D01*
G01X31854Y73805D02*
X15480D01*
G01Y67931D02*
X31854D01*
G01X30454Y67331D02*
X31254D01*
G01X22580D02*
X23380D01*
G01X22580Y66531D02*
X23380D01*
G01X31254D02*
X30454D01*
G01X31854Y65931D02*
X15480D01*
G01X29630Y108071D02*
X29899Y108137D01*
G01X31038D02*
X31306Y108202D01*
G01X21260Y148386D02*
G03X21063Y148189I0J-197D01*
G01Y146851D02*
G03X21260Y146654I197J0D01*
G01Y144685D02*
G03X21063Y144489I0J-197D01*
G01Y143150D02*
G03X21260Y142953I197J0D01*
G01X27721Y154685D02*
G03X27131Y154095I0J-590D01*
G01X27362Y137244D02*
G03X27953Y136654I590J0D01*
G01X27362Y142363D02*
G03X26771Y142953I-591J-1D01*
G01X26343Y150748D02*
X23031Y148386D01*
G01X40551Y154095D02*
X38582Y152126D01*
G01X40551Y144095D02*
X38582Y140552D01*
G01X21063Y149961D02*
X23976Y156654D01*
G01X42519D02*
Y158859D01*
G01Y135817D02*
Y135571D01*
G01Y144685D02*
Y136654D01*
G01Y154685D02*
Y146654D01*
G01X42126Y136654D02*
Y134685D01*
G01Y146654D02*
Y144685D01*
G01Y156654D02*
Y154685D01*
G01X41378Y136654D02*
Y134685D01*
G01Y146654D02*
Y144685D01*
G01Y156654D02*
Y154685D01*
G01X40551Y135571D02*
Y135817D01*
G01X40157Y144685D02*
Y146654D01*
G01Y136654D02*
Y134685D01*
G01Y137717D02*
Y134095D01*
G01Y147953D02*
Y143386D01*
G01Y156654D02*
Y154685D01*
G01Y157244D02*
Y153701D01*
G01X38582Y157244D02*
Y134095D01*
G01X37401Y152682D02*
Y139502D01*
G01X27362Y142363D02*
Y137244D01*
G01X27131Y154095D02*
Y150748D01*
G01X21260Y142953D02*
Y140747D01*
G01Y146654D02*
Y144685D01*
G01X21063Y139567D02*
Y153113D01*
G01Y153700D02*
Y139502D01*
G01X19685Y156103D02*
Y135237D01*
G01X17126Y139567D02*
Y153113D01*
G01X16338Y139567D02*
Y152528D01*
G01X23897Y134685D02*
X21063Y141199D01*
G01X38582Y150788D02*
X40551Y147244D01*
G01Y137244D02*
X38582Y139607D01*
G01X42227Y136063D02*
X42519Y135817D01*
G01X42184D02*
X41891Y136063D01*
G01X15748Y158859D02*
X42519D01*
G01X38582Y157244D02*
X42519D01*
G01X15748Y156851D02*
X40157D01*
G01X23976Y156654D02*
X42126D01*
G01X42519D02*
X40157D01*
G01Y156103D02*
X19685D01*
G01X27721Y154685D02*
X42126D01*
G01X42519D02*
X40157D01*
G01X42519Y154095D02*
X40551D01*
G01X21063Y153700D02*
X15748D01*
G01X17126Y153150D02*
X21063D01*
G01X37401Y152682D02*
X21063D01*
G01X16338Y152559D02*
X17126D01*
G01X27131Y150748D02*
X26343D01*
G01X23031Y148386D02*
X21260D01*
G01X42519Y147244D02*
X40551D01*
G01X21260Y146654D02*
X42126D01*
G01X42519D02*
X40157D01*
G01X42126Y144685D02*
X21260D01*
G01X42519D02*
X40157D01*
G01X42519Y144095D02*
X40551D01*
G01X21260Y142953D02*
X26771D01*
G01X21063Y139528D02*
X15748D01*
G01X37401Y139502D02*
X21063D01*
G01X42519Y137244D02*
X40551D01*
G01X27953Y136654D02*
X42126D01*
G01X42519D02*
X40157D01*
G01X41891Y136063D02*
X42227D01*
G01X40551Y135817D02*
X42184D01*
G01X42519Y135571D02*
X40551D01*
G01X40157Y135237D02*
X19685D01*
G01X42126Y134685D02*
X23897D01*
G01X42519D02*
X40157D01*
G01X15748Y134489D02*
X40157D01*
G01X38582Y134095D02*
X42519D01*
G01X55437Y322486D02*
G03I-1890J0D01*
G01Y302486D02*
G03I-1890J0D01*
G01X58547Y298274D02*
X57183Y297486D01*
G01X58547Y308274D02*
X57183Y307486D01*
G01X49911D02*
X48547Y306699D01*
G01X54020Y300790D02*
X54221Y300921D01*
G01X54556Y300724D02*
X54288Y300462D01*
G01X54221Y300921D02*
X54355Y301118D01*
G01X54690Y300987D02*
X54556Y300724D01*
G01X58547Y318274D02*
X57183Y317486D01*
G01X49911D02*
X48547Y316699D01*
G01X49911Y327486D02*
X48547Y326699D01*
G01X54355Y301118D02*
X54422Y301446D01*
G01X54757Y301380D02*
X54690Y300987D01*
G01X62484Y293549D02*
Y331423D01*
G01X58547Y318274D02*
Y326699D01*
G01Y308274D02*
Y316699D01*
G01Y298274D02*
Y306699D01*
G01X54807Y323746D02*
Y301226D01*
G01X54757Y301643D02*
Y301380D01*
G01X54471Y324105D02*
Y323711D01*
G01X54422Y301446D02*
Y301708D01*
G01X54020Y302365D02*
Y302692D01*
G01X52287Y323746D02*
Y301226D01*
G01X51942Y302233D02*
Y300396D01*
G01X51607D02*
Y302758D01*
G01X51321Y323711D02*
Y324105D01*
G01X50013Y321226D02*
Y323746D01*
G01Y301226D02*
Y303746D01*
G01X48547Y306699D02*
Y298274D01*
G01Y316699D02*
Y308274D01*
G01Y326699D02*
Y318274D01*
G01X44610Y331423D02*
Y293549D01*
G01X35433Y335315D02*
Y540040D01*
G01X54690Y302102D02*
X54757Y301643D01*
G01X54422Y301708D02*
X54355Y302037D01*
G01X54556Y302365D02*
X54690Y302102D01*
G01X54355Y302037D02*
X54221Y302233D01*
G01X53417Y300593D02*
X51942Y302233D01*
G01Y302758D02*
X53617Y300921D01*
G01X54288Y302627D02*
X54556Y302365D01*
G01X54002Y324499D02*
X54471Y324105D01*
G01X53935D02*
X53466Y324499D01*
G01X54221Y302233D02*
X54020Y302365D01*
G01X53617Y300462D02*
X53417Y300593D01*
G01X58547Y326699D02*
X57183Y327486D01*
G01X58547Y316699D02*
X57183Y317486D01*
G01X49911D02*
X48547Y318274D01*
G01X58547Y306699D02*
X57183Y307486D01*
G01X49911D02*
X48547Y308274D01*
G01X49911Y297486D02*
X48547Y298274D01*
G01X53617Y300921D02*
X53886Y300790D01*
G01X54020Y302692D02*
X54288Y302627D01*
G01X53886Y300396D02*
X53617Y300462D01*
G01X200787Y335315D02*
X35433D01*
G01X62484Y331423D02*
X44610D01*
G01X57183Y327486D02*
X49911D01*
G01X53466Y324499D02*
X54002D01*
G01X51321Y324105D02*
X53935D01*
G01X54807Y323746D02*
X50013D01*
G01X54471Y323711D02*
X51321D01*
G01X54807Y321226D02*
X50013D01*
G01X54807Y303746D02*
X50013D01*
G01X51607Y302758D02*
X51942D01*
G01X54807Y301226D02*
X50013D01*
G01X53886Y300790D02*
X54020D01*
G01X51942Y300396D02*
X51607D01*
G01X54020D02*
X53886D01*
G01X49911Y297486D02*
X57183D01*
G01X44610Y293549D02*
X62484D01*
G01X54288Y300462D02*
X54020Y300396D01*
G01X61027Y388510D02*
G03X64964Y384573I3937J0D01*
G01X76775Y404258D02*
G03X80712Y400321I3937J0D01*
G01X76775Y479061D02*
Y404258D01*
G01X61027Y494809D02*
Y388510D01*
G01X64964Y384573D02*
X171264D01*
G01X80712Y482998D02*
G03X76775Y479061I0J-3937D01*
G01X43484Y555315D02*
G03X43174Y555265I0J-984D01*
G01X66342Y494809D02*
G03I-1378J0D01*
G01X43802Y554331D02*
G03X43182Y554231I-1J-1969D01*
G01X53754Y558800D02*
G03X55695I970J-1713D01*
G01X53565Y559587D02*
G03X55884I1160J-2500D01*
G01X57795Y557087D02*
G03I-3071J0D01*
G01X64964Y498746D02*
G03X61027Y494809I0J-3937D01*
G01X17582Y554854D02*
G03X18226Y554567I696J696D01*
G01X15687Y555357D02*
G03X14484Y555505I-696J-696D01*
G01X20000Y553544D02*
G03I-1575J0D01*
G01X33779D02*
G03I-1575J0D01*
G01X16383Y556053D02*
G03X13977Y556348I-1392J-1392D01*
G01X16886Y554158D02*
G03X18175Y553584I1392J1392D01*
G01X39390Y553053D02*
G03X39928Y553152I-84J1967D01*
G01X12761Y536575D02*
G03X12170Y535985I0J-591D01*
G01X12401Y519134D02*
G03X12992Y518544I591J1D01*
G01X12401Y524252D02*
G03X11811Y524843I-590J1D01*
G01X23622Y532677D02*
X25590Y529134D01*
G01X13045Y555789D02*
X13553Y554945D01*
G01X11358Y554775D02*
X11865Y553931D01*
G01X17582Y554854D02*
X16383Y556053D01*
G01X16886Y554158D02*
X15687Y555357D01*
G01X60807Y556260D02*
X60620Y555294D01*
G01X77165Y554331D02*
Y622835D01*
G01X73228Y554331D02*
Y560000D01*
G01X72441D02*
Y554331D01*
G01X71653Y560532D02*
Y554331D01*
G01X67382Y555315D02*
Y554331D01*
G01X67283Y555315D02*
Y554331D01*
G01X66838Y493547D02*
Y493153D01*
G01Y496040D02*
Y495516D01*
G01X66201Y555315D02*
Y554331D01*
G01X65807Y555315D02*
Y554331D01*
G01X65019Y555445D02*
Y554331D01*
G01X64760Y495188D02*
Y496369D01*
G01X64492Y495122D02*
Y496434D01*
G01X63688Y493153D02*
Y493547D01*
G01Y494466D02*
Y494859D01*
G01Y496697D02*
Y497090D01*
G01X60197Y556300D02*
Y555315D01*
G01X59704D02*
Y554331D01*
G01X59055D02*
Y559587D01*
G01X58267D02*
Y554331D01*
G01X52756D02*
Y559587D01*
G01X52657Y557874D02*
Y554331D01*
G01X50393D02*
Y559587D01*
G01X49606D02*
Y554331D01*
G01X44291Y559587D02*
Y554331D01*
G01X43996Y557874D02*
Y554331D01*
G01X43307Y622835D02*
Y554331D01*
G01X39390Y553052D02*
Y567717D01*
G01X34764Y553052D02*
Y554036D01*
G01X33582D02*
Y553052D01*
G01X33477Y554036D02*
Y553052D01*
G01X33182D02*
Y554036D01*
G01X31818D02*
Y553052D01*
G01X31523D02*
Y554036D01*
G01X31496Y510433D02*
Y544685D01*
G01X31417Y554036D02*
Y553052D01*
G01X30236Y554036D02*
Y553052D01*
G01X23622Y521496D02*
X25590Y519134D01*
G01X66369Y493941D02*
X66838Y493547D01*
G01X66302D02*
X65833Y493941D01*
G01X27266Y517953D02*
X27559Y517707D01*
G01X27224D02*
X26931Y517953D01*
G01X63688Y497090D02*
X66838Y496040D01*
G01X64760Y496369D02*
X66570Y495778D01*
G01X64492Y496434D02*
X63688Y496697D01*
G01X65689Y555315D02*
X60807Y556260D01*
G01X65595Y554331D02*
X60620Y555294D01*
G01X28366Y554036D02*
X18226Y554567D01*
G01X28340Y553052D02*
X18175Y553584D01*
G01X15667Y556118D02*
X15130D01*
G01X67283Y555315D02*
X67382D01*
G01X43307D02*
X67283D01*
G01X43307Y554331D02*
X88582D01*
G01X39390Y554036D02*
X39467D01*
G01X25590Y525985D02*
X23622Y522441D01*
G01X29350Y553052D02*
Y554036D01*
G01X28366D02*
Y553052D01*
G01X27559Y538544D02*
Y540748D01*
G01Y514370D02*
Y516575D01*
G01Y517707D02*
Y517461D01*
G01Y526575D02*
Y518544D01*
G01Y536575D02*
Y528544D01*
G01X27165Y518544D02*
Y516575D01*
G01Y528544D02*
Y526575D01*
G01Y538544D02*
Y536575D01*
G01X26417Y518544D02*
Y516575D01*
G01Y528544D02*
Y526575D01*
G01Y538544D02*
Y536575D01*
G01X25590Y517461D02*
Y517707D01*
G01X25197Y526575D02*
Y528544D01*
G01Y519607D02*
Y515985D01*
G01Y518544D02*
Y516575D01*
G01Y529843D02*
Y525276D01*
G01Y538544D02*
Y536575D01*
G01Y539134D02*
Y535591D01*
G01X23622Y539134D02*
Y515985D01*
G01X22441Y534572D02*
Y521391D01*
G01X20984Y553052D02*
Y554036D01*
G01X19803D02*
Y553052D01*
G01X19697Y554036D02*
Y553052D01*
G01X19402D02*
Y554036D01*
G01X18038D02*
Y553052D01*
G01X17743D02*
Y554036D01*
G01X17638D02*
Y553052D01*
G01X16456Y554036D02*
Y553052D01*
G01X15667Y558533D02*
Y556118D01*
G01X15130D02*
Y561386D01*
G01X12401Y524252D02*
Y519134D01*
G01X12170Y535985D02*
Y532638D01*
G01X10177Y554036D02*
Y553052D01*
G01X9173D02*
Y554036D01*
G01X7992D02*
Y553052D01*
G01X7886Y554036D02*
Y553052D01*
G01X7815Y554036D02*
Y553052D01*
G01X35433Y540040D02*
X200787D01*
G01X23622Y539134D02*
X27559D01*
G01X9015Y538544D02*
X27165D01*
G01X27559D02*
X25197D01*
G01X12761Y536575D02*
X27165D01*
G01X27559D02*
X25197D01*
G01X27559Y535985D02*
X25590D01*
G01X12170Y532638D02*
X11383D01*
G01X27559Y529134D02*
X25590D01*
G01X27559Y528544D02*
X25197D01*
G01X27559Y526575D02*
X25197D01*
G01X27559Y525985D02*
X25590D01*
G01X27559Y519134D02*
X25590D01*
G01X12992Y518544D02*
X27165D01*
G01X27559D02*
X25197D01*
G01X26931Y517953D02*
X27266D01*
G01X25590Y517707D02*
X27224D01*
G01X27559Y517461D02*
X25590D01*
G01X27165Y516575D02*
X8937D01*
G01X27559D02*
X25197D01*
G01X23622Y515985D02*
X27559D01*
G01X171264Y498746D02*
X64964D01*
G01X65833Y493941D02*
X66369D01*
G01X63688Y493547D02*
X66302D01*
G01X66838Y493153D02*
X63688D01*
G01X66570Y495778D02*
X64760Y495188D01*
G01X63688Y494859D02*
X64492Y495122D01*
G01X66838Y495516D02*
X63688Y494466D01*
G01X11383Y532638D02*
X8071Y530276D01*
G01X25590Y535985D02*
X23622Y534016D01*
G01X43307Y554784D02*
X46004Y557481D01*
G01X44291Y556300D02*
X43307Y555315D01*
G01X43182Y554231D02*
X39928Y553152D01*
G01X43174Y555265D02*
X39467Y554036D01*
G01X14484Y555505D02*
X11865Y553931D01*
G01X13977Y556348D02*
X11358Y554775D01*
G01X53691Y618120D02*
X53754Y618366D01*
G01X53628Y617858D02*
X53691Y618120D01*
G01X53565Y617579D02*
X53628Y617858D01*
G01X55758Y559046D02*
X55695Y558800D01*
G01X55821Y559308D02*
X55758Y559046D01*
G01X55884Y559587D02*
X55821Y559308D01*
G01X53627Y559314D02*
X53565Y559587D01*
G01X53689Y559052D02*
X53627Y559314D01*
G01X53754Y558800D02*
X53689Y559052D01*
G01X55822Y617852D02*
X55884Y617579D01*
G01X55759Y618114D02*
X55822Y617852D01*
G01X55695Y618366D02*
X55759Y618114D01*
G01X51476Y618111D02*
G03X52657Y619292I0J1181D01*
G01X55695Y618366D02*
G03X53754I-971J1713D01*
G01X55884Y617579D02*
G03X53565I-1160J2500D01*
G01X57795Y620079D02*
G03I-3071J0D01*
G01X43174Y621901D02*
G03X43484Y621851I310J934D01*
G01X43996Y619292D02*
G03X45177Y618111I1181J0D01*
G01X43182Y622935D02*
G03X43802Y622835I619J1869D01*
G01X45177Y559055D02*
G03X43996Y557874I0J-1181D01*
G01X52657D02*
G03X51476Y559055I-1181J0D01*
G01X34468Y609449D02*
G03Y607481I0J-984D01*
G01X33779Y623622D02*
G03I-1575J0D01*
G01X39928Y624015D02*
G03X39390Y624113I-618J-1869D01*
G01X8878Y602776D02*
G03X8090Y603563I-787J0D01*
G01X14484Y621661D02*
G03X15687Y621809I507J844D01*
G01X18226Y622599D02*
G03X17582Y622312I52J-983D01*
G01X20000Y623622D02*
G03I-1575J0D01*
G01X12126D02*
G03I-1575J0D01*
G01X17736Y606300D02*
G03X13799I-1969J0D01*
G01X18175Y623582D02*
G03X16886Y623008I103J-1966D01*
G01X13977Y620817D02*
G03X16383Y621113I1014J1688D01*
G01X18588Y606300D02*
G03X12947I-2820J0D01*
G01X19441D02*
G03X12094I-3673J0D01*
G01X8090Y595177D02*
G03X8878Y595965I0J788D01*
G01X8090Y573603D02*
G03X8878Y574390I1J787D01*
G01Y581201D02*
G03X8090Y581989I-788J0D01*
G01X34468Y569685D02*
G03Y567717I0J-984D01*
G01X13799Y570866D02*
G03X17736I1969J0D01*
G01X12947D02*
G03X18588I2821J0D01*
G01X12094D02*
G03X19441I3674J0D01*
G01X73449Y615059D02*
X73228Y615591D01*
G01Y612441D02*
X73449Y611910D01*
G01X73228Y609292D02*
X73449Y608760D01*
G01X73228Y606142D02*
X73449Y605611D01*
G01X73228Y602992D02*
X73449Y602461D01*
G01X73228Y599843D02*
X73449Y599311D01*
G01X73228Y596693D02*
X73449Y596162D01*
G01X73228Y593544D02*
X73449Y593012D01*
G01X73228Y590394D02*
X73449Y589863D01*
G01X73228Y587244D02*
X73449Y586713D01*
G01X73228Y584095D02*
X73449Y583563D01*
G01X73228Y580945D02*
X73449Y580414D01*
G01X73228Y577796D02*
X73449Y577264D01*
G01X73228Y574646D02*
X73449Y574115D01*
G01X73228Y571496D02*
X73449Y570965D01*
G01X77165Y615256D02*
X76771Y615650D01*
G01X76063Y614075D02*
X76594Y613544D01*
G01X77165Y612107D02*
X76771Y612500D01*
G01X72441Y615591D02*
X72972Y615059D01*
G01X76063Y610926D02*
X76594Y610394D01*
G01X72693Y614285D02*
X72795Y614183D01*
G01X77165Y608957D02*
X76771Y609351D01*
G01X72441Y612441D02*
X72972Y611910D01*
G01X69921Y614952D02*
X70024Y614849D01*
G01X76063Y607776D02*
X76594Y607244D01*
G01X72693Y611135D02*
X72795Y611033D01*
G01X77165Y605807D02*
X76771Y606201D01*
G01X72441Y609292D02*
X72972Y608760D01*
G01X69921Y611802D02*
X70024Y611700D01*
G01X76063Y604626D02*
X76594Y604095D01*
G01X72693Y607986D02*
X72795Y607883D01*
G01X77165Y602658D02*
X76771Y603052D01*
G01X72441Y606142D02*
X72972Y605611D01*
G01X69921Y608653D02*
X70024Y608550D01*
G01X76063Y601477D02*
X76594Y600945D01*
G01X72693Y604836D02*
X72795Y604734D01*
G01X77165Y599508D02*
X76771Y599902D01*
G01X72441Y602992D02*
X72972Y602461D01*
G01X69921Y605503D02*
X70024Y605400D01*
G01X76063Y598327D02*
X76594Y597796D01*
G01X72693Y601687D02*
X72795Y601584D01*
G01X77165Y596359D02*
X76771Y596752D01*
G01X72441Y599843D02*
X72972Y599311D01*
G01X69921Y602353D02*
X70024Y602251D01*
G01X76063Y595177D02*
X76594Y594646D01*
G01X72693Y598537D02*
X72795Y598435D01*
G01X77165Y593209D02*
X76771Y593603D01*
G01X72441Y596693D02*
X72972Y596162D01*
G01X69921Y599204D02*
X70024Y599101D01*
G01X76063Y592028D02*
X76594Y591496D01*
G01X72693Y595387D02*
X72795Y595285D01*
G01X77165Y590059D02*
X76771Y590453D01*
G01X72441Y593544D02*
X72972Y593012D01*
G01X69921Y596054D02*
X70024Y595952D01*
G01X46004Y619685D02*
X43307Y622382D01*
G01Y621851D02*
X44291Y620866D01*
G01X76063Y588878D02*
X76594Y588347D01*
G01X72693Y592238D02*
X72795Y592135D01*
G01X77165Y586910D02*
X76771Y587303D01*
G01X48031Y615059D02*
X47500Y615591D01*
G01X72441Y590394D02*
X72972Y589863D01*
G01X69921Y592905D02*
X70024Y592802D01*
G01X76063Y585729D02*
X76594Y585197D01*
G01X72693Y589088D02*
X72795Y588986D01*
G01X77165Y583760D02*
X76771Y584154D01*
G01X48031Y611910D02*
X47500Y612441D01*
G01X72441Y587244D02*
X72972Y586713D01*
G01X69921Y589755D02*
X70024Y589652D01*
G01X76063Y582579D02*
X76594Y582048D01*
G01X72693Y585939D02*
X72795Y585836D01*
G01X77165Y580611D02*
X76771Y581004D01*
G01X48031Y608760D02*
X47500Y609292D01*
G01X72441Y584095D02*
X72972Y583563D01*
G01X69921Y586605D02*
X70024Y586503D01*
G01X76063Y579429D02*
X76594Y578898D01*
G01X72693Y582789D02*
X72795Y582687D01*
G01X77165Y577461D02*
X76771Y577855D01*
G01X48031Y605611D02*
X47500Y606142D01*
G01X72441Y580945D02*
X72972Y580414D01*
G01X69921Y583456D02*
X70024Y583353D01*
G01X76063Y576280D02*
X76594Y575748D01*
G01X72693Y579639D02*
X72795Y579537D01*
G01X23296Y559630D02*
X23404Y558972D01*
G01X60620Y621872D02*
X60807Y620906D01*
G01X30495Y560508D02*
X30603Y559959D01*
G01X29958Y560508D02*
X30065Y559959D01*
G01X22329Y560618D02*
X22437Y560069D01*
G01X34793Y560289D02*
X34901Y559850D01*
G01X34256Y560289D02*
X34364Y559850D01*
G01X32000Y559411D02*
X32107Y558972D01*
G01X26627Y560508D02*
X26735Y560069D01*
G01X21792Y560508D02*
X21899Y560069D01*
G01X18461Y560508D02*
X18569Y560069D01*
G01X31462Y559411D02*
X31677Y558642D01*
G01X34686Y560618D02*
X34793Y560289D01*
G01X30388Y560837D02*
X30495Y560508D01*
G01X23834Y559411D02*
X23941Y559081D01*
G01X17924Y560289D02*
X18031Y559959D01*
G01X8361Y559191D02*
X8791Y557874D01*
G01X7716Y563032D02*
X9436Y557874D01*
G01X14056Y561057D02*
X14271Y560508D01*
G01X73228Y568347D02*
X73449Y567815D01*
G01X73228Y565197D02*
X73449Y564666D01*
G01X73228Y562048D02*
X73449Y561516D01*
G01X23941Y559081D02*
X24049Y558862D01*
G01X23404Y558972D02*
X23619Y558533D01*
G01X22222Y560837D02*
X22329Y560618D01*
G01X18354Y560727D02*
X18461Y560508D01*
G01X15667Y558533D02*
X15775Y558313D01*
G01X13626Y560727D02*
X13734Y560508D01*
G01X11907Y560727D02*
X12014Y560508D01*
G01X34471Y560947D02*
X34686Y560618D01*
G01X34041D02*
X34256Y560289D01*
G01X32107Y558972D02*
X32322Y558642D01*
G01X31677D02*
X31892Y558313D01*
G01X25982Y560618D02*
X26197Y560289D01*
G01X17709Y560618D02*
X17924Y560289D01*
G01X15667Y559081D02*
X15882Y558752D01*
G01X26305Y560947D02*
X26627Y560508D01*
G01X34471Y560947D02*
X34256Y561166D01*
G01X34041Y560618D02*
X33826Y560837D01*
G01X30388D02*
X30173Y561057D01*
G01X32537Y558423D02*
X32322Y558642D01*
G01X29958Y560508D02*
X29743Y560727D01*
G01X32107Y558094D02*
X31892Y558313D01*
G01X22222Y560837D02*
X22007Y561057D01*
G01X24371Y558533D02*
X24049Y558862D01*
G01X21792Y560508D02*
X21577Y560727D01*
G01X23834Y558313D02*
X23619Y558533D01*
G01X18354Y560727D02*
X18031Y561057D01*
G01X14056D02*
X13841Y561276D01*
G01X13626Y560727D02*
X13519Y560837D01*
G01X15990Y558094D02*
X15775Y558313D01*
G01X12444Y560947D02*
X12122Y561276D01*
G01X11907Y560727D02*
X11799Y560837D01*
G01X77165Y574311D02*
X76771Y574705D01*
G01X48031Y602461D02*
X47500Y602992D01*
G01X72441Y577796D02*
X72972Y577264D01*
G01X69921Y580306D02*
X70024Y580203D01*
G01X76063Y573130D02*
X76594Y572599D01*
G01X72693Y576490D02*
X72795Y576387D01*
G01X77165Y571162D02*
X76771Y571555D01*
G01X48031Y599311D02*
X47500Y599843D01*
G01X72441Y574646D02*
X72972Y574115D01*
G01X69921Y577157D02*
X70024Y577054D01*
G01X76063Y569981D02*
X76594Y569449D01*
G01X72693Y573340D02*
X72795Y573238D01*
G01X77165Y568012D02*
X76771Y568406D01*
G01X48031Y596162D02*
X47500Y596693D01*
G01X72441Y571496D02*
X72972Y570965D01*
G01X69921Y574007D02*
X70024Y573904D01*
G01X76063Y566831D02*
X76594Y566300D01*
G01X72693Y570190D02*
X72795Y570088D01*
G01X77165Y564863D02*
X76771Y565256D01*
G01X48031Y593012D02*
X47500Y593544D01*
G01X72441Y568347D02*
X72972Y567815D01*
G01X69921Y570857D02*
X70024Y570755D01*
G01X76063Y563681D02*
X76594Y563150D01*
G01X72693Y567041D02*
X72795Y566939D01*
G01X77165Y561713D02*
X76771Y562107D01*
G01X48031Y589863D02*
X47500Y590394D01*
G01X72441Y565197D02*
X72972Y564666D01*
G01X69921Y567708D02*
X70024Y567605D01*
G01X76063Y560532D02*
X76594Y560000D01*
G01X72693Y563891D02*
X72795Y563789D01*
G01X48031Y586713D02*
X47500Y587244D01*
G01X72441Y562048D02*
X72972Y561516D01*
G01X69921Y564558D02*
X70024Y564455D01*
G01X72693Y560742D02*
X72795Y560639D01*
G01X48031Y583563D02*
X47500Y584095D01*
G01X69921Y561409D02*
X70024Y561306D01*
G01X48031Y580414D02*
X47500Y580945D01*
G01X48031Y577264D02*
X47500Y577796D01*
G01X48031Y574115D02*
X47500Y574646D01*
G01X48031Y570965D02*
X47500Y571496D01*
G01X48031Y567815D02*
X47500Y568347D01*
G01X48031Y564666D02*
X47500Y565197D01*
G01X48031Y561516D02*
X47500Y562048D01*
G01X30173Y561057D02*
X29851Y561276D01*
G01X25982Y560618D02*
X25660Y560837D01*
G01X22007Y561057D02*
X21685Y561276D01*
G01X24156Y558094D02*
X23834Y558313D01*
G01X18031Y561057D02*
X17709Y561276D01*
G01X16205Y558533D02*
X15882Y558752D01*
G01X26305Y560947D02*
X25767Y561276D01*
G01X14484Y621661D02*
X11865Y623235D01*
G01X13977Y620817D02*
X11358Y622391D01*
G01X34256Y561166D02*
X34041Y561276D01*
G01X29743Y560727D02*
X29528Y560837D01*
G01X32322Y557984D02*
X32107Y558094D01*
G01X21577Y560727D02*
X21362Y560837D01*
G01X24586Y558423D02*
X24371Y558533D01*
G01X17709Y560618D02*
X17279Y560837D01*
G01X43182Y622935D02*
X39928Y624015D01*
G01X43174Y621901D02*
X39467Y623130D01*
G01X49109Y615945D02*
X49843Y615748D01*
G01X49109Y612796D02*
X49843Y612599D01*
G01X49109Y609646D02*
X49843Y609449D01*
G01X49109Y606496D02*
X49843Y606300D01*
G01X49109Y603347D02*
X49843Y603150D01*
G01X49109Y600197D02*
X49843Y600000D01*
G01X49109Y597048D02*
X49843Y596851D01*
G01X49109Y593898D02*
X49843Y593701D01*
G01X49109Y590748D02*
X49843Y590552D01*
G01X49109Y587599D02*
X49843Y587402D01*
G01X49109Y584449D02*
X49843Y584252D01*
G01X49109Y581300D02*
X49843Y581103D01*
G01X49109Y578150D02*
X49843Y577953D01*
G01X49109Y575000D02*
X49843Y574803D01*
G01X49109Y571851D02*
X49843Y571654D01*
G01X55217Y615893D02*
X55193Y615898D01*
G01X55217Y612744D02*
X55193Y612749D01*
G01X55217Y609594D02*
X55193Y609599D01*
G01X55217Y606444D02*
X55193Y606450D01*
G01X55217Y603295D02*
X55193Y603300D01*
G01X55217Y600145D02*
X55193Y600150D01*
G01X55217Y596996D02*
X55193Y597001D01*
G01X55217Y593846D02*
X55193Y593851D01*
G01X55217Y590696D02*
X55193Y590702D01*
G01X55217Y587547D02*
X55193Y587552D01*
G01X55217Y584397D02*
X55193Y584402D01*
G01X55217Y581248D02*
X55193Y581253D01*
G01X55217Y578098D02*
X55193Y578103D01*
G01X55658Y614279D02*
X56175Y614174D01*
G01X55658Y611129D02*
X56175Y611024D01*
G01X55658Y607980D02*
X56175Y607874D01*
G01X55658Y604830D02*
X56175Y604725D01*
G01X55658Y601681D02*
X56175Y601575D01*
G01X55658Y598531D02*
X56175Y598426D01*
G01X55658Y595381D02*
X56175Y595276D01*
G01X55658Y592232D02*
X56175Y592126D01*
G01X55658Y589082D02*
X56175Y588977D01*
G01X55658Y585933D02*
X56175Y585827D01*
G01X55658Y582783D02*
X56175Y582677D01*
G01X55658Y579633D02*
X56175Y579528D01*
G01X53864Y614846D02*
X53270Y614961D01*
G01X53864Y611697D02*
X53270Y611811D01*
G01X53864Y608547D02*
X53270Y608662D01*
G01X53864Y605398D02*
X53270Y605512D01*
G01X53864Y602248D02*
X53270Y602363D01*
G01X53864Y599098D02*
X53270Y599213D01*
G01X53864Y595949D02*
X53270Y596063D01*
G01X53864Y592799D02*
X53270Y592914D01*
G01X53864Y589650D02*
X53270Y589764D01*
G01X53864Y586500D02*
X53270Y586615D01*
G01X53864Y583350D02*
X53270Y583465D01*
G01X53864Y580201D02*
X53270Y580315D01*
G01X53420Y616536D02*
X54319Y616375D01*
G01X53420Y613386D02*
X54319Y613225D01*
G01X53420Y610237D02*
X54319Y610076D01*
G01X53420Y607087D02*
X54319Y606926D01*
G01X53420Y603937D02*
X54319Y603776D01*
G01X53420Y600788D02*
X54319Y600627D01*
G01X53420Y597638D02*
X54319Y597477D01*
G01X53420Y594489D02*
X54319Y594327D01*
G01X53420Y591339D02*
X54319Y591178D01*
G01X53420Y588189D02*
X54319Y588028D01*
G01X53420Y585040D02*
X54319Y584879D01*
G01X56573Y615748D02*
X55417Y615863D01*
G01X56573Y612599D02*
X55417Y612713D01*
G01X56573Y609449D02*
X55417Y609564D01*
G01X56573Y606300D02*
X55417Y606414D01*
G01X56573Y603150D02*
X55417Y603265D01*
G01X56573Y600000D02*
X55417Y600115D01*
G01X56573Y596851D02*
X55417Y596965D01*
G01X39390Y623130D02*
X39467D01*
G01X43307Y622835D02*
X88582D01*
G01X67283Y621851D02*
X67382D01*
G01X43307D02*
X67283D01*
G01X60197Y620866D02*
X77165D01*
G01X43996D02*
X44291D01*
G01D02*
X52756D01*
G01X67401Y619685D02*
X46004D01*
G01X53754Y618366D02*
X55695D01*
G01X51476Y618111D02*
X45177D01*
G01X43307Y617579D02*
X59055D01*
G01X77165Y616929D02*
X75197D01*
G01X76909Y616772D02*
X43307D01*
G01X76771Y616634D02*
X67401D01*
G01X49843Y616536D02*
X87126D01*
G01X49843Y615748D02*
X87126D01*
G01X76771Y615650D02*
X67401D01*
G01X76594Y615591D02*
X47500D01*
G01X76909Y615512D02*
X43307D01*
G01X46063Y615355D02*
X43307D01*
G01X77165D02*
X75197D01*
G01X51771Y615059D02*
X48031D01*
G01X76063D02*
X57677D01*
G01X49325Y614961D02*
X77480D01*
G01X70280Y614764D02*
X72437D01*
G01Y614370D02*
X70280D01*
G01X77480Y614174D02*
X49325D01*
G01X57677Y614075D02*
X76063D01*
G01X48031D02*
X51771D01*
G01X46063Y613780D02*
X43307D01*
G01X77165D02*
X75197D01*
G01X76909Y613622D02*
X43307D01*
G01X47500Y613544D02*
X76594D01*
G01X76771Y613485D02*
X67401D01*
G01X49843Y613386D02*
X87126D01*
G01X49843Y612599D02*
X87126D01*
G01X76771Y612500D02*
X67401D01*
G01X76594Y612441D02*
X47500D01*
G01X76909Y612363D02*
X43307D01*
G01X46063Y612205D02*
X43307D01*
G01X77165D02*
X75197D01*
G01X51771Y611910D02*
X48031D01*
G01X76063D02*
X57677D01*
G01X49325Y611811D02*
X77480D01*
G01X70280Y611615D02*
X72437D01*
G01Y611221D02*
X70280D01*
G01X49325Y611024D02*
X77480D01*
G01X57677Y610926D02*
X76063D01*
G01X48031D02*
X51771D01*
G01X46063Y610630D02*
X43307D01*
G01X77165D02*
X75197D01*
G01X28340Y624115D02*
X18175Y623582D01*
G01X28366Y623130D02*
X18226Y622599D01*
G01X49117Y600195D02*
X49118Y600593D01*
G01X49117Y603344D02*
X49118Y603743D01*
G01X49117Y612793D02*
X49118Y613192D01*
G01X49117Y615943D02*
X49118Y616341D01*
G01X49117Y562400D02*
X49118Y562798D01*
G01X49117Y565549D02*
X49118Y565948D01*
G01X49117Y568699D02*
X49118Y569097D01*
G01X49117Y571848D02*
X49118Y572247D01*
G01X49117Y574998D02*
X49118Y575396D01*
G01X49117Y578148D02*
X49118Y578546D01*
G01X49117Y581297D02*
X49118Y581696D01*
G01X49117Y584447D02*
X49118Y584845D01*
G01X49117Y587596D02*
X49118Y587995D01*
G01X49117Y590746D02*
X49118Y591144D01*
G01X49117Y593896D02*
X49118Y594294D01*
G01X49117Y597045D02*
X49118Y597444D01*
G01X49117Y606494D02*
X49118Y606892D01*
G01X49117Y609644D02*
X49118Y610042D01*
G01X77756Y562992D02*
Y562205D01*
G01Y566142D02*
Y565355D01*
G01Y572441D02*
Y571654D01*
G01Y569292D02*
Y568504D01*
G01Y575591D02*
Y574803D01*
G01Y581890D02*
Y581103D01*
G01Y578740D02*
Y577953D01*
G01Y585040D02*
Y584252D01*
G01Y591339D02*
Y590552D01*
G01Y588189D02*
Y587402D01*
G01Y594489D02*
Y593701D01*
G01Y600788D02*
Y600000D01*
G01Y597638D02*
Y596851D01*
G01Y603937D02*
Y603150D01*
G01Y610237D02*
Y609449D01*
G01Y607087D02*
Y606300D01*
G01Y613386D02*
Y612599D01*
G01Y616536D02*
Y615748D01*
G01X77480Y614174D02*
Y614961D01*
G01Y611024D02*
Y611811D01*
G01Y607874D02*
Y608662D01*
G01Y604725D02*
Y605512D01*
G01Y601575D02*
Y602363D01*
G01Y598426D02*
Y599213D01*
G01Y595276D02*
Y596063D01*
G01Y592126D02*
Y592914D01*
G01Y588977D02*
Y589764D01*
G01Y585827D02*
Y586615D01*
G01Y582677D02*
Y583465D01*
G01Y579528D02*
Y580315D01*
G01Y576378D02*
Y577166D01*
G01Y573229D02*
Y574016D01*
G01Y570079D02*
Y570866D01*
G01Y566929D02*
Y567717D01*
G01Y563780D02*
Y564567D01*
G01Y560630D02*
Y561418D01*
G01X76890Y614174D02*
Y614961D01*
G01Y611024D02*
Y611811D01*
G01Y607874D02*
Y608662D01*
G01Y604725D02*
Y605512D01*
G01Y601575D02*
Y602363D01*
G01Y598426D02*
Y599213D01*
G01Y595276D02*
Y596063D01*
G01Y592126D02*
Y592914D01*
G01Y588977D02*
Y589764D01*
G01Y585827D02*
Y586615D01*
G01Y582677D02*
Y583465D01*
G01Y579528D02*
Y580315D01*
G01Y576378D02*
Y577166D01*
G01Y573229D02*
Y574016D01*
G01Y570079D02*
Y570866D01*
G01Y566929D02*
Y567717D01*
G01Y563780D02*
Y564567D01*
G01Y560630D02*
Y561418D01*
G01X76771Y563091D02*
Y562107D01*
G01Y566240D02*
Y565256D01*
G01Y572540D02*
Y571555D01*
G01Y569390D02*
Y568406D01*
G01Y575689D02*
Y574705D01*
G01Y581989D02*
Y581004D01*
G01Y578839D02*
Y577855D01*
G01Y585138D02*
Y584154D01*
G01Y591437D02*
Y590453D01*
G01Y588288D02*
Y587303D01*
G01Y594587D02*
Y593603D01*
G01Y600886D02*
Y599902D01*
G01Y597737D02*
Y596752D01*
G01Y604036D02*
Y603052D01*
G01Y610335D02*
Y609351D01*
G01Y607185D02*
Y606201D01*
G01Y613485D02*
Y612500D01*
G01Y616634D02*
Y615650D01*
G01X76594Y613544D02*
Y615591D01*
G01Y610394D02*
Y612441D01*
G01Y607244D02*
Y609292D01*
G01Y604095D02*
Y606142D01*
G01Y600945D02*
Y602992D01*
G01Y597796D02*
Y599843D01*
G01Y594646D02*
Y596693D01*
G01Y591496D02*
Y593544D01*
G01Y588347D02*
Y590394D01*
G01Y585197D02*
Y587244D01*
G01Y582048D02*
Y584095D01*
G01Y578898D02*
Y580945D01*
G01Y575748D02*
Y577796D01*
G01Y572599D02*
Y574646D01*
G01Y569449D02*
Y571496D01*
G01Y566300D02*
Y568347D01*
G01Y563150D02*
Y565197D01*
G01Y560000D02*
Y562048D01*
G01X76575Y615748D02*
Y616536D01*
G01Y612599D02*
Y613386D01*
G01Y609449D02*
Y610237D01*
G01Y606300D02*
Y607087D01*
G01Y603150D02*
Y603937D01*
G01Y600000D02*
Y600788D01*
G01Y596851D02*
Y597638D01*
G01Y593701D02*
Y594489D01*
G01Y590552D02*
Y591339D01*
G01Y587402D02*
Y588189D01*
G01Y584252D02*
Y585040D01*
G01Y581103D02*
Y581890D01*
G01Y577953D02*
Y578740D01*
G01Y574803D02*
Y575591D01*
G01Y571654D02*
Y572441D01*
G01Y568504D02*
Y569292D01*
G01Y565355D02*
Y566142D01*
G01Y562205D02*
Y562992D01*
G01X76063Y561516D02*
Y560532D01*
G01Y567815D02*
Y566831D01*
G01Y564666D02*
Y563681D01*
G01Y570965D02*
Y569981D01*
G01Y577264D02*
Y576280D01*
G01Y574115D02*
Y573130D01*
G01Y580414D02*
Y579429D01*
G01Y586713D02*
Y585729D01*
G01Y583563D02*
Y582579D01*
G01Y589863D02*
Y588878D01*
G01Y596162D02*
Y595177D01*
G01Y593012D02*
Y592028D01*
G01Y599311D02*
Y598327D01*
G01Y605611D02*
Y604626D01*
G01Y602461D02*
Y601477D01*
G01Y608760D02*
Y607776D01*
G01Y615059D02*
Y614075D01*
G01Y611910D02*
Y610926D01*
G01X75984Y614174D02*
Y614961D01*
G01Y611024D02*
Y611811D01*
G01Y607874D02*
Y608662D01*
G01Y604725D02*
Y605512D01*
G01Y601575D02*
Y602363D01*
G01Y598426D02*
Y599213D01*
G01Y595276D02*
Y596063D01*
G01Y592126D02*
Y592914D01*
G01Y588977D02*
Y589764D01*
G01Y585827D02*
Y586615D01*
G01Y582677D02*
Y583465D01*
G01Y579528D02*
Y580315D01*
G01Y576378D02*
Y577166D01*
G01Y573229D02*
Y574016D01*
G01Y570079D02*
Y570866D01*
G01Y566929D02*
Y567717D01*
G01Y563780D02*
Y564567D01*
G01Y560630D02*
Y561418D01*
G01X75787Y562992D02*
Y562205D01*
G01Y566142D02*
Y565355D01*
G01Y572441D02*
Y571654D01*
G01Y569292D02*
Y568504D01*
G01Y575591D02*
Y574803D01*
G01Y581890D02*
Y581103D01*
G01Y578740D02*
Y577953D01*
G01Y585040D02*
Y584252D01*
G01Y591339D02*
Y590552D01*
G01Y588189D02*
Y587402D01*
G01Y594489D02*
Y593701D01*
G01Y600788D02*
Y600000D01*
G01Y597638D02*
Y596851D01*
G01Y603937D02*
Y603150D01*
G01Y610237D02*
Y609449D01*
G01Y607087D02*
Y606300D01*
G01Y613386D02*
Y612599D01*
G01Y616536D02*
Y615748D01*
G01X75748Y561418D02*
Y560630D01*
G01Y567717D02*
Y566929D01*
G01Y564567D02*
Y563780D01*
G01Y570866D02*
Y570079D01*
G01Y577166D02*
Y576378D01*
G01Y574016D02*
Y573229D01*
G01Y580315D02*
Y579528D01*
G01Y586615D02*
Y585827D01*
G01Y583465D02*
Y582677D01*
G01Y589764D02*
Y588977D01*
G01Y596063D02*
Y595276D01*
G01Y592914D02*
Y592126D01*
G01Y599213D02*
Y598426D01*
G01Y605512D02*
Y604725D01*
G01Y602363D02*
Y601575D01*
G01Y608662D02*
Y607874D01*
G01Y614961D02*
Y614174D01*
G01Y611811D02*
Y611024D01*
G01X75669Y615748D02*
Y616536D01*
G01Y612599D02*
Y613386D01*
G01Y609449D02*
Y610237D01*
G01Y606300D02*
Y607087D01*
G01Y603150D02*
Y603937D01*
G01Y600000D02*
Y600788D01*
G01Y596851D02*
Y597638D01*
G01Y593701D02*
Y594489D01*
G01Y590552D02*
Y591339D01*
G01Y587402D02*
Y588189D01*
G01Y584252D02*
Y585040D01*
G01Y581103D02*
Y581890D01*
G01Y577953D02*
Y578740D01*
G01Y574803D02*
Y575591D01*
G01Y571654D02*
Y572441D01*
G01Y568504D02*
Y569292D01*
G01Y565355D02*
Y566142D01*
G01Y562205D02*
Y562992D01*
G01X75571Y614174D02*
Y614961D01*
G01Y611024D02*
Y611811D01*
G01Y607874D02*
Y608662D01*
G01Y604725D02*
Y605512D01*
G01Y601575D02*
Y602363D01*
G01Y598426D02*
Y599213D01*
G01Y595276D02*
Y596063D01*
G01Y592126D02*
Y592914D01*
G01Y588977D02*
Y589764D01*
G01Y585827D02*
Y586615D01*
G01Y582677D02*
Y583465D01*
G01Y579528D02*
Y580315D01*
G01Y576378D02*
Y577166D01*
G01Y573229D02*
Y574016D01*
G01Y570079D02*
Y570866D01*
G01Y566929D02*
Y567717D01*
G01Y563780D02*
Y564567D01*
G01Y560630D02*
Y561418D01*
G01X75197Y614174D02*
Y614961D01*
G01Y611024D02*
Y611811D01*
G01Y607874D02*
Y608662D01*
G01Y604725D02*
Y605512D01*
G01Y601575D02*
Y602363D01*
G01Y598426D02*
Y599213D01*
G01Y595276D02*
Y596063D01*
G01Y592126D02*
Y592914D01*
G01Y588977D02*
Y589764D01*
G01Y585827D02*
Y586615D01*
G01Y582677D02*
Y583465D01*
G01Y579528D02*
Y580315D01*
G01Y576378D02*
Y577166D01*
G01Y573229D02*
Y574016D01*
G01Y570079D02*
Y570866D01*
G01Y566929D02*
Y567717D01*
G01Y563780D02*
Y564567D01*
G01Y560630D02*
Y561418D01*
G01Y563386D02*
Y561811D01*
G01Y566536D02*
Y564961D01*
G01Y569685D02*
Y568111D01*
G01Y572835D02*
Y571260D01*
G01Y575985D02*
Y574410D01*
G01Y579134D02*
Y577559D01*
G01Y582284D02*
Y580709D01*
G01Y585433D02*
Y583859D01*
G01Y588583D02*
Y587008D01*
G01Y591733D02*
Y590158D01*
G01Y594882D02*
Y593307D01*
G01Y598032D02*
Y596457D01*
G01Y601181D02*
Y599607D01*
G01Y604331D02*
Y602756D01*
G01Y607481D02*
Y605906D01*
G01Y610630D02*
Y609055D01*
G01Y613780D02*
Y612205D01*
G01Y616929D02*
Y615355D01*
G01X75157Y561418D02*
Y560630D01*
G01Y567717D02*
Y566929D01*
G01Y564567D02*
Y563780D01*
G01Y570866D02*
Y570079D01*
G01Y577166D02*
Y576378D01*
G01Y574016D02*
Y573229D01*
G01Y580315D02*
Y579528D01*
G01Y586615D02*
Y585827D01*
G01Y583465D02*
Y582677D01*
G01Y589764D02*
Y588977D01*
G01Y596063D02*
Y595276D01*
G01Y592914D02*
Y592126D01*
G01Y599213D02*
Y598426D01*
G01Y605512D02*
Y604725D01*
G01Y602363D02*
Y601575D01*
G01Y608662D02*
Y607874D01*
G01Y614961D02*
Y614174D01*
G01Y611811D02*
Y611024D01*
G01X74055Y561418D02*
Y560630D01*
G01Y567717D02*
Y566929D01*
G01Y564567D02*
Y563780D01*
G01Y570866D02*
Y570079D01*
G01Y577166D02*
Y576378D01*
G01Y574016D02*
Y573229D01*
G01Y580315D02*
Y579528D01*
G01Y586615D02*
Y585827D01*
G01Y583465D02*
Y582677D01*
G01Y589764D02*
Y588977D01*
G01Y596063D02*
Y595276D01*
G01Y592914D02*
Y592126D01*
G01Y599213D02*
Y598426D01*
G01Y605512D02*
Y604725D01*
G01Y602363D02*
Y601575D01*
G01Y608662D02*
Y607874D01*
G01Y614961D02*
Y614174D01*
G01Y611811D02*
Y611024D01*
G01X73819Y614174D02*
Y614961D01*
G01Y611024D02*
Y611811D01*
G01Y607874D02*
Y608662D01*
G01Y604725D02*
Y605512D01*
G01Y601575D02*
Y602363D01*
G01Y598426D02*
Y599213D01*
G01Y595276D02*
Y596063D01*
G01Y592126D02*
Y592914D01*
G01Y588977D02*
Y589764D01*
G01Y585827D02*
Y586615D01*
G01Y582677D02*
Y583465D01*
G01Y579528D02*
Y580315D01*
G01Y576378D02*
Y577166D01*
G01Y573229D02*
Y574016D01*
G01Y570079D02*
Y570866D01*
G01Y566929D02*
Y567717D01*
G01Y563780D02*
Y564567D01*
G01Y560630D02*
Y561418D01*
G01X73779Y562992D02*
Y562205D01*
G01Y566142D02*
Y565355D01*
G01Y572441D02*
Y571654D01*
G01Y569292D02*
Y568504D01*
G01Y575591D02*
Y574803D01*
G01Y581890D02*
Y581103D01*
G01Y578740D02*
Y577953D01*
G01Y585040D02*
Y584252D01*
G01Y591339D02*
Y590552D01*
G01Y588189D02*
Y587402D01*
G01Y594489D02*
Y593701D01*
G01Y600788D02*
Y600000D01*
G01Y597638D02*
Y596851D01*
G01Y603937D02*
Y603150D01*
G01Y610237D02*
Y609449D01*
G01Y607087D02*
Y606300D01*
G01Y613386D02*
Y612599D01*
G01Y616536D02*
Y615748D01*
G01X73740Y562992D02*
Y562205D01*
G01Y566142D02*
Y565355D01*
G01Y572441D02*
Y571654D01*
G01Y569292D02*
Y568504D01*
G01Y575591D02*
Y574803D01*
G01Y581890D02*
Y581103D01*
G01Y578740D02*
Y577953D01*
G01Y585040D02*
Y584252D01*
G01Y591339D02*
Y590552D01*
G01Y588189D02*
Y587402D01*
G01Y594489D02*
Y593701D01*
G01Y600788D02*
Y600000D01*
G01Y597638D02*
Y596851D01*
G01Y603937D02*
Y603150D01*
G01Y610237D02*
Y609449D01*
G01Y607087D02*
Y606300D01*
G01Y613386D02*
Y612599D01*
G01Y616536D02*
Y615748D01*
G01X73641Y614174D02*
Y614961D01*
G01Y611024D02*
Y611811D01*
G01Y607874D02*
Y608662D01*
G01Y604725D02*
Y605512D01*
G01Y601575D02*
Y602363D01*
G01Y598426D02*
Y599213D01*
G01Y595276D02*
Y596063D01*
G01Y592126D02*
Y592914D01*
G01Y588977D02*
Y589764D01*
G01Y585827D02*
Y586615D01*
G01Y582677D02*
Y583465D01*
G01Y579528D02*
Y580315D01*
G01Y576378D02*
Y577166D01*
G01Y573229D02*
Y574016D01*
G01Y570079D02*
Y570866D01*
G01Y566929D02*
Y567717D01*
G01Y563780D02*
Y564567D01*
G01Y560630D02*
Y561418D01*
G01X73501Y615748D02*
Y616536D01*
G01Y612599D02*
Y613386D01*
G01Y609449D02*
Y610237D01*
G01Y606300D02*
Y607087D01*
G01Y603150D02*
Y603937D01*
G01Y600000D02*
Y600788D01*
G01Y596851D02*
Y597638D01*
G01Y593701D02*
Y594489D01*
G01Y590552D02*
Y591339D01*
G01Y587402D02*
Y588189D01*
G01Y584252D02*
Y585040D01*
G01Y581103D02*
Y581890D01*
G01Y577953D02*
Y578740D01*
G01Y574803D02*
Y575591D01*
G01Y571654D02*
Y572441D01*
G01Y568504D02*
Y569292D01*
G01Y565355D02*
Y566142D01*
G01Y562205D02*
Y562992D01*
G01X73464Y561418D02*
Y560630D01*
G01Y567717D02*
Y566929D01*
G01Y564567D02*
Y563780D01*
G01Y570866D02*
Y570079D01*
G01Y577166D02*
Y576378D01*
G01Y574016D02*
Y573229D01*
G01Y580315D02*
Y579528D01*
G01Y586615D02*
Y585827D01*
G01Y583465D02*
Y582677D01*
G01Y589764D02*
Y588977D01*
G01Y596063D02*
Y595276D01*
G01Y592914D02*
Y592126D01*
G01Y599213D02*
Y598426D01*
G01Y605512D02*
Y604725D01*
G01Y602363D02*
Y601575D01*
G01Y608662D02*
Y607874D01*
G01Y614961D02*
Y614174D01*
G01Y611811D02*
Y611024D01*
G01X73228Y615591D02*
Y622835D01*
G01Y614174D02*
Y614961D01*
G01Y611024D02*
Y611811D01*
G01Y612441D02*
Y613544D01*
G01Y607874D02*
Y608662D01*
G01Y609292D02*
Y610394D01*
G01Y606142D02*
Y607244D01*
G01Y604725D02*
Y605512D01*
G01Y601575D02*
Y602363D01*
G01Y602992D02*
Y604095D01*
G01Y598426D02*
Y599213D01*
G01Y599843D02*
Y600945D01*
G01Y596693D02*
Y597796D01*
G01Y595276D02*
Y596063D01*
G01Y592126D02*
Y592914D01*
G01Y593544D02*
Y594646D01*
G01Y588977D02*
Y589764D01*
G01Y590394D02*
Y591496D01*
G01Y587244D02*
Y588347D01*
G01Y585827D02*
Y586615D01*
G01Y582677D02*
Y583465D01*
G01Y584095D02*
Y585197D01*
G01Y579528D02*
Y580315D01*
G01Y580945D02*
Y582048D01*
G01Y577796D02*
Y578898D01*
G01Y576378D02*
Y577166D01*
G01Y573229D02*
Y574016D01*
G01Y574646D02*
Y575748D01*
G01Y570079D02*
Y570866D01*
G01Y571496D02*
Y572599D01*
G01Y568347D02*
Y569449D01*
G01Y566929D02*
Y567717D01*
G01Y563780D02*
Y564567D01*
G01Y565197D02*
Y566300D01*
G01Y560630D02*
Y561418D01*
G01Y562048D02*
Y563150D01*
G01X73208Y610926D02*
Y611910D01*
G01Y614075D02*
Y615059D01*
G01Y607776D02*
Y608760D01*
G01Y604626D02*
Y605611D01*
G01Y601477D02*
Y602461D01*
G01Y598327D02*
Y599311D01*
G01Y595177D02*
Y596162D01*
G01Y592028D02*
Y593012D01*
G01Y588878D02*
Y589863D01*
G01Y585729D02*
Y586713D01*
G01Y582579D02*
Y583563D01*
G01Y579429D02*
Y580414D01*
G01Y576280D02*
Y577264D01*
G01Y573130D02*
Y574115D01*
G01Y569981D02*
Y570965D01*
G01Y566831D02*
Y567815D01*
G01Y563681D02*
Y564666D01*
G01Y560532D02*
Y561516D01*
G01X73149Y561418D02*
Y560630D01*
G01Y567717D02*
Y566929D01*
G01Y564567D02*
Y563780D01*
G01Y570866D02*
Y570079D01*
G01Y577166D02*
Y576378D01*
G01Y574016D02*
Y573229D01*
G01Y580315D02*
Y579528D01*
G01Y586615D02*
Y585827D01*
G01Y583465D02*
Y582677D01*
G01Y589764D02*
Y588977D01*
G01Y596063D02*
Y595276D01*
G01Y592914D02*
Y592126D01*
G01Y599213D02*
Y598426D01*
G01Y605512D02*
Y604725D01*
G01Y602363D02*
Y601575D01*
G01Y608662D02*
Y607874D01*
G01Y614961D02*
Y614174D01*
G01Y611811D02*
Y611024D01*
G01X72893Y610926D02*
Y611910D01*
G01Y614075D02*
Y615059D01*
G01Y607776D02*
Y608760D01*
G01Y604626D02*
Y605611D01*
G01Y601477D02*
Y602461D01*
G01Y598327D02*
Y599311D01*
G01Y595177D02*
Y596162D01*
G01Y592028D02*
Y593012D01*
G01Y588878D02*
Y589863D01*
G01Y585729D02*
Y586713D01*
G01Y582579D02*
Y583563D01*
G01Y579429D02*
Y580414D01*
G01Y576280D02*
Y577264D01*
G01Y573130D02*
Y574115D01*
G01Y569981D02*
Y570965D01*
G01Y566831D02*
Y567815D01*
G01Y563681D02*
Y564666D01*
G01Y560532D02*
Y561516D01*
G01X72855Y561418D02*
Y560630D01*
G01Y567717D02*
Y566929D01*
G01Y564567D02*
Y563780D01*
G01Y570866D02*
Y570079D01*
G01Y577166D02*
Y576378D01*
G01Y574016D02*
Y573229D01*
G01Y580315D02*
Y579528D01*
G01Y586615D02*
Y585827D01*
G01Y583465D02*
Y582677D01*
G01Y589764D02*
Y588977D01*
G01Y596063D02*
Y595276D01*
G01Y592914D02*
Y592126D01*
G01Y599213D02*
Y598426D01*
G01Y605512D02*
Y604725D01*
G01Y602363D02*
Y601575D01*
G01Y608662D02*
Y607874D01*
G01Y614961D02*
Y614174D01*
G01Y611811D02*
Y611024D01*
G01X72834Y561418D02*
Y560630D01*
G01Y567717D02*
Y566929D01*
G01Y564567D02*
Y563780D01*
G01Y570866D02*
Y570079D01*
G01Y577166D02*
Y576378D01*
G01Y574016D02*
Y573229D01*
G01Y580315D02*
Y579528D01*
G01Y586615D02*
Y585827D01*
G01Y583465D02*
Y582677D01*
G01Y589764D02*
Y588977D01*
G01Y596063D02*
Y595276D01*
G01Y592914D02*
Y592126D01*
G01Y599213D02*
Y598426D01*
G01Y605512D02*
Y604725D01*
G01Y602363D02*
Y601575D01*
G01Y608662D02*
Y607874D01*
G01Y614961D02*
Y614174D01*
G01Y611811D02*
Y611024D01*
G01X72795Y614183D02*
Y614952D01*
G01Y611033D02*
Y611802D01*
G01Y607883D02*
Y608653D01*
G01Y604734D02*
Y605503D01*
G01Y601584D02*
Y602353D01*
G01Y598435D02*
Y599204D01*
G01Y595285D02*
Y596054D01*
G01Y592135D02*
Y592905D01*
G01Y588986D02*
Y589755D01*
G01Y585836D02*
Y586605D01*
G01Y582687D02*
Y583456D01*
G01Y579537D02*
Y580306D01*
G01Y576387D02*
Y577157D01*
G01Y573238D02*
Y574007D01*
G01Y570088D02*
Y570857D01*
G01Y566939D02*
Y567708D01*
G01Y563789D02*
Y564558D01*
G01Y560639D02*
Y561409D01*
G01X72783Y614174D02*
Y614961D01*
G01Y611024D02*
Y611811D01*
G01Y607874D02*
Y608662D01*
G01Y604725D02*
Y605512D01*
G01Y601575D02*
Y602363D01*
G01Y598426D02*
Y599213D01*
G01Y595276D02*
Y596063D01*
G01Y592126D02*
Y592914D01*
G01Y588977D02*
Y589764D01*
G01Y585827D02*
Y586615D01*
G01Y582677D02*
Y583465D01*
G01Y579528D02*
Y580315D01*
G01Y576378D02*
Y577166D01*
G01Y573229D02*
Y574016D01*
G01Y570079D02*
Y570866D01*
G01Y566929D02*
Y567717D01*
G01Y563780D02*
Y564567D01*
G01Y560630D02*
Y561418D01*
G01X72748D02*
Y560630D01*
G01Y567717D02*
Y566929D01*
G01Y564567D02*
Y563780D01*
G01Y570866D02*
Y570079D01*
G01Y577166D02*
Y576378D01*
G01Y574016D02*
Y573229D01*
G01Y580315D02*
Y579528D01*
G01Y586615D02*
Y585827D01*
G01Y583465D02*
Y582677D01*
G01Y589764D02*
Y588977D01*
G01Y596063D02*
Y595276D01*
G01Y592914D02*
Y592126D01*
G01Y599213D02*
Y598426D01*
G01Y605512D02*
Y604725D01*
G01Y602363D02*
Y601575D01*
G01Y608662D02*
Y607874D01*
G01Y614961D02*
Y614174D01*
G01Y611811D02*
Y611024D01*
G01X72693Y561306D02*
Y560742D01*
G01Y567605D02*
Y567041D01*
G01Y564455D02*
Y563891D01*
G01Y570755D02*
Y570190D01*
G01Y577054D02*
Y576490D01*
G01Y573904D02*
Y573340D01*
G01Y580203D02*
Y579639D01*
G01Y586503D02*
Y585939D01*
G01Y583353D02*
Y582789D01*
G01Y589652D02*
Y589088D01*
G01Y595952D02*
Y595387D01*
G01Y592802D02*
Y592238D01*
G01Y599101D02*
Y598537D01*
G01Y605400D02*
Y604836D01*
G01Y602251D02*
Y601687D01*
G01Y608550D02*
Y607986D01*
G01Y614849D02*
Y614285D01*
G01Y611700D02*
Y611135D01*
G01X72680Y562992D02*
Y562205D01*
G01Y566142D02*
Y565355D01*
G01Y572441D02*
Y571654D01*
G01Y569292D02*
Y568504D01*
G01Y575591D02*
Y574803D01*
G01Y581890D02*
Y581103D01*
G01Y578740D02*
Y577953D01*
G01Y585040D02*
Y584252D01*
G01Y591339D02*
Y590552D01*
G01Y588189D02*
Y587402D01*
G01Y594489D02*
Y593701D01*
G01Y600788D02*
Y600000D01*
G01Y597638D02*
Y596851D01*
G01Y603937D02*
Y603150D01*
G01Y610237D02*
Y609449D01*
G01Y607087D02*
Y606300D01*
G01Y613386D02*
Y612599D01*
G01Y616536D02*
Y615748D01*
G01X72667Y561418D02*
Y560630D01*
G01Y567717D02*
Y566929D01*
G01Y564567D02*
Y563780D01*
G01Y570866D02*
Y570079D01*
G01Y577166D02*
Y576378D01*
G01Y574016D02*
Y573229D01*
G01Y580315D02*
Y579528D01*
G01Y586615D02*
Y585827D01*
G01Y583465D02*
Y582677D01*
G01Y589764D02*
Y588977D01*
G01Y596063D02*
Y595276D01*
G01Y592914D02*
Y592126D01*
G01Y599213D02*
Y598426D01*
G01Y605512D02*
Y604725D01*
G01Y602363D02*
Y601575D01*
G01Y608662D02*
Y607874D01*
G01Y614961D02*
Y614174D01*
G01Y611811D02*
Y611024D01*
G01X72562Y615748D02*
Y616536D01*
G01Y612599D02*
Y613386D01*
G01Y609449D02*
Y610237D01*
G01Y606300D02*
Y607087D01*
G01Y603150D02*
Y603937D01*
G01Y600000D02*
Y600788D01*
G01Y596851D02*
Y597638D01*
G01Y593701D02*
Y594489D01*
G01Y590552D02*
Y591339D01*
G01Y587402D02*
Y588189D01*
G01Y584252D02*
Y585040D01*
G01Y581103D02*
Y581890D01*
G01Y577953D02*
Y578740D01*
G01Y574803D02*
Y575591D01*
G01Y571654D02*
Y572441D01*
G01Y568504D02*
Y569292D01*
G01Y565355D02*
Y566142D01*
G01Y562205D02*
Y562992D01*
G01X72441Y563150D02*
Y562048D01*
G01Y566300D02*
Y565197D01*
G01Y572599D02*
Y571496D01*
G01Y569449D02*
Y568347D01*
G01Y575748D02*
Y574646D01*
G01Y582048D02*
Y580945D01*
G01Y578898D02*
Y577796D01*
G01Y585197D02*
Y584095D01*
G01Y591496D02*
Y590394D01*
G01Y588347D02*
Y587244D01*
G01Y594646D02*
Y593544D01*
G01Y600945D02*
Y599843D01*
G01Y597796D02*
Y596693D01*
G01Y604095D02*
Y602992D01*
G01Y610394D02*
Y609292D01*
G01Y607244D02*
Y606142D01*
G01Y613544D02*
Y612441D01*
G01Y622835D02*
Y615591D01*
G01X72437Y614370D02*
Y614764D01*
G01Y611221D02*
Y611615D01*
G01Y608071D02*
Y608465D01*
G01Y604922D02*
Y605315D01*
G01Y601772D02*
Y602166D01*
G01Y598622D02*
Y599016D01*
G01Y595473D02*
Y595866D01*
G01Y592323D02*
Y592717D01*
G01Y589174D02*
Y589567D01*
G01Y586024D02*
Y586418D01*
G01Y582874D02*
Y583268D01*
G01Y579725D02*
Y580118D01*
G01Y576575D02*
Y576969D01*
G01Y573426D02*
Y573819D01*
G01Y570276D02*
Y570670D01*
G01Y567126D02*
Y567520D01*
G01Y563977D02*
Y564370D01*
G01Y560827D02*
Y561221D01*
G01X71653Y563681D02*
Y561516D01*
G01Y566831D02*
Y564666D01*
G01Y573130D02*
Y570965D01*
G01Y569981D02*
Y567815D01*
G01Y576280D02*
Y574115D01*
G01Y582579D02*
Y580414D01*
G01Y579429D02*
Y577264D01*
G01Y585729D02*
Y583563D01*
G01Y592028D02*
Y589863D01*
G01Y588878D02*
Y586713D01*
G01Y595177D02*
Y593012D01*
G01Y601477D02*
Y599311D01*
G01Y598327D02*
Y596162D01*
G01Y604626D02*
Y602461D01*
G01Y610926D02*
Y608760D01*
G01Y607776D02*
Y605611D01*
G01Y614075D02*
Y611910D01*
G01Y622835D02*
Y615059D01*
G01X71407Y562992D02*
Y562205D01*
G01Y566142D02*
Y565355D01*
G01Y572441D02*
Y571654D01*
G01Y569292D02*
Y568504D01*
G01Y575591D02*
Y574803D01*
G01Y581890D02*
Y581103D01*
G01Y578740D02*
Y577953D01*
G01Y585040D02*
Y584252D01*
G01Y591339D02*
Y590552D01*
G01Y588189D02*
Y587402D01*
G01Y594489D02*
Y593701D01*
G01Y600788D02*
Y600000D01*
G01Y597638D02*
Y596851D01*
G01Y603937D02*
Y603150D01*
G01Y610237D02*
Y609449D01*
G01Y607087D02*
Y606300D01*
G01Y613386D02*
Y612599D01*
G01Y616536D02*
Y615748D01*
G01X71385Y562992D02*
Y562205D01*
G01Y566142D02*
Y565355D01*
G01Y572441D02*
Y571654D01*
G01Y569292D02*
Y568504D01*
G01Y575591D02*
Y574803D01*
G01Y581890D02*
Y581103D01*
G01Y578740D02*
Y577953D01*
G01Y585040D02*
Y584252D01*
G01Y591339D02*
Y590552D01*
G01Y588189D02*
Y587402D01*
G01Y594489D02*
Y593701D01*
G01Y600788D02*
Y600000D01*
G01Y597638D02*
Y596851D01*
G01Y603937D02*
Y603150D01*
G01Y610237D02*
Y609449D01*
G01Y607087D02*
Y606300D01*
G01Y613386D02*
Y612599D01*
G01Y616536D02*
Y615748D01*
G01X71131D02*
Y616536D01*
G01Y612599D02*
Y613386D01*
G01Y609449D02*
Y610237D01*
G01Y606300D02*
Y607087D01*
G01Y603150D02*
Y603937D01*
G01Y600000D02*
Y600788D01*
G01Y596851D02*
Y597638D01*
G01Y593701D02*
Y594489D01*
G01Y590552D02*
Y591339D01*
G01Y587402D02*
Y588189D01*
G01Y584252D02*
Y585040D01*
G01Y581103D02*
Y581890D01*
G01Y577953D02*
Y578740D01*
G01Y574803D02*
Y575591D01*
G01Y571654D02*
Y572441D01*
G01Y568504D02*
Y569292D01*
G01Y565355D02*
Y566142D01*
G01Y562205D02*
Y562992D01*
G01X70472Y615748D02*
Y616536D01*
G01Y612599D02*
Y613386D01*
G01Y609449D02*
Y610237D01*
G01Y606300D02*
Y607087D01*
G01Y603150D02*
Y603937D01*
G01Y600000D02*
Y600788D01*
G01Y596851D02*
Y597638D01*
G01Y593701D02*
Y594489D01*
G01Y590552D02*
Y591339D01*
G01Y587402D02*
Y588189D01*
G01Y584252D02*
Y585040D01*
G01Y581103D02*
Y581890D01*
G01Y577953D02*
Y578740D01*
G01Y574803D02*
Y575591D01*
G01Y571654D02*
Y572441D01*
G01Y568504D02*
Y569292D01*
G01Y565355D02*
Y566142D01*
G01Y562205D02*
Y562992D01*
G01X70280Y561221D02*
Y560827D01*
G01Y567520D02*
Y567126D01*
G01Y564370D02*
Y563977D01*
G01Y570670D02*
Y570276D01*
G01Y576969D02*
Y576575D01*
G01Y573819D02*
Y573426D01*
G01Y580118D02*
Y579725D01*
G01Y586418D02*
Y586024D01*
G01Y583268D02*
Y582874D01*
G01Y589567D02*
Y589174D01*
G01Y595866D02*
Y595473D01*
G01Y592717D02*
Y592323D01*
G01Y599016D02*
Y598622D01*
G01Y605315D02*
Y604922D01*
G01Y602166D02*
Y601772D01*
G01Y608465D02*
Y608071D01*
G01Y614764D02*
Y614370D01*
G01Y611615D02*
Y611221D01*
G01X70024Y614285D02*
Y614849D01*
G01Y611135D02*
Y611700D01*
G01Y607986D02*
Y608550D01*
G01Y604836D02*
Y605400D01*
G01Y601687D02*
Y602251D01*
G01Y598537D02*
Y599101D01*
G01Y595387D02*
Y595952D01*
G01Y592238D02*
Y592802D01*
G01Y589088D02*
Y589652D01*
G01Y585939D02*
Y586503D01*
G01Y582789D02*
Y583353D01*
G01Y579639D02*
Y580203D01*
G01Y576490D02*
Y577054D01*
G01Y573340D02*
Y573904D01*
G01Y570190D02*
Y570755D01*
G01Y567041D02*
Y567605D01*
G01Y563891D02*
Y564455D01*
G01Y560742D02*
Y561306D01*
G01X69921Y561409D02*
Y560639D01*
G01Y567708D02*
Y566939D01*
G01Y564558D02*
Y563789D01*
G01Y570857D02*
Y570088D01*
G01Y577157D02*
Y576387D01*
G01Y574007D02*
Y573238D01*
G01Y580306D02*
Y579537D01*
G01Y586605D02*
Y585836D01*
G01Y583456D02*
Y582687D01*
G01Y589755D02*
Y588986D01*
G01Y596054D02*
Y595285D01*
G01Y592905D02*
Y592135D01*
G01Y599204D02*
Y598435D01*
G01Y605503D02*
Y604734D01*
G01Y602353D02*
Y601584D01*
G01Y608653D02*
Y607883D01*
G01Y614952D02*
Y614183D01*
G01Y611802D02*
Y611033D01*
G01X69882Y610926D02*
Y611910D01*
G01Y614075D02*
Y615059D01*
G01Y607776D02*
Y608760D01*
G01Y604626D02*
Y605611D01*
G01Y601477D02*
Y602461D01*
G01Y598327D02*
Y599311D01*
G01Y595177D02*
Y596162D01*
G01Y592028D02*
Y593012D01*
G01Y588878D02*
Y589863D01*
G01Y585729D02*
Y586713D01*
G01Y582579D02*
Y583563D01*
G01Y579429D02*
Y580414D01*
G01Y576280D02*
Y577264D01*
G01Y573130D02*
Y574115D01*
G01Y569981D02*
Y570965D01*
G01Y566831D02*
Y567815D01*
G01Y563681D02*
Y564666D01*
G01Y560532D02*
Y561516D01*
G01Y562992D02*
Y562205D01*
G01Y566142D02*
Y565355D01*
G01Y572441D02*
Y571654D01*
G01Y569292D02*
Y568504D01*
G01Y575591D02*
Y574803D01*
G01Y581890D02*
Y581103D01*
G01Y578740D02*
Y577953D01*
G01Y585040D02*
Y584252D01*
G01Y591339D02*
Y590552D01*
G01Y588189D02*
Y587402D01*
G01Y594489D02*
Y593701D01*
G01Y600788D02*
Y600000D01*
G01Y597638D02*
Y596851D01*
G01Y603937D02*
Y603150D01*
G01Y610237D02*
Y609449D01*
G01Y607087D02*
Y606300D01*
G01Y613386D02*
Y612599D01*
G01Y616536D02*
Y615748D01*
G01X69669Y614174D02*
Y614961D01*
G01Y611024D02*
Y611811D01*
G01Y607874D02*
Y608662D01*
G01Y604725D02*
Y605512D01*
G01Y601575D02*
Y602363D01*
G01Y598426D02*
Y599213D01*
G01Y595276D02*
Y596063D01*
G01Y592126D02*
Y592914D01*
G01Y588977D02*
Y589764D01*
G01Y585827D02*
Y586615D01*
G01Y582677D02*
Y583465D01*
G01Y579528D02*
Y580315D01*
G01Y576378D02*
Y577166D01*
G01Y573229D02*
Y574016D01*
G01Y570079D02*
Y570866D01*
G01Y566929D02*
Y567717D01*
G01Y563780D02*
Y564567D01*
G01Y560630D02*
Y561418D01*
G01X69567Y610926D02*
Y611910D01*
G01Y614075D02*
Y615059D01*
G01Y607776D02*
Y608760D01*
G01Y604626D02*
Y605611D01*
G01Y601477D02*
Y602461D01*
G01Y598327D02*
Y599311D01*
G01Y595177D02*
Y596162D01*
G01Y592028D02*
Y593012D01*
G01Y588878D02*
Y589863D01*
G01Y585729D02*
Y586713D01*
G01Y582579D02*
Y583563D01*
G01Y579429D02*
Y580414D01*
G01Y576280D02*
Y577264D01*
G01Y573130D02*
Y574115D01*
G01Y569981D02*
Y570965D01*
G01Y566831D02*
Y567815D01*
G01Y563681D02*
Y564666D01*
G01Y560532D02*
Y561516D01*
G01X69291Y615748D02*
Y616536D01*
G01Y612599D02*
Y613386D01*
G01Y609449D02*
Y610237D01*
G01Y606300D02*
Y607087D01*
G01Y603150D02*
Y603937D01*
G01Y600000D02*
Y600788D01*
G01Y596851D02*
Y597638D01*
G01Y593701D02*
Y594489D01*
G01Y590552D02*
Y591339D01*
G01Y587402D02*
Y588189D01*
G01Y584252D02*
Y585040D01*
G01Y581103D02*
Y581890D01*
G01Y577953D02*
Y578740D01*
G01Y574803D02*
Y575591D01*
G01Y571654D02*
Y572441D01*
G01Y568504D02*
Y569292D01*
G01Y565355D02*
Y566142D01*
G01Y562205D02*
Y562992D01*
G01X69252Y610926D02*
Y611910D01*
G01Y614075D02*
Y615059D01*
G01Y607776D02*
Y608760D01*
G01Y604626D02*
Y605611D01*
G01Y601477D02*
Y602461D01*
G01Y598327D02*
Y599311D01*
G01Y595177D02*
Y596162D01*
G01Y592028D02*
Y593012D01*
G01Y588878D02*
Y589863D01*
G01Y585729D02*
Y586713D01*
G01Y582579D02*
Y583563D01*
G01Y579429D02*
Y580414D01*
G01Y576280D02*
Y577264D01*
G01Y573130D02*
Y574115D01*
G01Y569981D02*
Y570965D01*
G01Y566831D02*
Y567815D01*
G01Y563681D02*
Y564666D01*
G01Y560532D02*
Y561516D01*
G01X69236Y561418D02*
Y560630D01*
G01Y567717D02*
Y566929D01*
G01Y564567D02*
Y563780D01*
G01Y570866D02*
Y570079D01*
G01Y577166D02*
Y576378D01*
G01Y574016D02*
Y573229D01*
G01Y580315D02*
Y579528D01*
G01Y586615D02*
Y585827D01*
G01Y583465D02*
Y582677D01*
G01Y589764D02*
Y588977D01*
G01Y596063D02*
Y595276D01*
G01Y592914D02*
Y592126D01*
G01Y599213D02*
Y598426D01*
G01Y605512D02*
Y604725D01*
G01Y602363D02*
Y601575D01*
G01Y608662D02*
Y607874D01*
G01Y614961D02*
Y614174D01*
G01Y611811D02*
Y611024D01*
G01X69012Y561418D02*
Y560630D01*
G01Y567717D02*
Y566929D01*
G01Y564567D02*
Y563780D01*
G01Y570866D02*
Y570079D01*
G01Y577166D02*
Y576378D01*
G01Y574016D02*
Y573229D01*
G01Y580315D02*
Y579528D01*
G01Y586615D02*
Y585827D01*
G01Y583465D02*
Y582677D01*
G01Y589764D02*
Y588977D01*
G01Y596063D02*
Y595276D01*
G01Y592914D02*
Y592126D01*
G01Y599213D02*
Y598426D01*
G01Y605512D02*
Y604725D01*
G01Y602363D02*
Y601575D01*
G01Y608662D02*
Y607874D01*
G01Y614961D02*
Y614174D01*
G01Y611811D02*
Y611024D01*
G01X68701Y562992D02*
Y562205D01*
G01Y566142D02*
Y565355D01*
G01Y572441D02*
Y571654D01*
G01Y569292D02*
Y568504D01*
G01Y575591D02*
Y574803D01*
G01Y581890D02*
Y581103D01*
G01Y578740D02*
Y577953D01*
G01Y585040D02*
Y584252D01*
G01Y591339D02*
Y590552D01*
G01Y588189D02*
Y587402D01*
G01Y594489D02*
Y593701D01*
G01Y600788D02*
Y600000D01*
G01Y597638D02*
Y596851D01*
G01Y603937D02*
Y603150D01*
G01Y610237D02*
Y609449D01*
G01Y607087D02*
Y606300D01*
G01Y613386D02*
Y612599D01*
G01Y616536D02*
Y615748D01*
G01X68578Y614174D02*
Y614961D01*
G01Y611024D02*
Y611811D01*
G01Y607874D02*
Y608662D01*
G01Y604725D02*
Y605512D01*
G01Y601575D02*
Y602363D01*
G01Y598426D02*
Y599213D01*
G01Y595276D02*
Y596063D01*
G01Y592126D02*
Y592914D01*
G01Y588977D02*
Y589764D01*
G01Y585827D02*
Y586615D01*
G01Y582677D02*
Y583465D01*
G01Y579528D02*
Y580315D01*
G01Y576378D02*
Y577166D01*
G01Y573229D02*
Y574016D01*
G01Y570079D02*
Y570866D01*
G01Y566929D02*
Y567717D01*
G01Y563780D02*
Y564567D01*
G01Y560630D02*
Y561418D01*
G01X68110Y615748D02*
Y616536D01*
G01Y612599D02*
Y613386D01*
G01Y609449D02*
Y610237D01*
G01Y606300D02*
Y607087D01*
G01Y603150D02*
Y603937D01*
G01Y600000D02*
Y600788D01*
G01Y596851D02*
Y597638D01*
G01Y593701D02*
Y594489D01*
G01Y590552D02*
Y591339D01*
G01Y587402D02*
Y588189D01*
G01Y584252D02*
Y585040D01*
G01Y581103D02*
Y581890D01*
G01Y577953D02*
Y578740D01*
G01Y574803D02*
Y575591D01*
G01Y571654D02*
Y572441D01*
G01Y568504D02*
Y569292D01*
G01Y565355D02*
Y566142D01*
G01Y562205D02*
Y562992D01*
G01X67401Y557481D02*
Y619685D01*
G01X67382Y622835D02*
Y621851D01*
G01X67283Y622835D02*
Y621851D01*
G01X66201Y622835D02*
Y621851D01*
G01X65807D02*
Y622835D01*
G01X65019D02*
Y621721D01*
G01X60499Y607481D02*
Y569685D01*
G01X60197Y621851D02*
Y620866D01*
G01X59728Y569685D02*
Y607481D01*
G01X59704Y622835D02*
Y621851D01*
G01X59675Y607481D02*
Y569685D01*
G01X59236Y607481D02*
Y569685D01*
G01X59055Y617579D02*
Y622835D01*
G01X58789Y569685D02*
Y607481D01*
G01X58267Y622835D02*
Y617579D01*
G01X57677Y615059D02*
Y615591D01*
G01Y610394D02*
Y610926D01*
G01Y611910D02*
Y612441D01*
G01Y613544D02*
Y614075D01*
G01Y605611D02*
Y606142D01*
G01Y607244D02*
Y607776D01*
G01Y608760D02*
Y609292D01*
G01Y600945D02*
Y601477D01*
G01Y602461D02*
Y602992D01*
G01Y604095D02*
Y604626D01*
G01Y596162D02*
Y596693D01*
G01Y597796D02*
Y598327D01*
G01Y599311D02*
Y599843D01*
G01Y591496D02*
Y592028D01*
G01Y593012D02*
Y593544D01*
G01Y594646D02*
Y595177D01*
G01Y586713D02*
Y587244D01*
G01Y588347D02*
Y588878D01*
G01Y589863D02*
Y590394D01*
G01Y582048D02*
Y582579D01*
G01Y583563D02*
Y584095D01*
G01Y585197D02*
Y585729D01*
G01Y577264D02*
Y577796D01*
G01Y578898D02*
Y579429D01*
G01Y580414D02*
Y580945D01*
G01Y572599D02*
Y573130D01*
G01Y574115D02*
Y574646D01*
G01Y575748D02*
Y576280D01*
G01Y567815D02*
Y568347D01*
G01Y569449D02*
Y569981D01*
G01Y570965D02*
Y571496D01*
G01Y563150D02*
Y563681D01*
G01Y564666D02*
Y565197D01*
G01Y566300D02*
Y566831D01*
G01Y560000D02*
Y560532D01*
G01Y561516D02*
Y562048D01*
G01X56850Y569685D02*
Y607481D01*
G01X56456D02*
Y569685D01*
G01X55658Y561312D02*
Y560736D01*
G01Y567611D02*
Y567035D01*
G01Y564462D02*
Y563885D01*
G01Y570761D02*
Y570185D01*
G01Y577060D02*
Y576484D01*
G01Y573911D02*
Y573334D01*
G01Y580210D02*
Y579633D01*
G01Y586509D02*
Y585933D01*
G01Y583359D02*
Y582783D01*
G01Y589659D02*
Y589082D01*
G01Y595958D02*
Y595381D01*
G01Y592808D02*
Y592232D01*
G01Y599107D02*
Y598531D01*
G01Y605407D02*
Y604830D01*
G01Y602257D02*
Y601681D01*
G01Y608556D02*
Y607980D01*
G01Y614855D02*
Y614279D01*
G01Y611706D02*
Y611129D01*
G01X55417Y615863D02*
Y616421D01*
G01Y612713D02*
Y613272D01*
G01Y609564D02*
Y610122D01*
G01Y606414D02*
Y606972D01*
G01Y603265D02*
Y603823D01*
G01Y600115D02*
Y600673D01*
G01Y596965D02*
Y597524D01*
G01Y593816D02*
Y594374D01*
G01Y590666D02*
Y591224D01*
G01Y587516D02*
Y588075D01*
G01Y584367D02*
Y584925D01*
G01Y581217D02*
Y581776D01*
G01Y578068D02*
Y578626D01*
G01Y574918D02*
Y575476D01*
G01Y571768D02*
Y572327D01*
G01Y568619D02*
Y569177D01*
G01Y565469D02*
Y566027D01*
G01Y562320D02*
Y562878D01*
G01X55314Y614174D02*
Y614961D01*
G01Y611024D02*
Y611811D01*
G01Y607874D02*
Y608662D01*
G01Y604725D02*
Y605512D01*
G01Y601575D02*
Y602363D01*
G01Y598426D02*
Y599213D01*
G01Y595276D02*
Y596063D01*
G01Y592126D02*
Y592914D01*
G01Y588977D02*
Y589764D01*
G01Y585827D02*
Y586615D01*
G01Y582677D02*
Y583465D01*
G01Y579528D02*
Y580315D01*
G01Y576378D02*
Y577166D01*
G01Y573229D02*
Y574016D01*
G01Y570079D02*
Y570866D01*
G01Y566929D02*
Y567717D01*
G01Y563780D02*
Y564567D01*
G01Y560630D02*
Y561418D01*
G01X55217Y562848D02*
Y562350D01*
G01Y565997D02*
Y565500D01*
G01Y572296D02*
Y571799D01*
G01Y569147D02*
Y568649D01*
G01Y575446D02*
Y574948D01*
G01Y581745D02*
Y581248D01*
G01Y578596D02*
Y578098D01*
G01Y584895D02*
Y584397D01*
G01Y591194D02*
Y590696D01*
G01Y588044D02*
Y587547D01*
G01Y594344D02*
Y593846D01*
G01Y600643D02*
Y600145D01*
G01Y597493D02*
Y596996D01*
G01Y603792D02*
Y603295D01*
G01Y610092D02*
Y609594D01*
G01Y606942D02*
Y606444D01*
G01Y613241D02*
Y612744D01*
G01Y616391D02*
Y615893D01*
G01X55193Y615898D02*
Y616386D01*
G01Y612749D02*
Y613236D01*
G01Y609599D02*
Y610087D01*
G01Y606450D02*
Y606937D01*
G01Y603300D02*
Y603787D01*
G01Y600150D02*
Y600638D01*
G01Y597001D02*
Y597488D01*
G01Y593851D02*
Y594339D01*
G01Y590702D02*
Y591189D01*
G01Y587552D02*
Y588039D01*
G01Y584402D02*
Y584890D01*
G01Y581253D02*
Y581740D01*
G01Y578103D02*
Y578590D01*
G01Y574953D02*
Y575441D01*
G01Y571804D02*
Y572291D01*
G01Y568654D02*
Y569142D01*
G01Y565505D02*
Y565992D01*
G01Y562355D02*
Y562842D01*
G01X55160Y562992D02*
Y562205D01*
G01Y566142D02*
Y565355D01*
G01Y572441D02*
Y571654D01*
G01Y569292D02*
Y568504D01*
G01Y575591D02*
Y574803D01*
G01Y581890D02*
Y581103D01*
G01Y578740D02*
Y577953D01*
G01Y585040D02*
Y584252D01*
G01Y591339D02*
Y590552D01*
G01Y588189D02*
Y587402D01*
G01Y594489D02*
Y593701D01*
G01Y600788D02*
Y600000D01*
G01Y597638D02*
Y596851D01*
G01Y603937D02*
Y603150D01*
G01Y610237D02*
Y609449D01*
G01Y607087D02*
Y606300D01*
G01Y613386D02*
Y612599D01*
G01Y616536D02*
Y615748D01*
G01X54977D02*
Y616536D01*
G01Y612599D02*
Y613386D01*
G01Y609449D02*
Y610237D01*
G01Y606300D02*
Y607087D01*
G01Y603150D02*
Y603937D01*
G01Y600000D02*
Y600788D01*
G01Y596851D02*
Y597638D01*
G01Y593701D02*
Y594489D01*
G01Y590552D02*
Y591339D01*
G01Y587402D02*
Y588189D01*
G01Y584252D02*
Y585040D01*
G01Y581103D02*
Y581890D01*
G01Y577953D02*
Y578740D01*
G01Y574803D02*
Y575591D01*
G01Y571654D02*
Y572441D01*
G01Y568504D02*
Y569292D01*
G01Y565355D02*
Y566142D01*
G01Y562205D02*
Y562992D01*
G01X54836D02*
Y562205D01*
G01Y566142D02*
Y565355D01*
G01Y572441D02*
Y571654D01*
G01Y569292D02*
Y568504D01*
G01Y575591D02*
Y574803D01*
G01Y581890D02*
Y581103D01*
G01Y578740D02*
Y577953D01*
G01Y585040D02*
Y584252D01*
G01Y591339D02*
Y590552D01*
G01Y588189D02*
Y587402D01*
G01Y594489D02*
Y593701D01*
G01Y600788D02*
Y600000D01*
G01Y597638D02*
Y596851D01*
G01Y603937D02*
Y603150D01*
G01Y610237D02*
Y609449D01*
G01Y607087D02*
Y606300D01*
G01Y613386D02*
Y612599D01*
G01Y616536D02*
Y615748D01*
G01X54619D02*
Y616536D01*
G01Y612599D02*
Y613386D01*
G01Y609449D02*
Y610237D01*
G01Y606300D02*
Y607087D01*
G01Y603150D02*
Y603937D01*
G01Y600000D02*
Y600788D01*
G01Y596851D02*
Y597638D01*
G01Y593701D02*
Y594489D01*
G01Y590552D02*
Y591339D01*
G01Y587402D02*
Y588189D01*
G01Y584252D02*
Y585040D01*
G01Y581103D02*
Y581890D01*
G01Y577953D02*
Y578740D01*
G01Y574803D02*
Y575591D01*
G01Y571654D02*
Y572441D01*
G01Y568504D02*
Y569292D01*
G01Y565355D02*
Y566142D01*
G01Y562205D02*
Y562992D01*
G01X54319Y562831D02*
Y562366D01*
G01Y565981D02*
Y565516D01*
G01Y572280D02*
Y571815D01*
G01Y569131D02*
Y568665D01*
G01Y575430D02*
Y574965D01*
G01Y581729D02*
Y581264D01*
G01Y578579D02*
Y578114D01*
G01Y584879D02*
Y584413D01*
G01Y591178D02*
Y590713D01*
G01Y588028D02*
Y587563D01*
G01Y594327D02*
Y593862D01*
G01Y600627D02*
Y600161D01*
G01Y597477D02*
Y597012D01*
G01Y603776D02*
Y603311D01*
G01Y610076D02*
Y609610D01*
G01Y606926D02*
Y606461D01*
G01Y613225D02*
Y612760D01*
G01Y616375D02*
Y615909D01*
G01X54289Y561418D02*
Y560630D01*
G01Y567717D02*
Y566929D01*
G01Y564567D02*
Y563780D01*
G01Y570866D02*
Y570079D01*
G01Y577166D02*
Y576378D01*
G01Y574016D02*
Y573229D01*
G01Y580315D02*
Y579528D01*
G01Y586615D02*
Y585827D01*
G01Y583465D02*
Y582677D01*
G01Y589764D02*
Y588977D01*
G01Y596063D02*
Y595276D01*
G01Y592914D02*
Y592126D01*
G01Y599213D02*
Y598426D01*
G01Y605512D02*
Y604725D01*
G01Y602363D02*
Y601575D01*
G01Y608662D02*
Y607874D01*
G01Y614961D02*
Y614174D01*
G01Y611811D02*
Y611024D01*
G01X53898Y569685D02*
Y607481D01*
G01X53864Y614288D02*
Y614846D01*
G01Y611139D02*
Y611697D01*
G01Y607989D02*
Y608547D01*
G01Y604839D02*
Y605398D01*
G01Y601690D02*
Y602248D01*
G01Y598540D02*
Y599098D01*
G01Y595390D02*
Y595949D01*
G01Y592241D02*
Y592799D01*
G01Y589091D02*
Y589650D01*
G01Y585942D02*
Y586500D01*
G01Y582792D02*
Y583350D01*
G01Y579642D02*
Y580201D01*
G01Y576493D02*
Y577051D01*
G01Y573343D02*
Y573902D01*
G01Y570194D02*
Y570752D01*
G01Y567044D02*
Y567602D01*
G01Y563894D02*
Y564453D01*
G01Y560745D02*
Y561303D01*
G01X53504Y607481D02*
Y569685D01*
G01X52756Y622835D02*
Y617579D01*
G01X52657Y622835D02*
Y619292D01*
G01X51771Y560532D02*
Y560000D01*
G01Y562048D02*
Y561516D01*
G01Y563681D02*
Y563150D01*
G01Y565197D02*
Y564666D01*
G01Y566831D02*
Y566300D01*
G01Y568347D02*
Y567815D01*
G01Y569981D02*
Y569449D01*
G01Y571496D02*
Y570965D01*
G01Y573130D02*
Y572599D01*
G01Y574646D02*
Y574115D01*
G01Y576280D02*
Y575748D01*
G01Y577796D02*
Y577264D01*
G01Y579429D02*
Y578898D01*
G01Y580945D02*
Y580414D01*
G01Y582579D02*
Y582048D01*
G01Y584095D02*
Y583563D01*
G01Y585729D02*
Y585197D01*
G01Y587244D02*
Y586713D01*
G01Y588878D02*
Y588347D01*
G01Y590394D02*
Y589863D01*
G01Y592028D02*
Y591496D01*
G01Y593544D02*
Y593012D01*
G01Y595177D02*
Y594646D01*
G01Y596693D02*
Y596162D01*
G01Y598327D02*
Y597796D01*
G01Y599843D02*
Y599311D01*
G01Y601477D02*
Y600945D01*
G01Y602992D02*
Y602461D01*
G01Y604626D02*
Y604095D01*
G01Y606142D02*
Y605611D01*
G01Y607776D02*
Y607244D01*
G01Y609292D02*
Y608760D01*
G01Y610926D02*
Y610394D01*
G01Y612441D02*
Y611910D01*
G01Y614075D02*
Y613544D01*
G01Y615591D02*
Y615059D01*
G01X51651Y607481D02*
Y569685D01*
G01X51205D02*
Y607481D01*
G01X50939Y561418D02*
Y560630D01*
G01Y567717D02*
Y566929D01*
G01Y564567D02*
Y563780D01*
G01Y570866D02*
Y570079D01*
G01Y577166D02*
Y576378D01*
G01Y574016D02*
Y573229D01*
G01Y580315D02*
Y579528D01*
G01Y586615D02*
Y585827D01*
G01Y583465D02*
Y582677D01*
G01Y589764D02*
Y588977D01*
G01Y596063D02*
Y595276D01*
G01Y592914D02*
Y592126D01*
G01Y599213D02*
Y598426D01*
G01Y605512D02*
Y604725D01*
G01Y602363D02*
Y601575D01*
G01Y608662D02*
Y607874D01*
G01Y614961D02*
Y614174D01*
G01Y611811D02*
Y611024D01*
G01X50766Y569685D02*
Y607481D01*
G01X50713D02*
Y569685D01*
G01X50468Y615748D02*
Y616536D01*
G01Y612599D02*
Y613386D01*
G01Y609449D02*
Y610237D01*
G01Y606300D02*
Y607087D01*
G01Y603150D02*
Y603937D01*
G01Y600000D02*
Y600788D01*
G01Y596851D02*
Y597638D01*
G01Y593701D02*
Y594489D01*
G01Y590552D02*
Y591339D01*
G01Y587402D02*
Y588189D01*
G01Y584252D02*
Y585040D01*
G01Y581103D02*
Y581890D01*
G01Y577953D02*
Y578740D01*
G01Y574803D02*
Y575591D01*
G01Y571654D02*
Y572441D01*
G01Y568504D02*
Y569292D01*
G01Y565355D02*
Y566142D01*
G01Y562205D02*
Y562992D01*
G01X50397Y569685D02*
Y607481D01*
G01X50393Y617579D02*
Y622835D01*
G01X50124Y607481D02*
Y569685D01*
G01X49656Y614174D02*
Y614961D01*
G01Y611024D02*
Y611811D01*
G01Y607874D02*
Y608662D01*
G01Y604725D02*
Y605512D01*
G01Y601575D02*
Y602363D01*
G01Y598426D02*
Y599213D01*
G01Y595276D02*
Y596063D01*
G01Y592126D02*
Y592914D01*
G01Y588977D02*
Y589764D01*
G01Y585827D02*
Y586615D01*
G01Y582677D02*
Y583465D01*
G01Y579528D02*
Y580315D01*
G01Y576378D02*
Y577166D01*
G01Y573229D02*
Y574016D01*
G01Y570079D02*
Y570866D01*
G01Y566929D02*
Y567717D01*
G01Y563780D02*
Y564567D01*
G01Y560630D02*
Y561418D01*
G01X49629Y562935D02*
Y562263D01*
G01Y566085D02*
Y565412D01*
G01Y572384D02*
Y571711D01*
G01Y569234D02*
Y568562D01*
G01Y575533D02*
Y574861D01*
G01Y581833D02*
Y581160D01*
G01Y578683D02*
Y578011D01*
G01Y584982D02*
Y584310D01*
G01Y591281D02*
Y590609D01*
G01Y588132D02*
Y587459D01*
G01Y594431D02*
Y593759D01*
G01Y600730D02*
Y600058D01*
G01Y597581D02*
Y596908D01*
G01Y603880D02*
Y603207D01*
G01Y610179D02*
Y609507D01*
G01Y607029D02*
Y606357D01*
G01Y613329D02*
Y612656D01*
G01Y616478D02*
Y615806D01*
G01X49606Y622835D02*
Y617579D01*
G01X49406Y561418D02*
Y560630D01*
G01Y567717D02*
Y566929D01*
G01Y564567D02*
Y563780D01*
G01Y570866D02*
Y570079D01*
G01Y577166D02*
Y576378D01*
G01Y574016D02*
Y573229D01*
G01Y580315D02*
Y579528D01*
G01Y586615D02*
Y585827D01*
G01Y583465D02*
Y582677D01*
G01Y589764D02*
Y588977D01*
G01Y596063D02*
Y595276D01*
G01Y592914D02*
Y592126D01*
G01Y599213D02*
Y598426D01*
G01Y605512D02*
Y604725D01*
G01Y602363D02*
Y601575D01*
G01Y608662D02*
Y607874D01*
G01Y614961D02*
Y614174D01*
G01Y611811D02*
Y611024D01*
G01X49366Y562865D02*
Y562333D01*
G01Y566014D02*
Y565483D01*
G01Y572313D02*
Y571782D01*
G01Y569164D02*
Y568632D01*
G01Y575463D02*
Y574931D01*
G01Y581762D02*
Y581231D01*
G01Y578613D02*
Y578081D01*
G01Y584912D02*
Y584380D01*
G01Y591211D02*
Y590679D01*
G01Y588061D02*
Y587530D01*
G01Y594361D02*
Y593829D01*
G01Y600660D02*
Y600128D01*
G01Y597510D02*
Y596979D01*
G01Y603809D02*
Y603278D01*
G01Y610109D02*
Y609577D01*
G01Y606959D02*
Y606427D01*
G01Y613258D02*
Y612727D01*
G01Y616408D02*
Y615876D01*
G01X49361Y615877D02*
Y616407D01*
G01Y612728D02*
Y613257D01*
G01Y609578D02*
Y610107D01*
G01Y606429D02*
Y606958D01*
G01Y603279D02*
Y603808D01*
G01Y600129D02*
Y600659D01*
G01Y596980D02*
Y597509D01*
G01Y593830D02*
Y594359D01*
G01Y590681D02*
Y591210D01*
G01Y587531D02*
Y588060D01*
G01Y584381D02*
Y584911D01*
G01Y581232D02*
Y581761D01*
G01Y578082D02*
Y578611D01*
G01Y574933D02*
Y575462D01*
G01Y571783D02*
Y572312D01*
G01Y568633D02*
Y569163D01*
G01Y565484D02*
Y566013D01*
G01Y562334D02*
Y562863D01*
G01X49353Y614174D02*
Y614961D01*
G01Y611024D02*
Y611811D01*
G01Y607874D02*
Y608662D01*
G01Y604725D02*
Y605512D01*
G01Y601575D02*
Y602363D01*
G01Y598426D02*
Y599213D01*
G01Y595276D02*
Y596063D01*
G01Y592126D02*
Y592914D01*
G01Y588977D02*
Y589764D01*
G01Y585827D02*
Y586615D01*
G01Y582677D02*
Y583465D01*
G01Y579528D02*
Y580315D01*
G01Y576378D02*
Y577166D01*
G01Y573229D02*
Y574016D01*
G01Y570079D02*
Y570866D01*
G01Y566929D02*
Y567717D01*
G01Y563780D02*
Y564567D01*
G01Y560630D02*
Y561418D01*
G01X49325Y614174D02*
Y614961D01*
G01Y611024D02*
Y611811D01*
G01Y607874D02*
Y608662D01*
G01Y604725D02*
Y605512D01*
G01Y601575D02*
Y602363D01*
G01Y598426D02*
Y599213D01*
G01Y595276D02*
Y596063D01*
G01Y592126D02*
Y592914D01*
G01Y588977D02*
Y589764D01*
G01Y585827D02*
Y586615D01*
G01Y582677D02*
Y583465D01*
G01Y579528D02*
Y580315D01*
G01Y576378D02*
Y577166D01*
G01Y573229D02*
Y574016D01*
G01Y570079D02*
Y570866D01*
G01Y566929D02*
Y567717D01*
G01Y563780D02*
Y564567D01*
G01Y560630D02*
Y561418D01*
G01X49109Y562796D02*
Y562402D01*
G01Y565945D02*
Y565552D01*
G01Y572244D02*
Y571851D01*
G01Y569095D02*
Y568701D01*
G01Y575394D02*
Y575000D01*
G01Y581693D02*
Y581300D01*
G01Y578544D02*
Y578150D01*
G01Y584843D02*
Y584449D01*
G01Y591142D02*
Y590748D01*
G01Y587992D02*
Y587599D01*
G01Y594292D02*
Y593898D01*
G01Y600592D02*
Y600197D01*
G01Y597441D02*
Y597048D01*
G01Y603742D02*
Y603347D01*
G01Y610040D02*
Y609646D01*
G01Y606890D02*
Y606496D01*
G01Y613190D02*
Y612796D01*
G01Y616340D02*
Y615945D01*
G01X48031Y561516D02*
Y560532D01*
G01Y564666D02*
Y563681D01*
G01Y567815D02*
Y566831D01*
G01Y570965D02*
Y569981D01*
G01Y574115D02*
Y573130D01*
G01Y577264D02*
Y576280D01*
G01Y580414D02*
Y579429D01*
G01Y583563D02*
Y582579D01*
G01Y586713D02*
Y585729D01*
G01Y589863D02*
Y588878D01*
G01Y593012D02*
Y592028D01*
G01Y596162D02*
Y595177D01*
G01Y599311D02*
Y598327D01*
G01Y602461D02*
Y601477D01*
G01Y605611D02*
Y604626D01*
G01Y608760D02*
Y607776D01*
G01Y611910D02*
Y610926D01*
G01Y615059D02*
Y614075D01*
G01X47500Y562048D02*
Y560000D01*
G01Y565197D02*
Y563150D01*
G01Y571496D02*
Y569449D01*
G01Y568347D02*
Y566300D01*
G01Y574646D02*
Y572599D01*
G01Y580945D02*
Y578898D01*
G01Y577796D02*
Y575748D01*
G01Y584095D02*
Y582048D01*
G01Y590394D02*
Y588347D01*
G01Y587244D02*
Y585197D01*
G01Y593544D02*
Y591496D01*
G01Y599843D02*
Y597796D01*
G01Y596693D02*
Y594646D01*
G01Y602992D02*
Y600945D01*
G01Y609292D02*
Y607244D01*
G01Y606142D02*
Y604095D01*
G01Y612441D02*
Y610394D01*
G01Y615591D02*
Y613544D01*
G01X46063Y561811D02*
Y560237D01*
G01Y564961D02*
Y563386D01*
G01Y568111D02*
Y566536D01*
G01Y571260D02*
Y569685D01*
G01Y574410D02*
Y572835D01*
G01Y577559D02*
Y575985D01*
G01Y580709D02*
Y579134D01*
G01Y583859D02*
Y582284D01*
G01Y587008D02*
Y585433D01*
G01Y590158D02*
Y588583D01*
G01Y593307D02*
Y591733D01*
G01Y596457D02*
Y594882D01*
G01Y599607D02*
Y598032D01*
G01Y602756D02*
Y601181D01*
G01Y605906D02*
Y604331D01*
G01Y609055D02*
Y607481D01*
G01Y612205D02*
Y610630D01*
G01Y615355D02*
Y613780D01*
G01X46004Y557481D02*
Y619685D01*
G01X44291Y622835D02*
Y617579D01*
G01X43996Y622835D02*
Y619292D01*
G01X41791Y569685D02*
Y607481D01*
G01X41518D02*
Y569685D01*
G01X39390Y624115D02*
Y609449D01*
G01X36297Y563032D02*
Y557874D01*
G01X35760D02*
Y563032D01*
G01X34901Y559850D02*
Y559411D01*
G01X34764Y623130D02*
Y624115D01*
G01X34364Y559850D02*
Y559411D01*
G01X33582Y624115D02*
Y623130D01*
G01X33477Y624115D02*
Y623130D01*
G01X33182D02*
Y624115D01*
G01X32000Y559411D02*
Y559850D01*
G01X31818Y624115D02*
Y623130D01*
G01X31523D02*
Y624115D01*
G01X31462Y559411D02*
Y559850D01*
G01X31417Y624115D02*
Y623130D01*
G01X30603Y559959D02*
Y557874D01*
G01X30236Y624115D02*
Y623130D01*
G01X30065Y557874D02*
Y559959D01*
G01X49477Y614174D02*
Y614961D01*
G01Y611024D02*
Y611811D01*
G01Y607874D02*
Y608662D01*
G01Y604725D02*
Y605512D01*
G01Y601575D02*
Y602363D01*
G01Y598426D02*
Y599213D01*
G01Y595276D02*
Y596063D01*
G01Y592126D02*
Y592914D01*
G01Y588977D02*
Y589764D01*
G01Y585827D02*
Y586615D01*
G01Y582677D02*
Y583465D01*
G01Y579528D02*
Y580315D01*
G01Y576378D02*
Y577166D01*
G01Y573229D02*
Y574016D01*
G01Y570079D02*
Y570866D01*
G01Y566929D02*
Y567717D01*
G01Y563780D02*
Y564567D01*
G01Y560630D02*
Y561418D01*
G01X13519Y560837D02*
X13304Y560947D01*
G01X11799Y560837D02*
X11584Y560947D01*
G01X16205Y557984D02*
X15990Y558094D01*
G01X29851Y561276D02*
X29528Y561386D01*
G01X21685Y561276D02*
X21362Y561386D01*
G01X24478Y557984D02*
X24156Y558094D01*
G01X13841Y561276D02*
X13519Y561386D01*
G01X12122Y561276D02*
X11799Y561386D01*
G01X49109Y568701D02*
X49843Y568504D01*
G01X49109Y565552D02*
X49843Y565355D01*
G01X49109Y562402D02*
X49843Y562205D01*
G01X34041Y561276D02*
X33611Y561386D01*
G01X33826Y560837D02*
X33396Y560947D01*
G01X29528Y560837D02*
X29099Y560947D01*
G01X32967Y558313D02*
X32537Y558423D01*
G01X21362Y560837D02*
X20932Y560947D01*
G01X32752Y557874D02*
X32322Y557984D01*
G01X17709Y561276D02*
X17279Y561386D01*
G01X25015Y558313D02*
X24586Y558423D01*
G01X16634D02*
X16205Y558533D01*
G01X16634Y557874D02*
X16205Y557984D01*
G01X55217Y574948D02*
X55193Y574953D01*
G01X55217Y571799D02*
X55193Y571804D01*
G01X55217Y568649D02*
X55193Y568654D01*
G01X55217Y565500D02*
X55193Y565505D01*
G01X55217Y562350D02*
X55193Y562355D01*
G01X55658Y576484D02*
X56175Y576378D01*
G01X55658Y573334D02*
X56175Y573229D01*
G01X55658Y570185D02*
X56175Y570079D01*
G01X55658Y567035D02*
X56175Y566929D01*
G01X55658Y563885D02*
X56175Y563780D01*
G01X55658Y560736D02*
X56175Y560630D01*
G01X53864Y577051D02*
X53270Y577166D01*
G01X53864Y573902D02*
X53270Y574016D01*
G01X53864Y570752D02*
X53270Y570866D01*
G01X53864Y567602D02*
X53270Y567717D01*
G01X53864Y564453D02*
X53270Y564567D01*
G01X53864Y561303D02*
X53270Y561418D01*
G01X53420Y581890D02*
X54319Y581729D01*
G01X53420Y578740D02*
X54319Y578579D01*
G01X53420Y575591D02*
X54319Y575430D01*
G01X53420Y572441D02*
X54319Y572280D01*
G01X53420Y569292D02*
X54319Y569131D01*
G01X53420Y566142D02*
X54319Y565981D01*
G01X53420Y562992D02*
X54319Y562831D01*
G01X25767Y561276D02*
X25123Y561386D01*
G01X25660Y560837D02*
X25015Y560947D01*
G01X25123Y557874D02*
X24478Y557984D01*
G01X56573Y593701D02*
X55417Y593816D01*
G01X56573Y590552D02*
X55417Y590666D01*
G01X56573Y587402D02*
X55417Y587516D01*
G01X56573Y584252D02*
X55417Y584367D01*
G01X56573Y581103D02*
X55417Y581217D01*
G01X56573Y577953D02*
X55417Y578068D01*
G01X56573Y574803D02*
X55417Y574918D01*
G01X56573Y571654D02*
X55417Y571768D01*
G01X56573Y568504D02*
X55417Y568619D01*
G01X56573Y565355D02*
X55417Y565469D01*
G01X56573Y562205D02*
X55417Y562320D01*
G01X76909Y610473D02*
X43307D01*
G01X47500Y610394D02*
X76594D01*
G01X76771Y610335D02*
X67401D01*
G01X49843Y610237D02*
X87126D01*
G01X49843Y609449D02*
X87126D01*
G01X39390D02*
X34468D01*
G01X76771Y609351D02*
X67401D01*
G01X76594Y609292D02*
X47500D01*
G01X76909Y609213D02*
X43307D01*
G01X46063Y609055D02*
X43307D01*
G01X77165D02*
X75197D01*
G01X51771Y608760D02*
X48031D01*
G01X76063D02*
X57677D01*
G01X49325Y608662D02*
X77480D01*
G01X70280Y608465D02*
X72437D01*
G01Y608071D02*
X70280D01*
G01X77480Y607874D02*
X49325D01*
G01X57677Y607776D02*
X76063D01*
G01X48031D02*
X51771D01*
G01X46063Y607481D02*
X60499D01*
G01X43307D02*
X34468D01*
G01X46063D02*
X43307D01*
G01X77165D02*
X75197D01*
G01X76909Y607323D02*
X43307D01*
G01X47500Y607244D02*
X76594D01*
G01X76771Y607185D02*
X67401D01*
G01X49843Y607087D02*
X87126D01*
G01X49843Y606300D02*
X87126D01*
G01X13799D02*
X12094D01*
G01X19441D02*
X17736D01*
G01X76771Y606201D02*
X67401D01*
G01X76594Y606142D02*
X47500D01*
G01X76909Y606063D02*
X43307D01*
G01X46063Y605906D02*
X43307D01*
G01X77165D02*
X75197D01*
G01X51771Y605611D02*
X48031D01*
G01X76063D02*
X57677D01*
G01X49325Y605512D02*
X77480D01*
G01X70280Y605315D02*
X72437D01*
G01Y604922D02*
X70280D01*
G01X77480Y604725D02*
X49325D01*
G01X57677Y604626D02*
X76063D01*
G01X48031D02*
X51771D01*
G01X46063Y604331D02*
X43307D01*
G01X77165D02*
X75197D01*
G01X76909Y604174D02*
X43307D01*
G01X47500Y604095D02*
X76594D01*
G01X76771Y604036D02*
X67401D01*
G01X49843Y603937D02*
X87126D01*
G01X49843Y603150D02*
X87126D01*
G01X76771Y603052D02*
X67401D01*
G01X76594Y602992D02*
X47500D01*
G01X76909Y602914D02*
X43307D01*
G01X46063Y602756D02*
X43307D01*
G01X77165D02*
X75197D01*
G01X51771Y602461D02*
X48031D01*
G01X76063D02*
X57677D01*
G01X49325Y602363D02*
X77480D01*
G01X70280Y602166D02*
X72437D01*
G01Y601772D02*
X70280D01*
G01X49325Y601575D02*
X77480D01*
G01X57677Y601477D02*
X76063D01*
G01X48031D02*
X51771D01*
G01X46063Y601181D02*
X43307D01*
G01X77165D02*
X75197D01*
G01X76909Y601024D02*
X43307D01*
G01X47500Y600945D02*
X76594D01*
G01X76771Y600886D02*
X67401D01*
G01X49843Y600788D02*
X87126D01*
G01X49843Y600000D02*
X87126D01*
G01X76771Y599902D02*
X67401D01*
G01X76594Y599843D02*
X47500D01*
G01X76909Y599764D02*
X43307D01*
G01X46063Y599607D02*
X43307D01*
G01X77165D02*
X75197D01*
G01X51771Y599311D02*
X48031D01*
G01X76063D02*
X57677D01*
G01X49325Y599213D02*
X77480D01*
G01X70280Y599016D02*
X72437D01*
G01Y598622D02*
X70280D01*
G01X77480Y598426D02*
X49325D01*
G01X57677Y598327D02*
X76063D01*
G01X48031D02*
X51771D01*
G01X46063Y598032D02*
X43307D01*
G01X77165D02*
X75197D01*
G01X76909Y597874D02*
X43307D01*
G01X47500Y597796D02*
X76594D01*
G01X76771Y597737D02*
X67401D01*
G01X49843Y597638D02*
X87126D01*
G01X49843Y596851D02*
X87126D01*
G01X76771Y596752D02*
X67401D01*
G01X76594Y596693D02*
X47500D01*
G01X76909Y596615D02*
X43307D01*
G01X46063Y596457D02*
X43307D01*
G01X77165D02*
X75197D01*
G01X51771Y596162D02*
X48031D01*
G01X76063D02*
X57677D01*
G01X49325Y596063D02*
X77480D01*
G01X70280Y595866D02*
X72437D01*
G01Y595473D02*
X70280D01*
G01X77480Y595276D02*
X49325D01*
G01X57677Y595177D02*
X76063D01*
G01X48031D02*
X51771D01*
G01X46063Y594882D02*
X43307D01*
G01X77165D02*
X75197D01*
G01X76909Y594725D02*
X43307D01*
G01X47500Y594646D02*
X76594D01*
G01X76771Y594587D02*
X67401D01*
G01X49843Y594489D02*
X87126D01*
G01X49843Y593701D02*
X87126D01*
G01X76771Y593603D02*
X67401D01*
G01X76594Y593544D02*
X47500D01*
G01X76909Y593465D02*
X43307D01*
G01X46063Y593307D02*
X43307D01*
G01X77165D02*
X75197D01*
G01X51771Y593012D02*
X48031D01*
G01X76063D02*
X57677D01*
G01X49325Y592914D02*
X77480D01*
G01X70280Y592717D02*
X72437D01*
G01Y592323D02*
X70280D01*
G01X49325Y592126D02*
X77480D01*
G01X57677Y592028D02*
X76063D01*
G01X48031D02*
X51771D01*
G01X46063Y591733D02*
X43307D01*
G01X77165D02*
X75197D01*
G01X76909Y591575D02*
X43307D01*
G01X47500Y591496D02*
X76594D01*
G01X76771Y591437D02*
X67401D01*
G01X49843Y591339D02*
X87126D01*
G01X49843Y590552D02*
X87126D01*
G01X76771Y590453D02*
X67401D01*
G01X76594Y590394D02*
X47500D01*
G01X76909Y590315D02*
X43307D01*
G01X46063Y590158D02*
X43307D01*
G01X77165D02*
X75197D01*
G01X51771Y589863D02*
X48031D01*
G01X76063D02*
X57677D01*
G01X49325Y589764D02*
X77480D01*
G01X70280Y589567D02*
X72437D01*
G01Y589174D02*
X70280D01*
G01X77480Y588977D02*
X49325D01*
G01X57677Y588878D02*
X76063D01*
G01X48031D02*
X51771D01*
G01X46063Y588583D02*
X43307D01*
G01X77165D02*
X75197D01*
G01X76909Y588426D02*
X43307D01*
G01X47500Y588347D02*
X76594D01*
G01X76771Y588288D02*
X67401D01*
G01X49843Y588189D02*
X87126D01*
G01X49843Y587402D02*
X87126D01*
G01X76771Y587303D02*
X67401D01*
G01X76594Y587244D02*
X47500D01*
G01X76909Y587166D02*
X43307D01*
G01X46063Y587008D02*
X43307D01*
G01X77165D02*
X75197D01*
G01X51771Y586713D02*
X48031D01*
G01X76063D02*
X57677D01*
G01X49325Y586615D02*
X77480D01*
G01X70280Y586418D02*
X72437D01*
G01Y586024D02*
X70280D01*
G01X77480Y585827D02*
X49325D01*
G01X57677Y585729D02*
X76063D01*
G01X48031D02*
X51771D01*
G01X46063Y585433D02*
X43307D01*
G01X77165D02*
X75197D01*
G01X76909Y585276D02*
X43307D01*
G01X47500Y585197D02*
X76594D01*
G01X76771Y585138D02*
X67401D01*
G01X49843Y585040D02*
X87126D01*
G01X49843Y584252D02*
X87126D01*
G01X76771Y584154D02*
X67401D01*
G01X76594Y584095D02*
X47500D01*
G01X76909Y584016D02*
X43307D01*
G01X46063Y583859D02*
X43307D01*
G01X77165D02*
X75197D01*
G01X51771Y583563D02*
X48031D01*
G01X76063D02*
X57677D01*
G01X49325Y583465D02*
X77480D01*
G01X70280Y583268D02*
X72437D01*
G01Y582874D02*
X70280D01*
G01X77480Y582677D02*
X49325D01*
G01X57677Y582579D02*
X76063D01*
G01X48031D02*
X51771D01*
G01X46063Y582284D02*
X43307D01*
G01X77165D02*
X75197D01*
G01X76909Y582126D02*
X43307D01*
G01X47500Y582048D02*
X76594D01*
G01X76771Y581989D02*
X67401D01*
G01X49843Y581890D02*
X87126D01*
G01X49843Y581103D02*
X87126D01*
G01X76771Y581004D02*
X67401D01*
G01X76594Y580945D02*
X47500D01*
G01X76909Y580866D02*
X43307D01*
G01X46063Y580709D02*
X43307D01*
G01X77165D02*
X75197D01*
G01X51771Y580414D02*
X48031D01*
G01X76063D02*
X57677D01*
G01X49325Y580315D02*
X77480D01*
G01X70280Y580118D02*
X72437D01*
G01Y579725D02*
X70280D01*
G01X77480Y579528D02*
X49325D01*
G01X57677Y579429D02*
X76063D01*
G01X48031D02*
X51771D01*
G01X46063Y579134D02*
X43307D01*
G01X77165D02*
X75197D01*
G01X76909Y578977D02*
X43307D01*
G01X47500Y578898D02*
X76594D01*
G01X76771Y578839D02*
X67401D01*
G01X49843Y578740D02*
X87126D01*
G01X49843Y577953D02*
X87126D01*
G01X76771Y577855D02*
X67401D01*
G01X76594Y577796D02*
X47500D01*
G01X76909Y577717D02*
X43307D01*
G01X46063Y577559D02*
X43307D01*
G01X77165D02*
X75197D01*
G01X51771Y577264D02*
X48031D01*
G01X76063D02*
X57677D01*
G01X49325Y577166D02*
X77480D01*
G01X70280Y576969D02*
X72437D01*
G01Y576575D02*
X70280D01*
G01X77480Y576378D02*
X49325D01*
G01X57677Y576280D02*
X76063D01*
G01X48031D02*
X51771D01*
G01X46063Y575985D02*
X43307D01*
G01X77165D02*
X75197D01*
G01X76909Y575827D02*
X43307D01*
G01X47500Y575748D02*
X76594D01*
G01X76771Y575689D02*
X67401D01*
G01X49843Y575591D02*
X87126D01*
G01X49843Y574803D02*
X87126D01*
G01X76771Y574705D02*
X67401D01*
G01X76594Y574646D02*
X47500D01*
G01X76909Y574567D02*
X43307D01*
G01X46063Y574410D02*
X43307D01*
G01X77165D02*
X75197D01*
G01X51771Y574115D02*
X48031D01*
G01X76063D02*
X57677D01*
G01X49325Y574016D02*
X77480D01*
G01X70280Y573819D02*
X72437D01*
G01Y573426D02*
X70280D01*
G01X77480Y573229D02*
X49325D01*
G01X57677Y573130D02*
X76063D01*
G01X48031D02*
X51771D01*
G01X46063Y572835D02*
X43307D01*
G01X77165D02*
X75197D01*
G01X76909Y572677D02*
X43307D01*
G01X47500Y572599D02*
X76594D01*
G01X76771Y572540D02*
X67401D01*
G01X49843Y572441D02*
X87126D01*
G01X49843Y571654D02*
X87126D01*
G01X76771Y571555D02*
X67401D01*
G01X76594Y571496D02*
X47500D01*
G01X76909Y571418D02*
X43307D01*
G01X46063Y571260D02*
X43307D01*
G01X77165D02*
X75197D01*
G01X51771Y570965D02*
X48031D01*
G01X76063D02*
X57677D01*
G01X49325Y570866D02*
X77480D01*
G01X13799D02*
X12094D01*
G01X19441D02*
X17736D01*
G01X70280Y570670D02*
X72437D01*
G01Y570276D02*
X70280D01*
G01X77480Y570079D02*
X49325D01*
G01X57677Y569981D02*
X76063D01*
G01X48031D02*
X51771D01*
G01X46063Y569685D02*
X60499D01*
G01X43307D02*
X34468D01*
G01X46063D02*
X43307D01*
G01X77165D02*
X75197D01*
G01X76909Y569528D02*
X43307D01*
G01X47500Y569449D02*
X76594D01*
G01X76771Y569390D02*
X67401D01*
G01X49843Y569292D02*
X87126D01*
G01X49843Y568504D02*
X87126D01*
G01X76771Y568406D02*
X67401D01*
G01X76594Y568347D02*
X47500D01*
G01X76909Y568268D02*
X43307D01*
G01X46063Y568111D02*
X43307D01*
G01X77165D02*
X75197D01*
G01X51771Y567815D02*
X48031D01*
G01X76063D02*
X57677D01*
G01X49325Y567717D02*
X77480D01*
G01X39390D02*
X34468D01*
G01X70280Y567520D02*
X72437D01*
G01Y567126D02*
X70280D01*
G01X77480Y566929D02*
X49325D01*
G01X57677Y566831D02*
X76063D01*
G01X48031D02*
X51771D01*
G01X46063Y566536D02*
X43307D01*
G01X77165D02*
X75197D01*
G01X76909Y566378D02*
X43307D01*
G01X47500Y566300D02*
X76594D01*
G01X76771Y566240D02*
X67401D01*
G01X49843Y566142D02*
X87126D01*
G01X49843Y565355D02*
X87126D01*
G01X76771Y565256D02*
X67401D01*
G01X76594Y565197D02*
X47500D01*
G01X43307Y565118D02*
X76909D01*
G01X46063Y564961D02*
X43307D01*
G01X77165D02*
X75197D01*
G01X51771Y564666D02*
X48031D01*
G01X76063D02*
X57677D01*
G01X49325Y564567D02*
X77480D01*
G01X70280Y564370D02*
X72437D01*
G01Y563977D02*
X70280D01*
G01X49325Y563780D02*
X77480D01*
G01X57677Y563681D02*
X76063D01*
G01X48031D02*
X51771D01*
G01X46063Y563386D02*
X43307D01*
G01X77165D02*
X75197D01*
G01X43307Y563229D02*
X76909D01*
G01X47500Y563150D02*
X76594D01*
G01X76771Y563091D02*
X67401D01*
G01X35760Y563032D02*
X36297D01*
G01X19428D02*
X19965D01*
G01X49843Y562992D02*
X87126D01*
G01X49843Y562205D02*
X87126D01*
G01X76771Y562107D02*
X67401D01*
G01X76594Y562048D02*
X47500D01*
G01X43307Y561969D02*
X76909D01*
G01X46063Y561811D02*
X43307D01*
G01X77165D02*
X75197D01*
G01X51771Y561516D02*
X48031D01*
G01X76063D02*
X57677D01*
G01X49325Y561418D02*
X77480D01*
G01X32752Y561386D02*
X33611D01*
G01X29099D02*
X29528D01*
G01X27594D02*
X28132D01*
G01X20932D02*
X21362D01*
G01X16634D02*
X17279D01*
G01X13089D02*
X13519D01*
G01X11370D02*
X11799D01*
G01X15130D02*
X15667D01*
G01X10295D02*
X10832D01*
G01X70280Y561221D02*
X72437D01*
G01X32967Y560947D02*
X33396D01*
G01X11584D02*
X11370D01*
G01X13304D02*
X12981D01*
G01X16634Y560837D02*
X17279D01*
G01X72437Y560827D02*
X70280D01*
G01X77480Y560630D02*
X49325D01*
G01X57677Y560532D02*
X76063D01*
G01X48031D02*
X51771D01*
G01X46063Y560237D02*
X43307D01*
G01X26197Y560069D02*
X23941D01*
G01X47500Y560000D02*
X76594D01*
G01X26735Y559630D02*
X23834D01*
G01X59055Y559587D02*
X43307D01*
G01X51476Y559055D02*
X45177D01*
G01X26197Y558972D02*
X26735D01*
G01X55695Y558800D02*
X53754D01*
G01X17064Y558423D02*
X16634D01*
G01X33396Y558313D02*
X32967D01*
G01X9436Y557874D02*
X8791D01*
G01X10832D02*
X10295D01*
G01X12552D02*
X12014D01*
G01X14271D02*
X13734D01*
G01X17279D02*
X16634D01*
G01X19965D02*
X19428D01*
G01X22437D02*
X21899D01*
G01X28132D02*
X27594D01*
G01X30603D02*
X30065D01*
G01X33611D02*
X32752D01*
G01X36297D02*
X35760D01*
G01X46004Y557481D02*
X67401D01*
G01X44291Y556300D02*
X43996D01*
G01X52756D02*
X44291D01*
G01X77165D02*
X60197D01*
G01X55417Y616421D02*
X56573Y616536D01*
G01X55417Y613272D02*
X56573Y613386D01*
G01X55417Y610122D02*
X56573Y610237D01*
G01X55417Y606972D02*
X56573Y607087D01*
G01X55417Y603823D02*
X56573Y603937D01*
G01X55417Y600673D02*
X56573Y600788D01*
G01X55417Y597524D02*
X56573Y597638D01*
G01X55417Y594374D02*
X56573Y594489D01*
G01X55417Y591224D02*
X56573Y591339D01*
G01X55417Y588075D02*
X56573Y588189D01*
G01X55417Y584925D02*
X56573Y585040D01*
G01X55417Y581776D02*
X56573Y581890D01*
G01X55417Y578626D02*
X56573Y578740D01*
G01X55417Y575476D02*
X56573Y575591D01*
G01X55417Y572327D02*
X56573Y572441D01*
G01X55417Y569177D02*
X56573Y569292D01*
G01X55417Y566027D02*
X56573Y566142D01*
G01X55417Y562878D02*
X56573Y562992D01*
G01X54319Y615909D02*
X53420Y615748D01*
G01X54319Y612760D02*
X53420Y612599D01*
G01X54319Y609610D02*
X53420Y609449D01*
G01X54319Y606461D02*
X53420Y606300D01*
G01X54319Y603311D02*
X53420Y603150D01*
G01X54319Y600161D02*
X53420Y600000D01*
G01X54319Y597012D02*
X53420Y596851D01*
G01X54319Y593862D02*
X53420Y593701D01*
G01X54319Y590713D02*
X53420Y590552D01*
G01X54319Y587563D02*
X53420Y587402D01*
G01X54319Y584413D02*
X53420Y584252D01*
G01X54319Y581264D02*
X53420Y581103D01*
G01X54319Y578114D02*
X53420Y577953D01*
G01X54319Y574965D02*
X53420Y574803D01*
G01X53270Y614174D02*
X53864Y614288D01*
G01X53270Y611024D02*
X53864Y611139D01*
G01X53270Y607874D02*
X53864Y607989D01*
G01X53270Y604725D02*
X53864Y604839D01*
G01X53270Y601575D02*
X53864Y601690D01*
G01X53270Y598426D02*
X53864Y598540D01*
G01X53270Y595276D02*
X53864Y595390D01*
G01X53270Y592126D02*
X53864Y592241D01*
G01X53270Y588977D02*
X53864Y589091D01*
G01X53270Y585827D02*
X53864Y585942D01*
G01X53270Y582677D02*
X53864Y582792D01*
G01X53270Y579528D02*
X53864Y579642D01*
G01X53270Y576378D02*
X53864Y576493D01*
G01X65595Y622835D02*
X60620Y621872D01*
G01X60807Y620906D02*
X65689Y621851D01*
G01X55658Y614855D02*
X56175Y614961D01*
G01X55658Y611706D02*
X56175Y611811D01*
G01X55658Y608556D02*
X56175Y608662D01*
G01X55658Y605407D02*
X56175Y605512D01*
G01X55658Y602257D02*
X56175Y602363D01*
G01X55658Y599107D02*
X56175Y599213D01*
G01X55658Y595958D02*
X56175Y596063D01*
G01X55658Y592808D02*
X56175Y592914D01*
G01X55658Y589659D02*
X56175Y589764D01*
G01X55658Y586509D02*
X56175Y586615D01*
G01X55658Y583359D02*
X56175Y583465D01*
G01X55658Y580210D02*
X56175Y580315D01*
G01X55193Y616386D02*
X55217Y616391D01*
G01X55193Y613236D02*
X55217Y613241D01*
G01X55193Y610087D02*
X55217Y610092D01*
G01X55193Y606937D02*
X55217Y606942D01*
G01X55193Y603787D02*
X55217Y603792D01*
G01X55193Y600638D02*
X55217Y600643D01*
G01X55193Y597488D02*
X55217Y597493D01*
G01X55193Y594339D02*
X55217Y594344D01*
G01X55193Y591189D02*
X55217Y591194D01*
G01X55193Y588039D02*
X55217Y588044D01*
G01X55193Y584890D02*
X55217Y584895D01*
G01X55193Y581740D02*
X55217Y581745D01*
G01X49108Y616339D02*
X49843Y616536D01*
G01X49108Y613189D02*
X49843Y613386D01*
G01X49109Y610040D02*
X49843Y610237D01*
G01X49109Y606890D02*
X49843Y607087D01*
G01X49108Y603740D02*
X49843Y603937D01*
G01X49108Y600591D02*
X49843Y600788D01*
G01X49109Y597441D02*
X49843Y597638D01*
G01X49109Y594292D02*
X49843Y594489D01*
G01X49109Y591142D02*
X49843Y591339D01*
G01X24049Y560398D02*
X23941Y560179D01*
G01X23619Y560727D02*
X23404Y560289D01*
G01X17924Y558972D02*
X17817Y558752D01*
G01X73449Y560532D02*
X73228Y560000D01*
G01X73449Y563681D02*
X73228Y563150D01*
G01X73449Y566831D02*
X73228Y566300D01*
G01X73449Y569981D02*
X73228Y569449D01*
G01X73449Y573130D02*
X73228Y572599D01*
G01X73449Y576280D02*
X73228Y575748D01*
G01X73449Y579429D02*
X73228Y578898D01*
G01X73449Y582579D02*
X73228Y582048D01*
G01X73449Y585729D02*
X73228Y585197D01*
G01X73449Y588878D02*
X73228Y588347D01*
G01X73449Y592028D02*
X73228Y591496D01*
G01X73449Y595177D02*
X73228Y594646D01*
G01X73449Y598327D02*
X73228Y597796D01*
G01X73449Y601477D02*
X73228Y600945D01*
G01X73449Y604626D02*
X73228Y604095D01*
G01X73449Y607776D02*
X73228Y607244D01*
G01X73449Y610926D02*
X73228Y610394D01*
G01X73449Y614075D02*
X73228Y613544D01*
G01X31677Y560618D02*
X31570Y560289D01*
G01X26197Y558972D02*
X26090Y558642D01*
G01X18031Y559301D02*
X17924Y558972D01*
G01X34901Y559411D02*
X34686Y558642D01*
G01X34364Y559411D02*
X34256Y558972D01*
G01X32107Y560289D02*
X32000Y559850D01*
G01X31570Y560289D02*
X31462Y559850D01*
G01X26735Y558972D02*
X26627Y558533D01*
G01X18569Y559191D02*
X18461Y558752D01*
G01X23404Y560289D02*
X23296Y559630D01*
G01X29350Y623130D02*
Y624115D01*
G01X28366D02*
Y623130D01*
G01X28132Y560398D02*
Y557874D01*
G01Y561386D02*
Y560837D01*
G01X27594Y557874D02*
Y561386D01*
G01X26735Y560069D02*
Y559630D01*
G01X26197Y560289D02*
Y560069D01*
G01X23941D02*
Y560179D01*
G01X23834Y559630D02*
Y559411D01*
G01X22437Y560069D02*
Y557874D01*
G01X21899D02*
Y560069D01*
G01X20984Y623130D02*
Y624115D01*
G01X19965Y560398D02*
Y557874D01*
G01Y563032D02*
Y560837D01*
G01X19803Y624115D02*
Y623130D01*
G01X19697Y624115D02*
Y623130D01*
G01X19441Y606300D02*
Y570866D01*
G01X19428Y557874D02*
Y563032D01*
G01X19402Y623130D02*
Y624115D01*
G01X18588Y606300D02*
Y570866D01*
G01X18569Y560069D02*
Y559191D01*
G01X18038Y624115D02*
Y623130D01*
G01X18031Y559959D02*
Y559301D01*
G01X17743Y623130D02*
Y624115D01*
G01X17736Y570866D02*
Y606300D01*
G01X17638Y624115D02*
Y623130D01*
G01X16456Y624115D02*
Y623130D01*
G01X15667Y559081D02*
Y560179D01*
G01Y561386D02*
Y560727D01*
G01X14271Y560508D02*
Y557874D01*
G01X13799Y606300D02*
Y570866D01*
G01X13734Y557874D02*
Y560508D01*
G01X13110Y623130D02*
Y624115D01*
G01X12947Y570866D02*
Y606300D01*
G01X12552Y560508D02*
Y557874D01*
G01X12094Y606300D02*
Y570866D01*
G01X12014Y557874D02*
Y560508D01*
G01X11929Y624115D02*
Y623130D01*
G01X11823Y624115D02*
Y623130D01*
G01X11528D02*
Y624115D01*
G01X10832Y560618D02*
Y557874D01*
G01Y561386D02*
Y561057D01*
G01X10295Y557874D02*
Y561386D01*
G01X10177Y624115D02*
Y623130D01*
G01X10164Y624115D02*
Y623130D01*
G01X9869D02*
Y624115D01*
G01X9764D02*
Y623130D01*
G01X8878Y581201D02*
Y574390D01*
G01Y602776D02*
Y595965D01*
G01X8582Y624115D02*
Y623130D01*
G01X7815Y624115D02*
Y623130D01*
G01X25767Y558423D02*
X25015Y558313D01*
G01X25875Y557984D02*
X25123Y557874D01*
G01Y561386D02*
X24478Y561276D01*
G01X54319Y571815D02*
X53420Y571654D01*
G01X54319Y568665D02*
X53420Y568504D01*
G01X54319Y565516D02*
X53420Y565355D01*
G01X54319Y562366D02*
X53420Y562205D01*
G01X53270Y573229D02*
X53864Y573343D01*
G01X53270Y570079D02*
X53864Y570194D01*
G01X53270Y566929D02*
X53864Y567044D01*
G01X53270Y563780D02*
X53864Y563894D01*
G01X53270Y560630D02*
X53864Y560745D01*
G01X55658Y577060D02*
X56175Y577166D01*
G01X55658Y573911D02*
X56175Y574016D01*
G01X55658Y570761D02*
X56175Y570866D01*
G01X55658Y567611D02*
X56175Y567717D01*
G01X55658Y564462D02*
X56175Y564567D01*
G01X55658Y561312D02*
X56175Y561418D01*
G01X55193Y578590D02*
X55217Y578596D01*
G01X55193Y575441D02*
X55217Y575446D01*
G01X55193Y572291D02*
X55217Y572296D01*
G01X55193Y569142D02*
X55217Y569147D01*
G01X55193Y565992D02*
X55217Y565997D01*
G01X55193Y562842D02*
X55217Y562848D01*
G01X16634Y561386D02*
X16205Y561276D01*
G01X16634Y560837D02*
X16205Y560727D01*
G01X20932Y561386D02*
X20503Y561276D01*
G01X20932Y560947D02*
X20503Y560837D01*
G01X25015Y560947D02*
X24586Y560837D01*
G01X17494Y558533D02*
X17064Y558423D01*
G01X29099Y561386D02*
X28669Y561276D01*
G01X29099Y560947D02*
X28669Y560837D01*
G01X17709Y557984D02*
X17279Y557874D01*
G01X32752Y561386D02*
X32322Y561276D01*
G01X32967Y560947D02*
X32537Y560837D01*
G01X33826Y558423D02*
X33396Y558313D01*
G01X34041Y557984D02*
X33611Y557874D01*
G01X49109Y587992D02*
X49843Y588189D01*
G01X49109Y584843D02*
X49843Y585040D01*
G01X49109Y581693D02*
X49843Y581890D01*
G01X49109Y578544D02*
X49843Y578740D01*
G01X49109Y575394D02*
X49843Y575591D01*
G01X49109Y572244D02*
X49843Y572441D01*
G01X49109Y569095D02*
X49843Y569292D01*
G01X49109Y565945D02*
X49843Y566142D01*
G01X49109Y562796D02*
X49843Y562992D01*
G01X76594Y562048D02*
X76063Y561516D01*
G01X77165Y563485D02*
X76771Y563091D01*
G01X72972Y560532D02*
X72441Y560000D01*
G01D02*
X72972Y560532D01*
G01X76594Y565197D02*
X76063Y564666D01*
G01X72693Y561306D02*
X72795Y561409D01*
G01X77165Y566634D02*
X76771Y566240D01*
G01X72972Y563681D02*
X72441Y563150D01*
G01D02*
X72972Y563681D01*
G01X70024Y560742D02*
X69921Y560639D01*
G01X76594Y568347D02*
X76063Y567815D01*
G01X72693Y564455D02*
X72795Y564558D01*
G01X77165Y569784D02*
X76771Y569390D01*
G01X72972Y566831D02*
X72441Y566300D01*
G01D02*
X72972Y566831D01*
G01X70024Y563891D02*
X69921Y563789D01*
G01X76594Y571496D02*
X76063Y570965D01*
G01X72693Y567605D02*
X72795Y567708D01*
G01X77165Y572933D02*
X76771Y572540D01*
G01X72972Y569981D02*
X72441Y569449D01*
G01D02*
X72972Y569981D01*
G01X70024Y567041D02*
X69921Y566939D01*
G01X76594Y574646D02*
X76063Y574115D01*
G01X72693Y570755D02*
X72795Y570857D01*
G01X77165Y576083D02*
X76771Y575689D01*
G01X72972Y573130D02*
X72441Y572599D01*
G01D02*
X72972Y573130D01*
G01X70024Y570190D02*
X69921Y570088D01*
G01X76594Y577796D02*
X76063Y577264D01*
G01X72693Y573904D02*
X72795Y574007D01*
G01X77165Y579233D02*
X76771Y578839D01*
G01X72972Y576280D02*
X72441Y575748D01*
G01D02*
X72972Y576280D01*
G01X70024Y573340D02*
X69921Y573238D01*
G01X76594Y580945D02*
X76063Y580414D01*
G01X72693Y577054D02*
X72795Y577157D01*
G01X77165Y582382D02*
X76771Y581989D01*
G01X72972Y579429D02*
X72441Y578898D01*
G01D02*
X72972Y579429D01*
G01X70024Y576490D02*
X69921Y576387D01*
G01X76594Y584095D02*
X76063Y583563D01*
G01X72693Y580203D02*
X72795Y580306D01*
G01X77165Y585532D02*
X76771Y585138D01*
G01X72972Y582579D02*
X72441Y582048D01*
G01D02*
X72972Y582579D01*
G01X70024Y579639D02*
X69921Y579537D01*
G01X76594Y587244D02*
X76063Y586713D01*
G01X72693Y583353D02*
X72795Y583456D01*
G01X77165Y588681D02*
X76771Y588288D01*
G01X48031Y560532D02*
X47500Y560000D01*
G01X72972Y585729D02*
X72441Y585197D01*
G01D02*
X72972Y585729D01*
G01X70024Y582789D02*
X69921Y582687D01*
G01X76594Y590394D02*
X76063Y589863D01*
G01X72693Y586503D02*
X72795Y586605D01*
G01X77165Y591831D02*
X76771Y591437D01*
G01X48031Y563681D02*
X47500Y563150D01*
G01X72972Y588878D02*
X72441Y588347D01*
G01D02*
X72972Y588878D01*
G01X70024Y585939D02*
X69921Y585836D01*
G01X76594Y593544D02*
X76063Y593012D01*
G01X72693Y589652D02*
X72795Y589755D01*
G01X77165Y594981D02*
X76771Y594587D01*
G01X48031Y566831D02*
X47500Y566300D01*
G01X72972Y592028D02*
X72441Y591496D01*
G01D02*
X72972Y592028D01*
G01X70024Y589088D02*
X69921Y588986D01*
G01X76594Y596693D02*
X76063Y596162D01*
G01X72693Y592802D02*
X72795Y592905D01*
G01X77165Y598130D02*
X76771Y597737D01*
G01X48031Y569981D02*
X47500Y569449D01*
G01X72972Y595177D02*
X72441Y594646D01*
G01D02*
X72972Y595177D01*
G01X70024Y592238D02*
X69921Y592135D01*
G01X76594Y599843D02*
X76063Y599311D01*
G01X72693Y595952D02*
X72795Y596054D01*
G01X77165Y601280D02*
X76771Y600886D01*
G01X48031Y573130D02*
X47500Y572599D01*
G01X72972Y598327D02*
X72441Y597796D01*
G01D02*
X72972Y598327D01*
G01X70024Y595387D02*
X69921Y595285D01*
G01X76594Y602992D02*
X76063Y602461D01*
G01X72693Y599101D02*
X72795Y599204D01*
G01X77165Y604429D02*
X76771Y604036D01*
G01X48031Y576280D02*
X47500Y575748D01*
G01X72972Y601477D02*
X72441Y600945D01*
G01D02*
X72972Y601477D01*
G01X70024Y598537D02*
X69921Y598435D01*
G01X76594Y606142D02*
X76063Y605611D01*
G01X72693Y602251D02*
X72795Y602353D01*
G01X77165Y607579D02*
X76771Y607185D01*
G01X48031Y579429D02*
X47500Y578898D01*
G01X72972Y604626D02*
X72441Y604095D01*
G01D02*
X72972Y604626D01*
G01X70024Y601687D02*
X69921Y601584D01*
G01X76594Y609292D02*
X76063Y608760D01*
G01X72693Y605400D02*
X72795Y605503D01*
G01X77165Y610729D02*
X76771Y610335D01*
G01X48031Y582579D02*
X47500Y582048D01*
G01X72972Y607776D02*
X72441Y607244D01*
G01D02*
X72972Y607776D01*
G01X70024Y604836D02*
X69921Y604734D01*
G01X76594Y612441D02*
X76063Y611910D01*
G01X72693Y608550D02*
X72795Y608653D01*
G01X77165Y613878D02*
X76771Y613485D01*
G01X48031Y585729D02*
X47500Y585197D01*
G01X72972Y610926D02*
X72441Y610394D01*
G01D02*
X72972Y610926D01*
G01X70024Y607986D02*
X69921Y607883D01*
G01X76594Y615591D02*
X76063Y615059D01*
G01X72693Y611700D02*
X72795Y611802D01*
G01X77165Y617028D02*
X76771Y616634D01*
G01X48031Y588878D02*
X47500Y588347D01*
G01X72972Y614075D02*
X72441Y613544D01*
G01D02*
X72972Y614075D01*
G01X70024Y611135D02*
X69921Y611033D01*
G01X72693Y614849D02*
X72795Y614952D01*
G01X48031Y592028D02*
X47500Y591496D01*
G01X70024Y614285D02*
X69921Y614183D01*
G01X48031Y595177D02*
X47500Y594646D01*
G01X48031Y598327D02*
X47500Y597796D01*
G01X48031Y601477D02*
X47500Y600945D01*
G01X48031Y604626D02*
X47500Y604095D01*
G01X48031Y607776D02*
X47500Y607244D01*
G01X48031Y610926D02*
X47500Y610394D01*
G01X48031Y614075D02*
X47500Y613544D01*
G01X34471Y558313D02*
X34256Y558094D01*
G01X34041Y558642D02*
X33826Y558423D01*
G01X32537Y560837D02*
X32322Y560618D01*
G01X32107Y561166D02*
X31892Y560947D01*
G01X26627Y558533D02*
X26305Y558203D01*
G01X28346Y560618D02*
X28132Y560398D01*
G01X28346Y561057D02*
X28132Y560837D01*
G01X24371Y560727D02*
X24049Y560398D01*
G01X23834Y560947D02*
X23619Y560727D01*
G01X20180Y560618D02*
X19965Y560398D01*
G01X20180Y561057D02*
X19965Y560837D01*
G01X15990Y561166D02*
X15775Y560947D01*
G01X12766Y560837D02*
X12659Y560727D01*
G01X12766Y561276D02*
X12444Y560947D01*
G01X11047Y560837D02*
X10832Y560618D01*
G01X11047Y561276D02*
X10832Y561057D01*
G01X18461Y558752D02*
X18031Y558203D01*
G01X34686Y558642D02*
X34471Y558313D01*
G01X34256Y558972D02*
X34041Y558642D01*
G01X32322Y560618D02*
X32107Y560289D01*
G01X31892Y560947D02*
X31677Y560618D01*
G01X15882Y560508D02*
X15667Y560179D01*
G01X13553Y622221D02*
X13045Y621377D01*
G01X11865Y623235D02*
X11358Y622391D01*
G01X15775Y560947D02*
X15667Y560727D01*
G01X12659D02*
X12552Y560508D01*
G01X24478Y561276D02*
X24156Y561166D01*
G01X13089Y561386D02*
X12766Y561276D01*
G01X11370Y560947D02*
X11047Y560837D01*
G01X11370Y561386D02*
X11047Y561276D01*
G01X34256Y558094D02*
X34041Y557984D01*
G01X26305Y558203D02*
X25875Y557984D01*
G01X32322Y561276D02*
X32107Y561166D01*
G01X24586Y560837D02*
X24371Y560727D01*
G01X16205Y561276D02*
X15990Y561166D01*
G01X12981Y560947D02*
X12766Y560837D01*
G01X26090Y558642D02*
X25767Y558423D01*
G01X28669Y560837D02*
X28346Y560618D01*
G01X28669Y561276D02*
X28346Y561057D01*
G01X24156Y561166D02*
X23834Y560947D01*
G01X18031Y558203D02*
X17709Y557984D01*
G01X17817Y558752D02*
X17494Y558533D01*
G01X20503Y560837D02*
X20180Y560618D01*
G01X20503Y561276D02*
X20180Y561057D01*
G01X16205Y560727D02*
X15882Y560508D01*
G01X17582Y622312D02*
X16383Y621113D01*
G01X16886Y623008D02*
X15687Y621809D01*
G01X55758Y677156D02*
X55695Y676910D01*
G01X55821Y677418D02*
X55758Y677156D01*
G01X55884Y677697D02*
X55821Y677418D01*
G01X53627Y677424D02*
X53565Y677697D01*
G01X53689Y677163D02*
X53627Y677424D01*
G01X53754Y676910D02*
X53689Y677163D01*
G01X52657Y675985D02*
G03X51476Y677166I-1181J0D01*
G01X53754Y676910D02*
G03X55695I970J-1713D01*
G01X53565Y677697D02*
G03X55884I1160J-2500D01*
G01X57795Y675197D02*
G03I-3071J0D01*
G01X43484Y673426D02*
G03X43174Y673376I0J-985D01*
G01X45177Y677166D02*
G03X43996Y675985I0J-1181D01*
G01X43802Y672441D02*
G03X43182Y672341I-1J-1968D01*
G01X34468Y687796D02*
G03Y685827I0J-985D01*
G01X33779Y671654D02*
G03I-1575J0D01*
G01X39390Y671163D02*
G03X39928Y671262I-84J1967D01*
G01X8090Y691713D02*
G03X8878Y692500I1J787D01*
G01X17582Y672965D02*
G03X18226Y672677I697J695D01*
G01X15687Y673467D02*
G03X14484Y673615I-696J-696D01*
G01X20000Y671654D02*
G03I-1575J0D01*
G01X13799Y688977D02*
G03X17736I1969J0D01*
G01X16383Y674163D02*
G03X13977Y674459I-1392J-1391D01*
G01X16886Y672268D02*
G03X18175Y671694I1392J1392D01*
G01X12947Y688977D02*
G03X18588I2821J0D01*
G01X12094D02*
G03X19441I3674J0D01*
G01X27721Y654685D02*
G03X27131Y654095I0J-590D01*
G01X27362Y637244D02*
G03X27953Y636654I590J0D01*
G01X27362Y642363D02*
G03X26771Y642953I-591J-1D01*
G01X21260Y648386D02*
G03X21063Y648189I0J-197D01*
G01Y646851D02*
G03X21260Y646654I197J0D01*
G01Y644685D02*
G03X21063Y644489I0J-197D01*
G01Y643150D02*
G03X21260Y642953I197J0D01*
G01X77165Y695571D02*
X76771Y695965D01*
G01X76063Y694390D02*
X76594Y693859D01*
G01X77165Y692422D02*
X76771Y692815D01*
G01X72441Y695906D02*
X72972Y695374D01*
G01X76063Y691240D02*
X76594Y690709D01*
G01X72693Y694600D02*
X72795Y694498D01*
G01X77165Y689272D02*
X76771Y689666D01*
G01X72441Y692756D02*
X72972Y692225D01*
G01X69921Y695267D02*
X70024Y695164D01*
G01X76063Y688091D02*
X76594Y687559D01*
G01X72693Y691450D02*
X72795Y691348D01*
G01X77165Y686122D02*
X76771Y686516D01*
G01X72441Y689607D02*
X72972Y689075D01*
G01X69921Y692117D02*
X70024Y692015D01*
G01X76063Y684941D02*
X76594Y684410D01*
G01X72693Y688301D02*
X72795Y688198D01*
G01X77165Y682973D02*
X76771Y683366D01*
G01X72441Y686457D02*
X72972Y685926D01*
G01X69921Y688968D02*
X70024Y688865D01*
G01X76063Y681792D02*
X76594Y681260D01*
G01X72693Y685151D02*
X72795Y685049D01*
G01X77165Y679823D02*
X76771Y680217D01*
G01X72441Y683307D02*
X72972Y682776D01*
G01X69921Y685818D02*
X70024Y685715D01*
G01X76063Y678642D02*
X76594Y678111D01*
G01X72693Y682002D02*
X72795Y681899D01*
G01X72441Y680158D02*
X72972Y679626D01*
G01X69921Y682668D02*
X70024Y682566D01*
G01X72693Y678852D02*
X72795Y678750D01*
G01X73228Y695906D02*
X73449Y695374D01*
G01X73228Y692756D02*
X73449Y692225D01*
G01X73228Y689607D02*
X73449Y689075D01*
G01X73228Y686457D02*
X73449Y685926D01*
G01X73228Y683307D02*
X73449Y682776D01*
G01X73228Y680158D02*
X73449Y679626D01*
G01X23941Y677192D02*
X24049Y676972D01*
G01X23404Y677082D02*
X23619Y676643D01*
G01X22222Y678947D02*
X22329Y678728D01*
G01X18354Y678838D02*
X18461Y678618D01*
G01X38582Y650788D02*
X40551Y647244D01*
G01X13045Y673899D02*
X13553Y673055D01*
G01X11358Y672885D02*
X11865Y672042D01*
G01X34471Y679057D02*
X34686Y678728D01*
G01X34041D02*
X34256Y678399D01*
G01X32107Y677082D02*
X32322Y676753D01*
G01X31677D02*
X31892Y676424D01*
G01X25982Y678728D02*
X26197Y678399D01*
G01X17709Y678728D02*
X17924Y678399D01*
G01X15667Y677192D02*
X15882Y676863D01*
G01X26305Y679057D02*
X26627Y678618D01*
G01X38582Y639607D02*
X40551Y637244D01*
G01X34471Y679057D02*
X34256Y679277D01*
G01X34041Y678728D02*
X33826Y678947D01*
G01X30388D02*
X30173Y679167D01*
G01X32537Y676533D02*
X32322Y676753D01*
G01X29958Y678618D02*
X29743Y678838D01*
G01X32107Y676204D02*
X31892Y676424D01*
G01X22222Y678947D02*
X22007Y679167D01*
G01X24371Y676643D02*
X24049Y676972D01*
G01X21792Y678618D02*
X21577Y678838D01*
G01X23834Y676424D02*
X23619Y676643D01*
G01X18354Y678838D02*
X18031Y679167D01*
G01X14056D02*
X13841Y679386D01*
G01X13626Y678838D02*
X13519Y678947D01*
G01X15990Y676204D02*
X15775Y676424D01*
G01X12444Y679057D02*
X12122Y679386D01*
G01X11907Y678838D02*
X11799Y678947D01*
G01X69921Y679519D02*
X70024Y679416D01*
G01X48031Y695374D02*
X47500Y695906D01*
G01X48031Y692225D02*
X47500Y692756D01*
G01X48031Y689075D02*
X47500Y689607D01*
G01X48031Y685926D02*
X47500Y686457D01*
G01X48031Y682776D02*
X47500Y683307D01*
G01X48031Y679626D02*
X47500Y680158D01*
G01X17582Y672965D02*
X16383Y674163D01*
G01X16886Y672268D02*
X15687Y673467D01*
G01X42227Y636063D02*
X42519Y635817D01*
G01X42184D02*
X41891Y636063D01*
G01X30173Y679167D02*
X29851Y679386D01*
G01X25982Y678728D02*
X25660Y678947D01*
G01X22007Y679167D02*
X21685Y679386D01*
G01X24156Y676204D02*
X23834Y676424D01*
G01X18031Y679167D02*
X17709Y679386D01*
G01X16205Y676643D02*
X15882Y676863D01*
G01X26305Y679057D02*
X25767Y679386D01*
G01X34256Y679277D02*
X34041Y679386D01*
G01X29743Y678838D02*
X29528Y678947D01*
G01X32322Y676094D02*
X32107Y676204D01*
G01X21577Y678838D02*
X21362Y678947D01*
G01X24586Y676533D02*
X24371Y676643D01*
G01X17709Y678728D02*
X17279Y678947D01*
G01X13519D02*
X13304Y679057D01*
G01X11799Y678947D02*
X11584Y679057D01*
G01X16205Y676094D02*
X15990Y676204D01*
G01X29851Y679386D02*
X29528Y679496D01*
G01X21685Y679386D02*
X21362Y679496D01*
G01X24478Y676094D02*
X24156Y676204D01*
G01X13841Y679386D02*
X13519Y679496D01*
G01X12122Y679386D02*
X11799Y679496D01*
G01X49109Y696260D02*
X49843Y696063D01*
G01X49109Y693111D02*
X49843Y692914D01*
G01X49109Y689961D02*
X49843Y689764D01*
G01X49109Y686811D02*
X49843Y686615D01*
G01X49109Y683662D02*
X49843Y683465D01*
G01X49109Y680512D02*
X49843Y680315D01*
G01X34041Y679386D02*
X33611Y679496D01*
G01X33826Y678947D02*
X33396Y679057D01*
G01X29528Y678947D02*
X29099Y679057D01*
G01X32967Y676424D02*
X32537Y676533D01*
G01X21362Y678947D02*
X20932Y679057D01*
G01X32752Y675985D02*
X32322Y676094D01*
G01X17709Y679386D02*
X17279Y679496D01*
G01X25015Y676424D02*
X24586Y676533D01*
G01X16634D02*
X16205Y676643D01*
G01X16634Y675985D02*
X16205Y676094D01*
G01X55217Y696208D02*
X55193Y696213D01*
G01X55217Y693059D02*
X55193Y693064D01*
G01X55217Y689909D02*
X55193Y689914D01*
G01X55217Y686759D02*
X55193Y686765D01*
G01X55217Y683610D02*
X55193Y683615D01*
G01X55217Y680460D02*
X55193Y680465D01*
G01X55658Y694594D02*
X56175Y694489D01*
G01X55658Y691444D02*
X56175Y691339D01*
G01X55658Y688295D02*
X56175Y688189D01*
G01X55658Y685145D02*
X56175Y685040D01*
G01X55658Y681996D02*
X56175Y681890D01*
G01X55658Y678846D02*
X56175Y678740D01*
G01X65689Y673426D02*
X60807Y674370D01*
G01X65595Y672441D02*
X60620Y673404D01*
G01X53864Y695161D02*
X53270Y695276D01*
G01X53864Y692012D02*
X53270Y692126D01*
G01X53864Y688862D02*
X53270Y688977D01*
G01X53864Y685713D02*
X53270Y685827D01*
G01X53864Y682563D02*
X53270Y682677D01*
G01X53864Y679413D02*
X53270Y679528D01*
G01X53420Y696851D02*
X54319Y696690D01*
G01X53420Y693701D02*
X54319Y693540D01*
G01X53420Y690552D02*
X54319Y690390D01*
G01X53420Y687402D02*
X54319Y687241D01*
G01X53420Y684252D02*
X54319Y684091D01*
G01X53420Y681103D02*
X54319Y680942D01*
G01X25767Y679386D02*
X25123Y679496D01*
G01X25660Y678947D02*
X25015Y679057D01*
G01X25123Y675985D02*
X24478Y676094D01*
G01X56573Y696063D02*
X55417Y696178D01*
G01X56573Y692914D02*
X55417Y693028D01*
G01X56573Y689764D02*
X55417Y689879D01*
G01X56573Y686615D02*
X55417Y686729D01*
G01X56573Y683465D02*
X55417Y683579D01*
G01X56573Y680315D02*
X55417Y680430D01*
G01X76771Y696949D02*
X67401D01*
G01X49843Y696851D02*
X87126D01*
G01X49843Y696063D02*
X87126D01*
G01X76771Y695965D02*
X67401D01*
G01X76594Y695906D02*
X47500D01*
G01X76909Y695827D02*
X43307D01*
G01X46063Y695670D02*
X43307D01*
G01X77165D02*
X75197D01*
G01X51771Y695374D02*
X48031D01*
G01X76063D02*
X57677D01*
G01X49325Y695276D02*
X77480D01*
G01X70280Y695079D02*
X72437D01*
G01Y694685D02*
X70280D01*
G01X77480Y694489D02*
X49325D01*
G01X57677Y694390D02*
X76063D01*
G01X48031D02*
X51771D01*
G01X46063Y694095D02*
X43307D01*
G01X77165D02*
X75197D01*
G01X76909Y693937D02*
X43307D01*
G01X47500Y693859D02*
X76594D01*
G01X76771Y693800D02*
X67401D01*
G01X49843Y693701D02*
X87126D01*
G01X49843Y692914D02*
X87126D01*
G01X76771Y692815D02*
X67401D01*
G01X76594Y692756D02*
X47500D01*
G01X76909Y692677D02*
X43307D01*
G01X46063Y692520D02*
X43307D01*
G01X77165D02*
X75197D01*
G01X51771Y692225D02*
X48031D01*
G01X76063D02*
X57677D01*
G01X49325Y692126D02*
X77480D01*
G01X70280Y691929D02*
X72437D01*
G01Y691536D02*
X70280D01*
G01X77480Y691339D02*
X49325D01*
G01X57677Y691240D02*
X76063D01*
G01X48031D02*
X51771D01*
G01X46063Y690945D02*
X43307D01*
G01X77165D02*
X75197D01*
G01X76909Y690788D02*
X43307D01*
G01X47500Y690709D02*
X76594D01*
G01X76771Y690650D02*
X67401D01*
G01X49843Y690552D02*
X87126D01*
G01X49843Y689764D02*
X87126D01*
G01X76771Y689666D02*
X67401D01*
G01X76594Y689607D02*
X47500D01*
G01X76909Y689528D02*
X43307D01*
G01X46063Y689370D02*
X43307D01*
G01X77165D02*
X75197D01*
G01X51771Y689075D02*
X48031D01*
G01X76063D02*
X57677D01*
G01X49325Y688977D02*
X77480D01*
G01X13799D02*
X12094D01*
G01X19441D02*
X17736D01*
G01X70280Y688780D02*
X72437D01*
G01Y688386D02*
X70280D01*
G01X77480Y688189D02*
X49325D01*
G01X57677Y688091D02*
X76063D01*
G01X48031D02*
X51771D01*
G01X46063Y687796D02*
X60499D01*
G01X43307D02*
X34468D01*
G01X46063D02*
X43307D01*
G01X77165D02*
X75197D01*
G01X76909Y687638D02*
X43307D01*
G01X47500Y687559D02*
X76594D01*
G01X76771Y687500D02*
X67401D01*
G01X49843Y687402D02*
X87126D01*
G01X49843Y686615D02*
X87126D01*
G01X76771Y686516D02*
X67401D01*
G01X76594Y686457D02*
X47500D01*
G01X76909Y686378D02*
X43307D01*
G01X46063Y686221D02*
X43307D01*
G01X77165D02*
X75197D01*
G01X51771Y685926D02*
X48031D01*
G01X76063D02*
X57677D01*
G01X49325Y685827D02*
X77480D01*
G01X39390D02*
X34468D01*
G01X70280Y685630D02*
X72437D01*
G01Y685237D02*
X70280D01*
G01X77480Y685040D02*
X49325D01*
G01X57677Y684941D02*
X76063D01*
G01X48031D02*
X51771D01*
G01X46063Y684646D02*
X43307D01*
G01X77165D02*
X75197D01*
G01X76909Y684489D02*
X43307D01*
G01X47500Y684410D02*
X76594D01*
G01X76771Y684351D02*
X67401D01*
G01X49843Y684252D02*
X87126D01*
G01X49843Y683465D02*
X87126D01*
G01X76771Y683366D02*
X67401D01*
G01X76594Y683307D02*
X47500D01*
G01X43307Y683229D02*
X76909D01*
G01X46063Y683071D02*
X43307D01*
G01X77165D02*
X75197D01*
G01X51771Y682776D02*
X48031D01*
G01X76063D02*
X57677D01*
G01X49325Y682677D02*
X77480D01*
G01X70280Y682481D02*
X72437D01*
G01Y682087D02*
X70280D01*
G01X49325Y681890D02*
X77480D01*
G01X57677Y681792D02*
X76063D01*
G01X48031D02*
X51771D01*
G01X46063Y681496D02*
X43307D01*
G01X77165D02*
X75197D01*
G01X43307Y681339D02*
X76909D01*
G01X47500Y681260D02*
X76594D01*
G01X76771Y681201D02*
X67401D01*
G01X35760Y681142D02*
X36297D01*
G01X19428D02*
X19965D01*
G01X49843Y681103D02*
X87126D01*
G01X49843Y680315D02*
X87126D01*
G01X76771Y680217D02*
X67401D01*
G01X76594Y680158D02*
X47500D01*
G01X43307Y680079D02*
X76909D01*
G01X23296Y677740D02*
X23404Y677082D01*
G01X30495Y678618D02*
X30603Y678070D01*
G01X29958Y678618D02*
X30065Y678070D01*
G01X22329Y678728D02*
X22437Y678179D01*
G01X34793Y678399D02*
X34901Y677960D01*
G01X34256Y678399D02*
X34364Y677960D01*
G01X32000Y677521D02*
X32107Y677082D01*
G01X26627Y678618D02*
X26735Y678179D01*
G01X21792Y678618D02*
X21899Y678179D01*
G01X18461Y678618D02*
X18569Y678179D01*
G01X31462Y677521D02*
X31677Y676753D01*
G01X34686Y678728D02*
X34793Y678399D01*
G01X30388Y678947D02*
X30495Y678618D01*
G01X23834Y677521D02*
X23941Y677192D01*
G01X17924Y678399D02*
X18031Y678070D01*
G01X8361Y677302D02*
X8791Y675985D01*
G01X7716Y681142D02*
X9436Y675985D01*
G01X14056Y679167D02*
X14271Y678618D01*
G01X23897Y634685D02*
X21063Y641199D01*
G01X15667Y676643D02*
X15775Y676424D01*
G01X13626Y678838D02*
X13734Y678618D01*
G01X11907Y678838D02*
X12014Y678618D01*
G01X28366Y672146D02*
X18226Y672677D01*
G01X28340Y671162D02*
X18175Y671694D01*
G01X46063Y679922D02*
X43307D01*
G01X77165D02*
X75197D01*
G01X51771Y679626D02*
X48031D01*
G01X76063D02*
X57677D01*
G01X49325Y679528D02*
X77480D01*
G01X32752Y679496D02*
X33611D01*
G01X29099D02*
X29528D01*
G01X27594D02*
X28132D01*
G01X20932D02*
X21362D01*
G01X16634D02*
X17279D01*
G01X13089D02*
X13519D01*
G01X11370D02*
X11799D01*
G01X15130D02*
X15667D01*
G01X10295D02*
X10832D01*
G01X70280Y679331D02*
X72437D01*
G01X32967Y679057D02*
X33396D01*
G01X11584D02*
X11370D01*
G01X13304D02*
X12981D01*
G01X16634Y678947D02*
X17279D01*
G01X72437Y678937D02*
X70280D01*
G01X77480Y678740D02*
X49325D01*
G01X57677Y678642D02*
X76063D01*
G01X48031D02*
X51771D01*
G01X46063Y678347D02*
X43307D01*
G01X26197Y678179D02*
X23941D01*
G01X47500Y678111D02*
X76594D01*
G01X26735Y677740D02*
X23834D01*
G01X59055Y677697D02*
X43307D01*
G01X51476Y677166D02*
X45177D01*
G01X26197Y677082D02*
X26735D01*
G01X55695Y676910D02*
X53754D01*
G01X17064Y676533D02*
X16634D01*
G01X33396Y676424D02*
X32967D01*
G01X9436Y675985D02*
X8791D01*
G01X10832D02*
X10295D01*
G01X12552D02*
X12014D01*
G01X14271D02*
X13734D01*
G01X17279D02*
X16634D01*
G01X19965D02*
X19428D01*
G01X22437D02*
X21899D01*
G01X28132D02*
X27594D01*
G01X30603D02*
X30065D01*
G01X33611D02*
X32752D01*
G01X36297D02*
X35760D01*
G01X46004Y675591D02*
X67401D01*
G01X44291Y674410D02*
X43996D01*
G01X52756D02*
X44291D01*
G01X77165D02*
X60197D01*
G01X15667Y674229D02*
X15130D01*
G01X67283Y673426D02*
X67382D01*
G01X43307D02*
X67283D01*
G01X43307Y672441D02*
X88582D01*
G01X39390Y672146D02*
X39467D01*
G01X15748Y658859D02*
X42519D01*
G01X38582Y657244D02*
X42519D01*
G01X15748Y656851D02*
X40157D01*
G01X23976Y656654D02*
X42126D01*
G01X42519D02*
X40157D01*
G01Y656103D02*
X19685D01*
G01X27721Y654685D02*
X42126D01*
G01X42519D02*
X40157D01*
G01X42519Y654095D02*
X40551D01*
G01X21063Y653700D02*
X15748D01*
G01X17126Y653150D02*
X21063D01*
G01X37401Y652682D02*
X21063D01*
G01X16338Y652559D02*
X17126D01*
G01X27131Y650748D02*
X26343D01*
G01X23031Y648386D02*
X21260D01*
G01X42519Y647244D02*
X40551D01*
G01X21260Y646654D02*
X42126D01*
G01X42519D02*
X40157D01*
G01X42126Y644685D02*
X21260D01*
G01X42519D02*
X40157D01*
G01X42519Y644095D02*
X40551D01*
G01X21260Y642953D02*
X26771D01*
G01X21063Y639528D02*
X15748D01*
G01X37401Y639502D02*
X21063D01*
G01X42519Y637244D02*
X40551D01*
G01X27953Y636654D02*
X42126D01*
G01X42519D02*
X40157D01*
G01X41891Y636063D02*
X42227D01*
G01X40551Y635817D02*
X42184D01*
G01X42519Y635571D02*
X40551D01*
G01X40157Y635237D02*
X19685D01*
G01X42126Y634685D02*
X23897D01*
G01X42519D02*
X40157D01*
G01X15748Y634489D02*
X40157D01*
G01X38582Y634095D02*
X42519D01*
G01X15748Y632481D02*
X42519D01*
G01X55417Y696736D02*
X56573Y696851D01*
G01X55417Y693587D02*
X56573Y693701D01*
G01X55417Y690437D02*
X56573Y690552D01*
G01X55417Y687287D02*
X56573Y687402D01*
G01X55417Y684138D02*
X56573Y684252D01*
G01X55417Y680988D02*
X56573Y681103D01*
G01X25767Y676533D02*
X25015Y676424D01*
G01X25875Y676094D02*
X25123Y675985D01*
G01Y679496D02*
X24478Y679386D01*
G01X54319Y696224D02*
X53420Y696063D01*
G01X54319Y693075D02*
X53420Y692914D01*
G01X54319Y689925D02*
X53420Y689764D01*
G01X54319Y686776D02*
X53420Y686615D01*
G01X54319Y683626D02*
X53420Y683465D01*
G01X54319Y680476D02*
X53420Y680315D01*
G01X53270Y694489D02*
X53864Y694603D01*
G01X53270Y691339D02*
X53864Y691453D01*
G01X53270Y688189D02*
X53864Y688304D01*
G01X53270Y685040D02*
X53864Y685154D01*
G01X53270Y681890D02*
X53864Y682005D01*
G01X53270Y678740D02*
X53864Y678855D01*
G01X55658Y695170D02*
X56175Y695276D01*
G01X55658Y692021D02*
X56175Y692126D01*
G01X55658Y688871D02*
X56175Y688977D01*
G01X55658Y685722D02*
X56175Y685827D01*
G01X55658Y682572D02*
X56175Y682677D01*
G01X55658Y679422D02*
X56175Y679528D01*
G01X55193Y696701D02*
X55217Y696706D01*
G01X55193Y693551D02*
X55217Y693556D01*
G01X55193Y690402D02*
X55217Y690407D01*
G01X55193Y687252D02*
X55217Y687257D01*
G01X55193Y684102D02*
X55217Y684107D01*
G01X55193Y680953D02*
X55217Y680958D01*
G01X16634Y679496D02*
X16205Y679386D01*
G01X16634Y678947D02*
X16205Y678838D01*
G01X20932Y679496D02*
X20503Y679386D01*
G01X20932Y679057D02*
X20503Y678947D01*
G01X25015Y679057D02*
X24586Y678947D01*
G01X17494Y676643D02*
X17064Y676533D01*
G01X29099Y679496D02*
X28669Y679386D01*
G01X29099Y679057D02*
X28669Y678947D01*
G01X17709Y676094D02*
X17279Y675985D01*
G01X32752Y679496D02*
X32322Y679386D01*
G01X32967Y679057D02*
X32537Y678947D01*
G01X33826Y676533D02*
X33396Y676424D01*
G01X34041Y676094D02*
X33611Y675985D01*
G01X49109Y696654D02*
X49843Y696851D01*
G01X49109Y693504D02*
X49843Y693701D01*
G01X49109Y690355D02*
X49843Y690552D01*
G01X49109Y687205D02*
X49843Y687402D01*
G01X49109Y684055D02*
X49843Y684252D01*
G01X49109Y680906D02*
X49843Y681103D01*
G01X49117Y680510D02*
X49118Y680908D01*
G01X49117Y683659D02*
X49118Y684058D01*
G01X49117Y686809D02*
X49118Y687207D01*
G01X49117Y689959D02*
X49118Y690357D01*
G01X49117Y693108D02*
X49118Y693507D01*
G01X49117Y696258D02*
X49118Y696656D01*
G01X77756Y684252D02*
Y683465D01*
G01Y681103D02*
Y680315D01*
G01Y687402D02*
Y686615D01*
G01Y693701D02*
Y692914D01*
G01Y690552D02*
Y689764D01*
G01Y696851D02*
Y696063D01*
G01X77480Y694489D02*
Y695276D01*
G01Y691339D02*
Y692126D01*
G01Y688189D02*
Y688977D01*
G01Y685040D02*
Y685827D01*
G01Y681890D02*
Y682677D01*
G01Y678740D02*
Y679528D01*
G01X77165Y672441D02*
Y740945D01*
G01X76890Y694489D02*
Y695276D01*
G01Y691339D02*
Y692126D01*
G01Y688189D02*
Y688977D01*
G01Y685040D02*
Y685827D01*
G01Y681890D02*
Y682677D01*
G01Y678740D02*
Y679528D01*
G01X76771Y684351D02*
Y683366D01*
G01Y681201D02*
Y680217D01*
G01Y687500D02*
Y686516D01*
G01Y693800D02*
Y692815D01*
G01Y690650D02*
Y689666D01*
G01Y696949D02*
Y695965D01*
G01X76594Y693859D02*
Y695906D01*
G01Y690709D02*
Y692756D01*
G01Y687559D02*
Y689607D01*
G01Y684410D02*
Y686457D01*
G01Y681260D02*
Y683307D01*
G01Y678111D02*
Y680158D01*
G01X76575Y696063D02*
Y696851D01*
G01Y692914D02*
Y693701D01*
G01Y689764D02*
Y690552D01*
G01Y686615D02*
Y687402D01*
G01Y683465D02*
Y684252D01*
G01Y680315D02*
Y681103D01*
G01X76063Y679626D02*
Y678642D01*
G01Y682776D02*
Y681792D01*
G01Y689075D02*
Y688091D01*
G01Y685926D02*
Y684941D01*
G01Y692225D02*
Y691240D01*
G01Y695374D02*
Y694390D01*
G01X75984Y694489D02*
Y695276D01*
G01Y691339D02*
Y692126D01*
G01Y688189D02*
Y688977D01*
G01Y685040D02*
Y685827D01*
G01Y681890D02*
Y682677D01*
G01Y678740D02*
Y679528D01*
G01X75787Y684252D02*
Y683465D01*
G01Y681103D02*
Y680315D01*
G01Y687402D02*
Y686615D01*
G01Y693701D02*
Y692914D01*
G01Y690552D02*
Y689764D01*
G01Y696851D02*
Y696063D01*
G01X75748Y679528D02*
Y678740D01*
G01Y682677D02*
Y681890D01*
G01Y688977D02*
Y688189D01*
G01Y685827D02*
Y685040D01*
G01Y692126D02*
Y691339D01*
G01Y695276D02*
Y694489D01*
G01X75669Y696063D02*
Y696851D01*
G01Y692914D02*
Y693701D01*
G01Y689764D02*
Y690552D01*
G01Y686615D02*
Y687402D01*
G01Y683465D02*
Y684252D01*
G01Y680315D02*
Y681103D01*
G01X75571Y694489D02*
Y695276D01*
G01Y691339D02*
Y692126D01*
G01Y688189D02*
Y688977D01*
G01Y685040D02*
Y685827D01*
G01Y681890D02*
Y682677D01*
G01Y678740D02*
Y679528D01*
G01X75197Y694489D02*
Y695276D01*
G01Y691339D02*
Y692126D01*
G01Y688189D02*
Y688977D01*
G01Y685040D02*
Y685827D01*
G01Y681890D02*
Y682677D01*
G01Y678740D02*
Y679528D01*
G01Y681496D02*
Y679922D01*
G01Y684646D02*
Y683071D01*
G01Y687796D02*
Y686221D01*
G01Y690945D02*
Y689370D01*
G01Y694095D02*
Y692520D01*
G01Y697244D02*
Y695670D01*
G01X75157Y679528D02*
Y678740D01*
G01Y682677D02*
Y681890D01*
G01Y688977D02*
Y688189D01*
G01Y685827D02*
Y685040D01*
G01Y692126D02*
Y691339D01*
G01Y695276D02*
Y694489D01*
G01X74055Y679528D02*
Y678740D01*
G01Y682677D02*
Y681890D01*
G01Y688977D02*
Y688189D01*
G01Y685827D02*
Y685040D01*
G01Y692126D02*
Y691339D01*
G01Y695276D02*
Y694489D01*
G01X73819D02*
Y695276D01*
G01Y691339D02*
Y692126D01*
G01Y688189D02*
Y688977D01*
G01Y685040D02*
Y685827D01*
G01Y681890D02*
Y682677D01*
G01Y678740D02*
Y679528D01*
G01X73779Y684252D02*
Y683465D01*
G01Y681103D02*
Y680315D01*
G01Y687402D02*
Y686615D01*
G01Y693701D02*
Y692914D01*
G01Y690552D02*
Y689764D01*
G01Y696851D02*
Y696063D01*
G01X73740Y684252D02*
Y683465D01*
G01Y681103D02*
Y680315D01*
G01Y687402D02*
Y686615D01*
G01Y693701D02*
Y692914D01*
G01Y690552D02*
Y689764D01*
G01Y696851D02*
Y696063D01*
G01X73641Y694489D02*
Y695276D01*
G01Y691339D02*
Y692126D01*
G01Y688189D02*
Y688977D01*
G01Y685040D02*
Y685827D01*
G01Y681890D02*
Y682677D01*
G01Y678740D02*
Y679528D01*
G01X73501Y696063D02*
Y696851D01*
G01Y692914D02*
Y693701D01*
G01Y689764D02*
Y690552D01*
G01Y686615D02*
Y687402D01*
G01Y683465D02*
Y684252D01*
G01Y680315D02*
Y681103D01*
G01X73464Y679528D02*
Y678740D01*
G01Y682677D02*
Y681890D01*
G01Y688977D02*
Y688189D01*
G01Y685827D02*
Y685040D01*
G01Y692126D02*
Y691339D01*
G01Y695276D02*
Y694489D01*
G01X73228D02*
Y695276D01*
G01Y695906D02*
Y697008D01*
G01Y691339D02*
Y692126D01*
G01Y692756D02*
Y693859D01*
G01Y689607D02*
Y690709D01*
G01Y688189D02*
Y688977D01*
G01Y685040D02*
Y685827D01*
G01Y686457D02*
Y687559D01*
G01Y681890D02*
Y682677D01*
G01Y683307D02*
Y684410D01*
G01Y680158D02*
Y681260D01*
G01Y678740D02*
Y679528D01*
G01Y672441D02*
Y678111D01*
G01X73208Y694390D02*
Y695374D01*
G01Y691240D02*
Y692225D01*
G01Y688091D02*
Y689075D01*
G01Y684941D02*
Y685926D01*
G01Y681792D02*
Y682776D01*
G01Y678642D02*
Y679626D01*
G01X73149Y679528D02*
Y678740D01*
G01Y682677D02*
Y681890D01*
G01Y688977D02*
Y688189D01*
G01Y685827D02*
Y685040D01*
G01Y692126D02*
Y691339D01*
G01Y695276D02*
Y694489D01*
G01X72893Y694390D02*
Y695374D01*
G01Y691240D02*
Y692225D01*
G01Y688091D02*
Y689075D01*
G01Y684941D02*
Y685926D01*
G01Y681792D02*
Y682776D01*
G01Y678642D02*
Y679626D01*
G01X72855Y679528D02*
Y678740D01*
G01Y682677D02*
Y681890D01*
G01Y688977D02*
Y688189D01*
G01Y685827D02*
Y685040D01*
G01Y692126D02*
Y691339D01*
G01Y695276D02*
Y694489D01*
G01X72834Y679528D02*
Y678740D01*
G01Y682677D02*
Y681890D01*
G01Y688977D02*
Y688189D01*
G01Y685827D02*
Y685040D01*
G01Y692126D02*
Y691339D01*
G01Y695276D02*
Y694489D01*
G01X72795Y694498D02*
Y695267D01*
G01Y691348D02*
Y692117D01*
G01Y688198D02*
Y688968D01*
G01Y685049D02*
Y685818D01*
G01Y681899D02*
Y682668D01*
G01Y678750D02*
Y679519D01*
G01X72783Y694489D02*
Y695276D01*
G01Y691339D02*
Y692126D01*
G01Y688189D02*
Y688977D01*
G01Y685040D02*
Y685827D01*
G01Y681890D02*
Y682677D01*
G01Y678740D02*
Y679528D01*
G01X72748D02*
Y678740D01*
G01Y682677D02*
Y681890D01*
G01Y688977D02*
Y688189D01*
G01Y685827D02*
Y685040D01*
G01Y692126D02*
Y691339D01*
G01Y695276D02*
Y694489D01*
G01X72693Y679416D02*
Y678852D01*
G01Y682566D02*
Y682002D01*
G01Y688865D02*
Y688301D01*
G01Y685715D02*
Y685151D01*
G01Y692015D02*
Y691450D01*
G01Y695164D02*
Y694600D01*
G01X72680Y684252D02*
Y683465D01*
G01Y681103D02*
Y680315D01*
G01Y687402D02*
Y686615D01*
G01Y693701D02*
Y692914D01*
G01Y690552D02*
Y689764D01*
G01Y696851D02*
Y696063D01*
G01X72667Y679528D02*
Y678740D01*
G01Y682677D02*
Y681890D01*
G01Y688977D02*
Y688189D01*
G01Y685827D02*
Y685040D01*
G01Y692126D02*
Y691339D01*
G01Y695276D02*
Y694489D01*
G01X72562Y696063D02*
Y696851D01*
G01Y692914D02*
Y693701D01*
G01Y689764D02*
Y690552D01*
G01Y686615D02*
Y687402D01*
G01Y683465D02*
Y684252D01*
G01Y680315D02*
Y681103D01*
G01X72441Y678111D02*
Y672441D01*
G01Y684410D02*
Y683307D01*
G01Y681260D02*
Y680158D01*
G01Y687559D02*
Y686457D01*
G01Y693859D02*
Y692756D01*
G01Y690709D02*
Y689607D01*
G01Y697008D02*
Y695906D01*
G01X72437Y694685D02*
Y695079D01*
G01Y691536D02*
Y691929D01*
G01Y688386D02*
Y688780D01*
G01Y685237D02*
Y685630D01*
G01Y682087D02*
Y682481D01*
G01Y678937D02*
Y679331D01*
G01X71653Y678642D02*
Y672441D01*
G01Y681792D02*
Y679626D01*
G01Y684941D02*
Y682776D01*
G01Y688091D02*
Y685926D01*
G01Y691240D02*
Y689075D01*
G01Y694390D02*
Y692225D01*
G01Y697540D02*
Y695374D01*
G01X71407Y684252D02*
Y683465D01*
G01Y681103D02*
Y680315D01*
G01Y687402D02*
Y686615D01*
G01Y693701D02*
Y692914D01*
G01Y690552D02*
Y689764D01*
G01Y696851D02*
Y696063D01*
G01X71385Y684252D02*
Y683465D01*
G01Y681103D02*
Y680315D01*
G01Y687402D02*
Y686615D01*
G01Y693701D02*
Y692914D01*
G01Y690552D02*
Y689764D01*
G01Y696851D02*
Y696063D01*
G01X71131D02*
Y696851D01*
G01Y692914D02*
Y693701D01*
G01Y689764D02*
Y690552D01*
G01Y686615D02*
Y687402D01*
G01Y683465D02*
Y684252D01*
G01Y680315D02*
Y681103D01*
G01X70472Y696063D02*
Y696851D01*
G01Y692914D02*
Y693701D01*
G01Y689764D02*
Y690552D01*
G01Y686615D02*
Y687402D01*
G01Y683465D02*
Y684252D01*
G01Y680315D02*
Y681103D01*
G01X70280Y679331D02*
Y678937D01*
G01Y682481D02*
Y682087D01*
G01Y688780D02*
Y688386D01*
G01Y685630D02*
Y685237D01*
G01Y691929D02*
Y691536D01*
G01Y695079D02*
Y694685D01*
G01X70024Y694600D02*
Y695164D01*
G01Y691450D02*
Y692015D01*
G01Y688301D02*
Y688865D01*
G01Y685151D02*
Y685715D01*
G01Y682002D02*
Y682566D01*
G01Y678852D02*
Y679416D01*
G01X69921Y679519D02*
Y678750D01*
G01Y682668D02*
Y681899D01*
G01Y688968D02*
Y688198D01*
G01Y685818D02*
Y685049D01*
G01Y692117D02*
Y691348D01*
G01Y695267D02*
Y694498D01*
G01X69882Y694390D02*
Y695374D01*
G01Y691240D02*
Y692225D01*
G01Y688091D02*
Y689075D01*
G01Y684941D02*
Y685926D01*
G01Y681792D02*
Y682776D01*
G01Y678642D02*
Y679626D01*
G01Y684252D02*
Y683465D01*
G01Y681103D02*
Y680315D01*
G01Y687402D02*
Y686615D01*
G01Y693701D02*
Y692914D01*
G01Y690552D02*
Y689764D01*
G01Y696851D02*
Y696063D01*
G01X69669Y694489D02*
Y695276D01*
G01Y691339D02*
Y692126D01*
G01Y688189D02*
Y688977D01*
G01Y685040D02*
Y685827D01*
G01Y681890D02*
Y682677D01*
G01Y678740D02*
Y679528D01*
G01X69567Y694390D02*
Y695374D01*
G01Y691240D02*
Y692225D01*
G01Y688091D02*
Y689075D01*
G01Y684941D02*
Y685926D01*
G01Y681792D02*
Y682776D01*
G01Y678642D02*
Y679626D01*
G01X69291Y696063D02*
Y696851D01*
G01Y692914D02*
Y693701D01*
G01Y689764D02*
Y690552D01*
G01Y686615D02*
Y687402D01*
G01Y683465D02*
Y684252D01*
G01Y680315D02*
Y681103D01*
G01X69252Y694390D02*
Y695374D01*
G01Y691240D02*
Y692225D01*
G01Y688091D02*
Y689075D01*
G01Y684941D02*
Y685926D01*
G01Y681792D02*
Y682776D01*
G01Y678642D02*
Y679626D01*
G01X69236Y679528D02*
Y678740D01*
G01Y682677D02*
Y681890D01*
G01Y688977D02*
Y688189D01*
G01Y685827D02*
Y685040D01*
G01Y692126D02*
Y691339D01*
G01Y695276D02*
Y694489D01*
G01X69012Y679528D02*
Y678740D01*
G01Y682677D02*
Y681890D01*
G01Y688977D02*
Y688189D01*
G01Y685827D02*
Y685040D01*
G01Y692126D02*
Y691339D01*
G01Y695276D02*
Y694489D01*
G01X68701Y684252D02*
Y683465D01*
G01Y681103D02*
Y680315D01*
G01Y687402D02*
Y686615D01*
G01Y693701D02*
Y692914D01*
G01Y690552D02*
Y689764D01*
G01Y696851D02*
Y696063D01*
G01X68578Y694489D02*
Y695276D01*
G01Y691339D02*
Y692126D01*
G01Y688189D02*
Y688977D01*
G01Y685040D02*
Y685827D01*
G01Y681890D02*
Y682677D01*
G01Y678740D02*
Y679528D01*
G01X68110Y696063D02*
Y696851D01*
G01Y692914D02*
Y693701D01*
G01Y689764D02*
Y690552D01*
G01Y686615D02*
Y687402D01*
G01Y683465D02*
Y684252D01*
G01Y680315D02*
Y681103D01*
G01X67401Y675591D02*
Y737796D01*
G01X67382Y673426D02*
Y672441D01*
G01X67283Y673426D02*
Y672441D01*
G01X66201Y673426D02*
Y672441D01*
G01X65807Y673426D02*
Y672441D01*
G01X65019Y673555D02*
Y672441D01*
G01X60499Y725591D02*
Y687796D01*
G01X60197Y674410D02*
Y673426D01*
G01X59728Y687796D02*
Y725591D01*
G01X59704Y673426D02*
Y672441D01*
G01X59675Y725591D02*
Y687796D01*
G01X59236Y725591D02*
Y687796D01*
G01X59055Y672441D02*
Y677697D01*
G01X58789Y687796D02*
Y725591D01*
G01X58267Y677697D02*
Y672441D01*
G01X57677Y695374D02*
Y695906D01*
G01Y690709D02*
Y691240D01*
G01Y692225D02*
Y692756D01*
G01Y693859D02*
Y694390D01*
G01Y685926D02*
Y686457D01*
G01Y687559D02*
Y688091D01*
G01Y689075D02*
Y689607D01*
G01Y681260D02*
Y681792D01*
G01Y682776D02*
Y683307D01*
G01Y684410D02*
Y684941D01*
G01Y678111D02*
Y678642D01*
G01Y679626D02*
Y680158D01*
G01X56850Y687796D02*
Y725591D01*
G01X56456D02*
Y687796D01*
G01X55658Y679422D02*
Y678846D01*
G01Y682572D02*
Y681996D01*
G01Y688871D02*
Y688295D01*
G01Y685722D02*
Y685145D01*
G01Y692021D02*
Y691444D01*
G01Y695170D02*
Y694594D01*
G01X55417Y696178D02*
Y696736D01*
G01Y693028D02*
Y693587D01*
G01Y689879D02*
Y690437D01*
G01Y686729D02*
Y687287D01*
G01Y683579D02*
Y684138D01*
G01Y680430D02*
Y680988D01*
G01X55314Y694489D02*
Y695276D01*
G01Y691339D02*
Y692126D01*
G01Y688189D02*
Y688977D01*
G01Y685040D02*
Y685827D01*
G01Y681890D02*
Y682677D01*
G01Y678740D02*
Y679528D01*
G01X55217Y684107D02*
Y683610D01*
G01Y680958D02*
Y680460D01*
G01Y687257D02*
Y686759D01*
G01Y693556D02*
Y693059D01*
G01Y690407D02*
Y689909D01*
G01Y696706D02*
Y696208D01*
G01X55193Y696213D02*
Y696701D01*
G01Y693064D02*
Y693551D01*
G01Y689914D02*
Y690402D01*
G01Y686765D02*
Y687252D01*
G01Y683615D02*
Y684102D01*
G01Y680465D02*
Y680953D01*
G01X55160Y684252D02*
Y683465D01*
G01Y681103D02*
Y680315D01*
G01Y687402D02*
Y686615D01*
G01Y693701D02*
Y692914D01*
G01Y690552D02*
Y689764D01*
G01Y696851D02*
Y696063D01*
G01X54977D02*
Y696851D01*
G01Y692914D02*
Y693701D01*
G01Y689764D02*
Y690552D01*
G01Y686615D02*
Y687402D01*
G01Y683465D02*
Y684252D01*
G01Y680315D02*
Y681103D01*
G01X54836Y684252D02*
Y683465D01*
G01Y681103D02*
Y680315D01*
G01Y687402D02*
Y686615D01*
G01Y693701D02*
Y692914D01*
G01Y690552D02*
Y689764D01*
G01Y696851D02*
Y696063D01*
G01X54619D02*
Y696851D01*
G01Y692914D02*
Y693701D01*
G01Y689764D02*
Y690552D01*
G01Y686615D02*
Y687402D01*
G01Y683465D02*
Y684252D01*
G01Y680315D02*
Y681103D01*
G01X54319Y684091D02*
Y683626D01*
G01Y680942D02*
Y680476D01*
G01Y687241D02*
Y686776D01*
G01Y693540D02*
Y693075D01*
G01Y690390D02*
Y689925D01*
G01Y696690D02*
Y696224D01*
G01X54289Y679528D02*
Y678740D01*
G01Y682677D02*
Y681890D01*
G01Y688977D02*
Y688189D01*
G01Y685827D02*
Y685040D01*
G01Y692126D02*
Y691339D01*
G01Y695276D02*
Y694489D01*
G01X53898Y687796D02*
Y725591D01*
G01X53864Y694603D02*
Y695161D01*
G01Y691453D02*
Y692012D01*
G01Y688304D02*
Y688862D01*
G01Y685154D02*
Y685713D01*
G01Y682005D02*
Y682563D01*
G01Y678855D02*
Y679413D01*
G01X53504Y725591D02*
Y687796D01*
G01X52756Y672441D02*
Y677697D01*
G01X52657Y675985D02*
Y672441D01*
G01X51771Y678642D02*
Y678111D01*
G01Y680158D02*
Y679626D01*
G01Y681792D02*
Y681260D01*
G01Y683307D02*
Y682776D01*
G01Y684941D02*
Y684410D01*
G01Y686457D02*
Y685926D01*
G01Y688091D02*
Y687559D01*
G01Y689607D02*
Y689075D01*
G01Y691240D02*
Y690709D01*
G01Y692756D02*
Y692225D01*
G01Y694390D02*
Y693859D01*
G01Y695906D02*
Y695374D01*
G01X51651Y725591D02*
Y687796D01*
G01X51205D02*
Y725591D01*
G01X50939Y679528D02*
Y678740D01*
G01Y682677D02*
Y681890D01*
G01Y688977D02*
Y688189D01*
G01Y685827D02*
Y685040D01*
G01Y692126D02*
Y691339D01*
G01Y695276D02*
Y694489D01*
G01X50766Y687796D02*
Y725591D01*
G01X50713D02*
Y687796D01*
G01X50468Y696063D02*
Y696851D01*
G01Y692914D02*
Y693701D01*
G01Y689764D02*
Y690552D01*
G01Y686615D02*
Y687402D01*
G01Y683465D02*
Y684252D01*
G01Y680315D02*
Y681103D01*
G01X50397Y687796D02*
Y725591D01*
G01X50393Y672441D02*
Y677697D01*
G01X50124Y725591D02*
Y687796D01*
G01X49656Y694489D02*
Y695276D01*
G01Y691339D02*
Y692126D01*
G01Y688189D02*
Y688977D01*
G01Y685040D02*
Y685827D01*
G01Y681890D02*
Y682677D01*
G01Y678740D02*
Y679528D01*
G01X49629Y684195D02*
Y683522D01*
G01Y681045D02*
Y680373D01*
G01Y687344D02*
Y686672D01*
G01Y693644D02*
Y692971D01*
G01Y690494D02*
Y689822D01*
G01Y696793D02*
Y696121D01*
G01X49606Y677697D02*
Y672441D01*
G01X49406Y679528D02*
Y678740D01*
G01Y682677D02*
Y681890D01*
G01Y688977D02*
Y688189D01*
G01Y685827D02*
Y685040D01*
G01Y692126D02*
Y691339D01*
G01Y695276D02*
Y694489D01*
G01X49366Y684124D02*
Y683593D01*
G01Y680975D02*
Y680443D01*
G01Y687274D02*
Y686742D01*
G01Y693573D02*
Y693042D01*
G01Y690424D02*
Y689892D01*
G01Y696723D02*
Y696191D01*
G01X49361Y696192D02*
Y696722D01*
G01Y693043D02*
Y693572D01*
G01Y689893D02*
Y690422D01*
G01Y686744D02*
Y687273D01*
G01Y683594D02*
Y684123D01*
G01Y680444D02*
Y680974D01*
G01X49353Y694489D02*
Y695276D01*
G01Y691339D02*
Y692126D01*
G01Y688189D02*
Y688977D01*
G01Y685040D02*
Y685827D01*
G01Y681890D02*
Y682677D01*
G01Y678740D02*
Y679528D01*
G01X49325Y694489D02*
Y695276D01*
G01Y691339D02*
Y692126D01*
G01Y688189D02*
Y688977D01*
G01Y685040D02*
Y685827D01*
G01Y681890D02*
Y682677D01*
G01Y678740D02*
Y679528D01*
G01X49109Y684055D02*
Y683662D01*
G01Y680906D02*
Y680512D01*
G01Y687205D02*
Y686811D01*
G01Y693504D02*
Y693111D01*
G01Y690355D02*
Y689961D01*
G01Y696654D02*
Y696260D01*
G01X48031Y679626D02*
Y678642D01*
G01Y682776D02*
Y681792D01*
G01Y685926D02*
Y684941D01*
G01Y689075D02*
Y688091D01*
G01Y692225D02*
Y691240D01*
G01Y695374D02*
Y694390D01*
G01X47500Y680158D02*
Y678111D01*
G01Y683307D02*
Y681260D01*
G01Y689607D02*
Y687559D01*
G01Y686457D02*
Y684410D01*
G01Y692756D02*
Y690709D01*
G01Y695906D02*
Y693859D01*
G01X46456Y628544D02*
Y662796D01*
G01X46063Y679922D02*
Y678347D01*
G01Y683071D02*
Y681496D01*
G01Y686221D02*
Y684646D01*
G01Y689370D02*
Y687796D01*
G01Y692520D02*
Y690945D01*
G01Y695670D02*
Y694095D01*
G01X46004Y675591D02*
Y737796D01*
G01X44291Y677697D02*
Y672441D01*
G01X43996Y675985D02*
Y672441D01*
G01X43307Y740945D02*
Y672441D01*
G01X42519Y656654D02*
Y658859D01*
G01Y632481D02*
Y634685D01*
G01Y635817D02*
Y635571D01*
G01Y644685D02*
Y636654D01*
G01Y654685D02*
Y646654D01*
G01X42126Y636654D02*
Y634685D01*
G01Y646654D02*
Y644685D01*
G01Y656654D02*
Y654685D01*
G01X41791Y687796D02*
Y725591D01*
G01X41518D02*
Y687796D01*
G01X41378Y636654D02*
Y634685D01*
G01Y646654D02*
Y644685D01*
G01Y656654D02*
Y654685D01*
G01X40551Y635571D02*
Y635817D01*
G01X40157Y644685D02*
Y646654D01*
G01Y636654D02*
Y634685D01*
G01Y637717D02*
Y634095D01*
G01Y647953D02*
Y643386D01*
G01Y656654D02*
Y654685D01*
G01Y657244D02*
Y653701D01*
G01X39390Y671162D02*
Y685827D01*
G01X38582Y657244D02*
Y634095D01*
G01X37401Y652682D02*
Y639502D01*
G01X36297Y681142D02*
Y675985D01*
G01X35760D02*
Y681142D01*
G01X34901Y677960D02*
Y677521D01*
G01X34764Y671162D02*
Y672146D01*
G01X34364Y677960D02*
Y677521D01*
G01X33582Y672146D02*
Y671162D01*
G01X33477Y672146D02*
Y671162D01*
G01X33182D02*
Y672146D01*
G01X32000Y677521D02*
Y677960D01*
G01X31818Y672146D02*
Y671162D01*
G01X31523D02*
Y672146D01*
G01X31462Y677521D02*
Y677960D01*
G01X31417Y672146D02*
Y671162D01*
G01X30603Y678070D02*
Y675985D01*
G01X30236Y672146D02*
Y671162D01*
G01X30065Y675985D02*
Y678070D01*
G01X49477Y694489D02*
Y695276D01*
G01Y691339D02*
Y692126D01*
G01Y688189D02*
Y688977D01*
G01Y685040D02*
Y685827D01*
G01Y681890D02*
Y682677D01*
G01Y678740D02*
Y679528D01*
G01X73449Y678642D02*
X73228Y678111D01*
G01X73449Y681792D02*
X73228Y681260D01*
G01X73449Y684941D02*
X73228Y684410D01*
G01X73449Y688091D02*
X73228Y687559D01*
G01X73449Y691240D02*
X73228Y690709D01*
G01X73449Y694390D02*
X73228Y693859D01*
G01X34901Y677521D02*
X34686Y676753D01*
G01X34364Y677521D02*
X34256Y677082D01*
G01X32107Y678399D02*
X32000Y677960D01*
G01X31570Y678399D02*
X31462Y677960D01*
G01X26735Y677082D02*
X26627Y676643D01*
G01X18569Y677302D02*
X18461Y676863D01*
G01X60807Y674370D02*
X60620Y673404D01*
G01X23404Y678399D02*
X23296Y677740D01*
G01X29350Y671162D02*
Y672146D01*
G01X28366D02*
Y671162D01*
G01X28132Y678509D02*
Y675985D01*
G01Y679496D02*
Y678947D01*
G01X27594Y675985D02*
Y679496D01*
G01X27362Y642363D02*
Y637244D01*
G01X27131Y654095D02*
Y650748D01*
G01X26735Y678179D02*
Y677740D01*
G01X26197Y678399D02*
Y678179D01*
G01X23941D02*
Y678289D01*
G01X23834Y677740D02*
Y677521D01*
G01X22437Y678179D02*
Y675985D01*
G01X21899D02*
Y678179D01*
G01X21260Y642953D02*
Y640747D01*
G01Y646654D02*
Y644685D01*
G01X21063Y639567D02*
Y653113D01*
G01Y653700D02*
Y639502D01*
G01X20984Y671162D02*
Y672146D01*
G01X19965Y678509D02*
Y675985D01*
G01Y681142D02*
Y678947D01*
G01X19803Y672146D02*
Y671162D01*
G01X19697Y672146D02*
Y671162D01*
G01X19685Y656103D02*
Y635237D01*
G01X19441Y724410D02*
Y688977D01*
G01X19428Y675985D02*
Y681142D01*
G01X19402Y671162D02*
Y672146D01*
G01X18588Y724410D02*
Y688977D01*
G01X18569Y678179D02*
Y677302D01*
G01X18038Y672146D02*
Y671162D01*
G01X18031Y678070D02*
Y677411D01*
G01X17743Y671162D02*
Y672146D01*
G01X17736Y688977D02*
Y724410D01*
G01X17638Y672146D02*
Y671162D01*
G01X17126Y639567D02*
Y653113D01*
G01X16456Y672146D02*
Y671162D01*
G01X16338Y639567D02*
Y652528D01*
G01X15748Y658859D02*
Y632481D01*
G01X15667Y677192D02*
Y678289D01*
G01Y676643D02*
Y674229D01*
G01Y679496D02*
Y678838D01*
G01X15130Y674229D02*
Y679496D01*
G01X14271Y678618D02*
Y675985D01*
G01X13799Y724410D02*
Y688977D01*
G01X13734Y675985D02*
Y678618D01*
G01X12947Y688977D02*
Y724410D01*
G01X12552Y678618D02*
Y675985D01*
G01X12094Y724410D02*
Y688977D01*
G01X12014Y675985D02*
Y678618D01*
G01X10832Y678728D02*
Y675985D01*
G01Y679496D02*
Y679167D01*
G01X10295Y675985D02*
Y679496D01*
G01X10177Y672146D02*
Y671162D01*
G01X9173D02*
Y672146D01*
G01X8878Y699311D02*
Y692500D01*
G01X7992Y672146D02*
Y671162D01*
G01X7886Y672146D02*
Y671162D01*
G01X7815Y672146D02*
Y671162D01*
G01X34686Y676753D02*
X34471Y676424D01*
G01X34256Y677082D02*
X34041Y676753D01*
G01X40551Y644095D02*
X38582Y640552D01*
G01X24049Y678509D02*
X23941Y678289D01*
G01X23619Y678838D02*
X23404Y678399D01*
G01X17924Y677082D02*
X17817Y676863D01*
G01X15775Y679057D02*
X15667Y678838D01*
G01X12659D02*
X12552Y678618D01*
G01X21063Y649961D02*
X23976Y656654D01*
G01X31677Y678728D02*
X31570Y678399D01*
G01X26197Y677082D02*
X26090Y676753D01*
G01X18031Y677411D02*
X17924Y677082D01*
G01X76594Y680158D02*
X76063Y679626D01*
G01X77165Y681595D02*
X76771Y681201D01*
G01X72972Y678642D02*
X72441Y678111D01*
G01D02*
X72972Y678642D01*
G01X76594Y683307D02*
X76063Y682776D01*
G01X72693Y679416D02*
X72795Y679519D01*
G01X77165Y684744D02*
X76771Y684351D01*
G01X72972Y681792D02*
X72441Y681260D01*
G01D02*
X72972Y681792D01*
G01X70024Y678852D02*
X69921Y678750D01*
G01X76594Y686457D02*
X76063Y685926D01*
G01X72693Y682566D02*
X72795Y682668D01*
G01X77165Y687894D02*
X76771Y687500D01*
G01X72972Y684941D02*
X72441Y684410D01*
G01D02*
X72972Y684941D01*
G01X70024Y682002D02*
X69921Y681899D01*
G01X76594Y689607D02*
X76063Y689075D01*
G01X72693Y685715D02*
X72795Y685818D01*
G01X40551Y654095D02*
X38582Y652126D01*
G01X77165Y691044D02*
X76771Y690650D01*
G01X72972Y688091D02*
X72441Y687559D01*
G01D02*
X72972Y688091D01*
G01X70024Y685151D02*
X69921Y685049D01*
G01X76594Y692756D02*
X76063Y692225D01*
G01X72693Y688865D02*
X72795Y688968D01*
G01X77165Y694193D02*
X76771Y693800D01*
G01X72972Y691240D02*
X72441Y690709D01*
G01D02*
X72972Y691240D01*
G01X70024Y688301D02*
X69921Y688198D01*
G01X76594Y695906D02*
X76063Y695374D01*
G01X72693Y692015D02*
X72795Y692117D01*
G01X77165Y697343D02*
X76771Y696949D01*
G01X72972Y694390D02*
X72441Y693859D01*
G01D02*
X72972Y694390D01*
G01X70024Y691450D02*
X69921Y691348D01*
G01X72693Y695164D02*
X72795Y695267D01*
G01X70024Y694600D02*
X69921Y694498D01*
G01X43307Y672894D02*
X46004Y675591D01*
G01X44291Y674410D02*
X43307Y673426D01*
G01X48031Y678642D02*
X47500Y678111D01*
G01X48031Y681792D02*
X47500Y681260D01*
G01X48031Y684941D02*
X47500Y684410D01*
G01X48031Y688091D02*
X47500Y687559D01*
G01X48031Y691240D02*
X47500Y690709D01*
G01X48031Y694390D02*
X47500Y693859D01*
G01X34471Y676424D02*
X34256Y676204D01*
G01X34041Y676753D02*
X33826Y676533D01*
G01X32537Y678947D02*
X32322Y678728D01*
G01X32107Y679277D02*
X31892Y679057D01*
G01X26627Y676643D02*
X26305Y676314D01*
G01X28346Y678728D02*
X28132Y678509D01*
G01X28346Y679167D02*
X28132Y678947D01*
G01X24371Y678838D02*
X24049Y678509D01*
G01X23834Y679057D02*
X23619Y678838D01*
G01X20180Y678728D02*
X19965Y678509D01*
G01X20180Y679167D02*
X19965Y678947D01*
G01X15990Y679277D02*
X15775Y679057D01*
G01X12766Y678947D02*
X12659Y678838D01*
G01X12766Y679386D02*
X12444Y679057D01*
G01X11047Y678947D02*
X10832Y678728D01*
G01X11047Y679386D02*
X10832Y679167D01*
G01X18461Y676863D02*
X18031Y676314D01*
G01X32322Y678728D02*
X32107Y678399D01*
G01X31892Y679057D02*
X31677Y678728D01*
G01X15882Y678618D02*
X15667Y678289D01*
G01X34256Y676204D02*
X34041Y676094D01*
G01X26305Y676314D02*
X25875Y676094D01*
G01X32322Y679386D02*
X32107Y679277D01*
G01X24586Y678947D02*
X24371Y678838D01*
G01X14484Y673615D02*
X11865Y672042D01*
G01X13977Y674459D02*
X11358Y672885D01*
G01X26090Y676753D02*
X25767Y676533D01*
G01X28669Y678947D02*
X28346Y678728D01*
G01X28669Y679386D02*
X28346Y679167D01*
G01X24156Y679277D02*
X23834Y679057D01*
G01X18031Y676314D02*
X17709Y676094D01*
G01X17817Y676863D02*
X17494Y676643D01*
G01X20503Y678947D02*
X20180Y678728D01*
G01X20503Y679386D02*
X20180Y679167D01*
G01X16205Y678838D02*
X15882Y678618D01*
G01X26343Y650748D02*
X23031Y648386D01*
G01X43182Y672341D02*
X39928Y671262D01*
G01X43174Y673376D02*
X39467Y672146D01*
G01X24478Y679386D02*
X24156Y679277D01*
G01X13089Y679496D02*
X12766Y679386D01*
G01X11370Y679057D02*
X11047Y678947D01*
G01X11370Y679496D02*
X11047Y679386D01*
G01X16205D02*
X15990Y679277D01*
G01X12981Y679057D02*
X12766Y678947D01*
G01X53691Y736230D02*
X53754Y736477D01*
G01X53628Y735968D02*
X53691Y736230D01*
G01X53565Y735689D02*
X53628Y735968D01*
G01X55822Y735963D02*
X55884Y735689D01*
G01X55759Y736224D02*
X55822Y735963D01*
G01X55695Y736477D02*
X55759Y736224D01*
G01X43174Y740011D02*
G03X43484Y739961I310J934D01*
G01X34468Y727559D02*
G03Y725591I0J-984D01*
G01X43996Y737402D02*
G03X45177Y736221I1181J0D01*
G01X51476D02*
G03X52657Y737402I0J1181D01*
G01X33779Y741733D02*
G03I-1575J0D01*
G01X39928Y742125D02*
G03X39390Y742223I-618J-1869D01*
G01X43182Y741045D02*
G03X43802Y740945I619J1869D01*
G01X55695Y736477D02*
G03X53754I-971J1712D01*
G01X55884Y735689D02*
G03X53565I-1160J2500D01*
G01X57795Y738189D02*
G03I-3071J0D01*
G01X21260Y766496D02*
G03X21063Y766300I0J-197D01*
G01Y764961D02*
G03X21260Y764764I197J0D01*
G01Y762796D02*
G03X21063Y762599I0J-197D01*
G01Y761260D02*
G03X21260Y761063I197J0D01*
G01X27362Y755355D02*
G03X27953Y754764I591J0D01*
G01X27362Y760473D02*
G03X26771Y761063I-590J0D01*
G01X8878Y720886D02*
G03X8090Y721674I-788J0D01*
G01X14484Y739771D02*
G03X15687Y739919I507J844D01*
G01X18226Y740709D02*
G03X17582Y740422I52J-983D01*
G01X20000Y741733D02*
G03I-1575J0D01*
G01X12126D02*
G03I-1575J0D01*
G01X17736Y724410D02*
G03X13799I-1969J0D01*
G01X18175Y741692D02*
G03X16886Y741118I103J-1966D01*
G01X13977Y738927D02*
G03X16383Y739223I1014J1688D01*
G01X18588Y724410D02*
G03X12947I-2820J0D01*
G01X19441D02*
G03X12094I-3673J0D01*
G01X8090Y713288D02*
G03X8878Y714075I1J787D01*
G01Y699311D02*
G03X8090Y700099I-788J0D01*
G01X38582Y757717D02*
X40551Y755355D01*
G01X77165Y733366D02*
X76771Y733760D01*
G01X76063Y732185D02*
X76594Y731654D01*
G01X77165Y730217D02*
X76771Y730611D01*
G01X72441Y733701D02*
X72972Y733170D01*
G01X76063Y729036D02*
X76594Y728504D01*
G01X72693Y732395D02*
X72795Y732293D01*
G01X77165Y727067D02*
X76771Y727461D01*
G01X72441Y730552D02*
X72972Y730020D01*
G01X69921Y733062D02*
X70024Y732959D01*
G01X76063Y725886D02*
X76594Y725355D01*
G01X72693Y729246D02*
X72795Y729143D01*
G01X77165Y723918D02*
X76771Y724311D01*
G01X72441Y727402D02*
X72972Y726870D01*
G01X69921Y729913D02*
X70024Y729810D01*
G01X76063Y722737D02*
X76594Y722205D01*
G01X72693Y726096D02*
X72795Y725994D01*
G01X77165Y720768D02*
X76771Y721162D01*
G01X72441Y724252D02*
X72972Y723721D01*
G01X69921Y726763D02*
X70024Y726660D01*
G01X76063Y719587D02*
X76594Y719055D01*
G01X72693Y722946D02*
X72795Y722844D01*
G01X77165Y717618D02*
X76771Y718012D01*
G01X72441Y721103D02*
X72972Y720571D01*
G01X69921Y723613D02*
X70024Y723511D01*
G01X76063Y716437D02*
X76594Y715906D01*
G01X72693Y719797D02*
X72795Y719694D01*
G01X77165Y714469D02*
X76771Y714863D01*
G01X72441Y717953D02*
X72972Y717422D01*
G01X69921Y720464D02*
X70024Y720361D01*
G01X76063Y713288D02*
X76594Y712756D01*
G01X72693Y716647D02*
X72795Y716545D01*
G01X77165Y711319D02*
X76771Y711713D01*
G01X72441Y714803D02*
X72972Y714272D01*
G01X69921Y717314D02*
X70024Y717211D01*
G01X76063Y710138D02*
X76594Y709607D01*
G01X72693Y713498D02*
X72795Y713395D01*
G01X77165Y708170D02*
X76771Y708563D01*
G01X72441Y711654D02*
X72972Y711122D01*
G01X69921Y714165D02*
X70024Y714062D01*
G01X46004Y737796D02*
X43307Y740492D01*
G01Y739961D02*
X44291Y738977D01*
G01X76063Y706989D02*
X76594Y706457D01*
G01X72693Y710348D02*
X72795Y710246D01*
G01X77165Y705020D02*
X76771Y705414D01*
G01X48031Y733170D02*
X47500Y733701D01*
G01X72441Y708504D02*
X72972Y707973D01*
G01X69921Y711015D02*
X70024Y710912D01*
G01X76063Y703839D02*
X76594Y703307D01*
G01X72693Y707198D02*
X72795Y707096D01*
G01X77165Y701870D02*
X76771Y702264D01*
G01X48031Y730020D02*
X47500Y730552D01*
G01X72441Y705355D02*
X72972Y704823D01*
G01X69921Y707865D02*
X70024Y707763D01*
G01X76063Y700689D02*
X76594Y700158D01*
G01X72693Y704049D02*
X72795Y703946D01*
G01X77165Y698721D02*
X76771Y699115D01*
G01X48031Y726870D02*
X47500Y727402D01*
G01X72441Y702205D02*
X72972Y701674D01*
G01X69921Y704716D02*
X70024Y704613D01*
G01X76063Y697540D02*
X76594Y697008D01*
G01X72693Y700899D02*
X72795Y700797D01*
G01X48031Y723721D02*
X47500Y724252D01*
G01X72441Y699055D02*
X72972Y698524D01*
G01X69921Y701566D02*
X70024Y701463D01*
G01X72693Y697750D02*
X72795Y697647D01*
G01X48031Y720571D02*
X47500Y721103D01*
G01X69921Y698416D02*
X70024Y698314D01*
G01X48031Y717422D02*
X47500Y717953D01*
G01X48031Y714272D02*
X47500Y714803D01*
G01X48031Y711122D02*
X47500Y711654D01*
G01X48031Y707973D02*
X47500Y708504D01*
G01X48031Y704823D02*
X47500Y705355D01*
G01X42227Y754174D02*
X42519Y753927D01*
G01X42184D02*
X41891Y754174D01*
G01X14484Y739771D02*
X11865Y741345D01*
G01X13977Y738927D02*
X11358Y740501D01*
G01X43182Y741045D02*
X39928Y742125D01*
G01X43174Y740011D02*
X39467Y741240D01*
G01X49109Y734055D02*
X49843Y733859D01*
G01X49109Y730906D02*
X49843Y730709D01*
G01X49109Y727756D02*
X49843Y727559D01*
G01X49109Y724607D02*
X49843Y724410D01*
G01X49109Y721457D02*
X49843Y721260D01*
G01X49109Y718307D02*
X49843Y718111D01*
G01X49109Y715158D02*
X49843Y714961D01*
G01X55217Y734003D02*
X55193Y734009D01*
G01X55217Y730854D02*
X55193Y730859D01*
G01X55217Y727704D02*
X55193Y727709D01*
G01X55217Y724555D02*
X55193Y724560D01*
G01X55217Y721405D02*
X55193Y721410D01*
G01X55658Y732389D02*
X56175Y732284D01*
G01X55658Y729240D02*
X56175Y729134D01*
G01X55658Y726090D02*
X56175Y725985D01*
G01X55658Y722940D02*
X56175Y722835D01*
G01X55658Y719791D02*
X56175Y719685D01*
G01X53864Y732957D02*
X53270Y733071D01*
G01X53864Y729807D02*
X53270Y729922D01*
G01X53864Y726657D02*
X53270Y726772D01*
G01X53864Y723508D02*
X53270Y723622D01*
G01X53420Y734646D02*
X54319Y734485D01*
G01X53420Y731496D02*
X54319Y731335D01*
G01X53420Y728347D02*
X54319Y728186D01*
G01X53420Y725197D02*
X54319Y725036D01*
G01X56573Y733859D02*
X55417Y733973D01*
G01X23031Y766496D02*
X21260D01*
G01X42519Y765355D02*
X40551D01*
G01X21260Y764764D02*
X42126D01*
G01X42519D02*
X40157D01*
G01X42126Y762796D02*
X21260D01*
G01X42519D02*
X40157D01*
G01X42519Y762205D02*
X40551D01*
G01X21260Y761063D02*
X26771D01*
G01X21063Y757638D02*
X15748D01*
G01X37401Y757612D02*
X21063D01*
G01X42519Y755355D02*
X40551D01*
G01X27953Y754764D02*
X42126D01*
G01X42519D02*
X40157D01*
G01X41891Y754174D02*
X42227D01*
G01X40551Y753927D02*
X42184D01*
G01X42519Y753681D02*
X40551D01*
G01X40157Y753347D02*
X19685D01*
G01X42126Y752796D02*
X23897D01*
G01X42519D02*
X40157D01*
G01X15748Y752599D02*
X40157D01*
G01X38582Y752205D02*
X42519D01*
G01X15748Y750591D02*
X42519D01*
G01X60620Y739982D02*
X60807Y739016D01*
G01X73449Y733170D02*
X73228Y733701D01*
G01Y730552D02*
X73449Y730020D01*
G01X73228Y727402D02*
X73449Y726870D01*
G01X73228Y724252D02*
X73449Y723721D01*
G01X73228Y721103D02*
X73449Y720571D01*
G01X73228Y717953D02*
X73449Y717422D01*
G01X73228Y714803D02*
X73449Y714272D01*
G01X73228Y711654D02*
X73449Y711122D01*
G01X73228Y708504D02*
X73449Y707973D01*
G01X73228Y705355D02*
X73449Y704823D01*
G01X73228Y702205D02*
X73449Y701674D01*
G01X73228Y699055D02*
X73449Y698524D01*
G01X23897Y752796D02*
X21063Y759309D01*
G01X38582Y768898D02*
X40551Y765355D01*
G01X48031Y701674D02*
X47500Y702205D01*
G01X48031Y698524D02*
X47500Y699055D01*
G01X49109Y712008D02*
X49843Y711811D01*
G01X49109Y708859D02*
X49843Y708662D01*
G01X49109Y705709D02*
X49843Y705512D01*
G01X49109Y702559D02*
X49843Y702363D01*
G01X49109Y699410D02*
X49843Y699213D01*
G01X55217Y718255D02*
X55193Y718261D01*
G01X55217Y715106D02*
X55193Y715111D01*
G01X55217Y711956D02*
X55193Y711961D01*
G01X55217Y708807D02*
X55193Y708812D01*
G01X55217Y705657D02*
X55193Y705662D01*
G01X55217Y702507D02*
X55193Y702513D01*
G01X55217Y699358D02*
X55193Y699363D01*
G01X55658Y716641D02*
X56175Y716536D01*
G01X55658Y713492D02*
X56175Y713386D01*
G01X55658Y710342D02*
X56175Y710237D01*
G01X55658Y707192D02*
X56175Y707087D01*
G01X55658Y704043D02*
X56175Y703937D01*
G01X55658Y700893D02*
X56175Y700788D01*
G01X55658Y697744D02*
X56175Y697638D01*
G01X53864Y720358D02*
X53270Y720473D01*
G01X53864Y717209D02*
X53270Y717323D01*
G01X53864Y714059D02*
X53270Y714174D01*
G01X53864Y710909D02*
X53270Y711024D01*
G01X53864Y707760D02*
X53270Y707874D01*
G01X53864Y704610D02*
X53270Y704725D01*
G01X53864Y701461D02*
X53270Y701575D01*
G01X53864Y698311D02*
X53270Y698426D01*
G01X53420Y722048D02*
X54319Y721887D01*
G01X53420Y718898D02*
X54319Y718737D01*
G01X53420Y715748D02*
X54319Y715587D01*
G01X53420Y712599D02*
X54319Y712438D01*
G01X53420Y709449D02*
X54319Y709288D01*
G01X53420Y706300D02*
X54319Y706139D01*
G01X53420Y703150D02*
X54319Y702989D01*
G01X53420Y700000D02*
X54319Y699839D01*
G01X56573Y730709D02*
X55417Y730824D01*
G01X56573Y727559D02*
X55417Y727674D01*
G01X56573Y724410D02*
X55417Y724524D01*
G01X56573Y721260D02*
X55417Y721375D01*
G01X56573Y718111D02*
X55417Y718225D01*
G01X56573Y714961D02*
X55417Y715076D01*
G01X56573Y711811D02*
X55417Y711926D01*
G01X56573Y708662D02*
X55417Y708776D01*
G01X56573Y705512D02*
X55417Y705627D01*
G01X56573Y702363D02*
X55417Y702477D01*
G01X56573Y699213D02*
X55417Y699327D01*
G01X39390Y741240D02*
X39467D01*
G01X43307Y740945D02*
X88582D01*
G01X67283Y739961D02*
X67382D01*
G01X43307D02*
X67283D01*
G01X60197Y738977D02*
X77165D01*
G01X43996D02*
X44291D01*
G01D02*
X52756D01*
G01X67401Y737796D02*
X46004D01*
G01X53754Y736477D02*
X55695D01*
G01X51476Y736221D02*
X45177D01*
G01X43307Y735689D02*
X59055D01*
G01X77165Y735040D02*
X75197D01*
G01X76909Y734882D02*
X43307D01*
G01X76771Y734744D02*
X67401D01*
G01X49843Y734646D02*
X87126D01*
G01X49843Y733859D02*
X87126D01*
G01X76771Y733760D02*
X67401D01*
G01X76594Y733701D02*
X47500D01*
G01X76909Y733622D02*
X43307D01*
G01X46063Y733465D02*
X43307D01*
G01X77165D02*
X75197D01*
G01X51771Y733170D02*
X48031D01*
G01X76063D02*
X57677D01*
G01X49325Y733071D02*
X77480D01*
G01X70280Y732874D02*
X72437D01*
G01Y732481D02*
X70280D01*
G01X77480Y732284D02*
X49325D01*
G01X57677Y732185D02*
X76063D01*
G01X48031D02*
X51771D01*
G01X46063Y731890D02*
X43307D01*
G01X77165D02*
X75197D01*
G01X76909Y731733D02*
X43307D01*
G01X47500Y731654D02*
X76594D01*
G01X76771Y731595D02*
X67401D01*
G01X49843Y731496D02*
X87126D01*
G01X49843Y730709D02*
X87126D01*
G01X76771Y730611D02*
X67401D01*
G01X76594Y730552D02*
X47500D01*
G01X76909Y730473D02*
X43307D01*
G01X46063Y730315D02*
X43307D01*
G01X77165D02*
X75197D01*
G01X51771Y730020D02*
X48031D01*
G01X76063D02*
X57677D01*
G01X49325Y729922D02*
X77480D01*
G01X70280Y729725D02*
X72437D01*
G01Y729331D02*
X70280D01*
G01X49325Y729134D02*
X77480D01*
G01X57677Y729036D02*
X76063D01*
G01X48031D02*
X51771D01*
G01X46063Y728740D02*
X43307D01*
G01X77165D02*
X75197D01*
G01X76909Y728583D02*
X43307D01*
G01X47500Y728504D02*
X76594D01*
G01X76771Y728445D02*
X67401D01*
G01X49843Y728347D02*
X87126D01*
G01X49843Y727559D02*
X87126D01*
G01X39390D02*
X34468D01*
G01X76771Y727461D02*
X67401D01*
G01X76594Y727402D02*
X47500D01*
G01X76909Y727323D02*
X43307D01*
G01X46063Y727166D02*
X43307D01*
G01X77165D02*
X75197D01*
G01X51771Y726870D02*
X48031D01*
G01X76063D02*
X57677D01*
G01X49325Y726772D02*
X77480D01*
G01X70280Y726575D02*
X72437D01*
G01Y726181D02*
X70280D01*
G01X77480Y725985D02*
X49325D01*
G01X57677Y725886D02*
X76063D01*
G01X48031D02*
X51771D01*
G01X46063Y725591D02*
X60499D01*
G01X43307D02*
X34468D01*
G01X46063D02*
X43307D01*
G01X77165D02*
X75197D01*
G01X76909Y725433D02*
X43307D01*
G01X47500Y725355D02*
X76594D01*
G01X76771Y725296D02*
X67401D01*
G01X49843Y725197D02*
X87126D01*
G01X49843Y724410D02*
X87126D01*
G01X13799D02*
X12094D01*
G01X19441D02*
X17736D01*
G01X76771Y724311D02*
X67401D01*
G01X76594Y724252D02*
X47500D01*
G01X76909Y724174D02*
X43307D01*
G01X46063Y724016D02*
X43307D01*
G01X77165D02*
X75197D01*
G01X51771Y723721D02*
X48031D01*
G01X76063D02*
X57677D01*
G01X49325Y723622D02*
X77480D01*
G01X70280Y723426D02*
X72437D01*
G01Y723032D02*
X70280D01*
G01X77480Y722835D02*
X49325D01*
G01X57677Y722737D02*
X76063D01*
G01X48031D02*
X51771D01*
G01X46063Y722441D02*
X43307D01*
G01X77165D02*
X75197D01*
G01X76909Y722284D02*
X43307D01*
G01X47500Y722205D02*
X76594D01*
G01X76771Y722146D02*
X67401D01*
G01X49843Y722048D02*
X87126D01*
G01X49843Y721260D02*
X87126D01*
G01X76771Y721162D02*
X67401D01*
G01X76594Y721103D02*
X47500D01*
G01X76909Y721024D02*
X43307D01*
G01X46063Y720866D02*
X43307D01*
G01X77165D02*
X75197D01*
G01X51771Y720571D02*
X48031D01*
G01X76063D02*
X57677D01*
G01X49325Y720473D02*
X77480D01*
G01X70280Y720276D02*
X72437D01*
G01Y719882D02*
X70280D01*
G01X49325Y719685D02*
X77480D01*
G01X57677Y719587D02*
X76063D01*
G01X48031D02*
X51771D01*
G01X46063Y719292D02*
X43307D01*
G01X77165D02*
X75197D01*
G01X76909Y719134D02*
X43307D01*
G01X47500Y719055D02*
X76594D01*
G01X76771Y718996D02*
X67401D01*
G01X49843Y718898D02*
X87126D01*
G01X49843Y718111D02*
X87126D01*
G01X76771Y718012D02*
X67401D01*
G01X76594Y717953D02*
X47500D01*
G01X76909Y717874D02*
X43307D01*
G01X46063Y717717D02*
X43307D01*
G01X77165D02*
X75197D01*
G01X51771Y717422D02*
X48031D01*
G01X76063D02*
X57677D01*
G01X49325Y717323D02*
X77480D01*
G01X70280Y717126D02*
X72437D01*
G01Y716733D02*
X70280D01*
G01X77480Y716536D02*
X49325D01*
G01X57677Y716437D02*
X76063D01*
G01X48031D02*
X51771D01*
G01X46063Y716142D02*
X43307D01*
G01X77165D02*
X75197D01*
G01X76909Y715985D02*
X43307D01*
G01X47500Y715906D02*
X76594D01*
G01X76771Y715847D02*
X67401D01*
G01X49843Y715748D02*
X87126D01*
G01X49843Y714961D02*
X87126D01*
G01X76771Y714863D02*
X67401D01*
G01X76594Y714803D02*
X47500D01*
G01X76909Y714725D02*
X43307D01*
G01X46063Y714567D02*
X43307D01*
G01X77165D02*
X75197D01*
G01X51771Y714272D02*
X48031D01*
G01X76063D02*
X57677D01*
G01X49325Y714174D02*
X77480D01*
G01X70280Y713977D02*
X72437D01*
G01Y713583D02*
X70280D01*
G01X77480Y713386D02*
X49325D01*
G01X57677Y713288D02*
X76063D01*
G01X48031D02*
X51771D01*
G01X46063Y712992D02*
X43307D01*
G01X77165D02*
X75197D01*
G01X76909Y712835D02*
X43307D01*
G01X47500Y712756D02*
X76594D01*
G01X76771Y712697D02*
X67401D01*
G01X49843Y712599D02*
X87126D01*
G01X49843Y711811D02*
X87126D01*
G01X76771Y711713D02*
X67401D01*
G01X76594Y711654D02*
X47500D01*
G01X76909Y711575D02*
X43307D01*
G01X46063Y711418D02*
X43307D01*
G01X77165D02*
X75197D01*
G01X51771Y711122D02*
X48031D01*
G01X76063D02*
X57677D01*
G01X49325Y711024D02*
X77480D01*
G01X70280Y710827D02*
X72437D01*
G01Y710433D02*
X70280D01*
G01X49325Y710237D02*
X77480D01*
G01X57677Y710138D02*
X76063D01*
G01X48031D02*
X51771D01*
G01X46063Y709843D02*
X43307D01*
G01X77165D02*
X75197D01*
G01X76909Y709685D02*
X43307D01*
G01X47500Y709607D02*
X76594D01*
G01X76771Y709548D02*
X67401D01*
G01X49843Y709449D02*
X87126D01*
G01X49843Y708662D02*
X87126D01*
G01X76771Y708563D02*
X67401D01*
G01X76594Y708504D02*
X47500D01*
G01X76909Y708426D02*
X43307D01*
G01X46063Y708268D02*
X43307D01*
G01X77165D02*
X75197D01*
G01X51771Y707973D02*
X48031D01*
G01X76063D02*
X57677D01*
G01X49325Y707874D02*
X77480D01*
G01X70280Y707677D02*
X72437D01*
G01Y707284D02*
X70280D01*
G01X77480Y707087D02*
X49325D01*
G01X57677Y706989D02*
X76063D01*
G01X48031D02*
X51771D01*
G01X46063Y706693D02*
X43307D01*
G01X77165D02*
X75197D01*
G01X76909Y706536D02*
X43307D01*
G01X47500Y706457D02*
X76594D01*
G01X76771Y706398D02*
X67401D01*
G01X49843Y706300D02*
X87126D01*
G01X49843Y705512D02*
X87126D01*
G01X76771Y705414D02*
X67401D01*
G01X76594Y705355D02*
X47500D01*
G01X76909Y705276D02*
X43307D01*
G01X46063Y705118D02*
X43307D01*
G01X77165D02*
X75197D01*
G01X51771Y704823D02*
X48031D01*
G01X76063D02*
X57677D01*
G01X49325Y704725D02*
X77480D01*
G01X70280Y704528D02*
X72437D01*
G01Y704134D02*
X70280D01*
G01X77480Y703937D02*
X49325D01*
G01X57677Y703839D02*
X76063D01*
G01X48031D02*
X51771D01*
G01X46063Y703544D02*
X43307D01*
G01X77165D02*
X75197D01*
G01X76909Y703386D02*
X43307D01*
G01X47500Y703307D02*
X76594D01*
G01X76771Y703248D02*
X67401D01*
G01X49843Y703150D02*
X87126D01*
G01X49843Y702363D02*
X87126D01*
G01X76771Y702264D02*
X67401D01*
G01X76594Y702205D02*
X47500D01*
G01X76909Y702126D02*
X43307D01*
G01X46063Y701969D02*
X43307D01*
G01X77165D02*
X75197D01*
G01X51771Y701674D02*
X48031D01*
G01X76063D02*
X57677D01*
G01X49325Y701575D02*
X77480D01*
G01X70280Y701378D02*
X72437D01*
G01Y700985D02*
X70280D01*
G01X77480Y700788D02*
X49325D01*
G01X57677Y700689D02*
X76063D01*
G01X48031D02*
X51771D01*
G01X46063Y700394D02*
X43307D01*
G01X77165D02*
X75197D01*
G01X76909Y700237D02*
X43307D01*
G01X47500Y700158D02*
X76594D01*
G01X76771Y700099D02*
X67401D01*
G01X49843Y700000D02*
X87126D01*
G01X49843Y699213D02*
X87126D01*
G01X76771Y699115D02*
X67401D01*
G01X76594Y699055D02*
X47500D01*
G01X76909Y698977D02*
X43307D01*
G01X46063Y698819D02*
X43307D01*
G01X77165D02*
X75197D01*
G01X51771Y698524D02*
X48031D01*
G01X76063D02*
X57677D01*
G01X49325Y698426D02*
X77480D01*
G01X70280Y698229D02*
X72437D01*
G01Y697835D02*
X70280D01*
G01X77480Y697638D02*
X49325D01*
G01X57677Y697540D02*
X76063D01*
G01X48031D02*
X51771D01*
G01X46063Y697244D02*
X43307D01*
G01X77165D02*
X75197D01*
G01X76909Y697087D02*
X43307D01*
G01X47500Y697008D02*
X76594D01*
G01X28340Y742225D02*
X18175Y741692D01*
G01X28366Y741240D02*
X18226Y740709D01*
G01X55417Y734531D02*
X56573Y734646D01*
G01X55417Y731382D02*
X56573Y731496D01*
G01X55417Y728232D02*
X56573Y728347D01*
G01X55417Y725083D02*
X56573Y725197D01*
G01X55417Y721933D02*
X56573Y722048D01*
G01X55417Y718783D02*
X56573Y718898D01*
G01X55417Y715634D02*
X56573Y715748D01*
G01X55417Y712484D02*
X56573Y712599D01*
G01X55417Y709335D02*
X56573Y709449D01*
G01X55417Y706185D02*
X56573Y706300D01*
G01X55417Y703035D02*
X56573Y703150D01*
G01X55417Y699886D02*
X56573Y700000D01*
G01X54319Y734020D02*
X53420Y733859D01*
G01X54319Y730870D02*
X53420Y730709D01*
G01X54319Y727720D02*
X53420Y727559D01*
G01X54319Y724571D02*
X53420Y724410D01*
G01X54319Y721421D02*
X53420Y721260D01*
G01X54319Y718272D02*
X53420Y718111D01*
G01X54319Y715122D02*
X53420Y714961D01*
G01X53270Y732284D02*
X53864Y732398D01*
G01X53270Y729134D02*
X53864Y729249D01*
G01X53270Y725985D02*
X53864Y726099D01*
G01X53270Y722835D02*
X53864Y722950D01*
G01X53270Y719685D02*
X53864Y719800D01*
G01X65595Y740945D02*
X60620Y739982D01*
G01X60807Y739016D02*
X65689Y739961D01*
G01X55658Y732966D02*
X56175Y733071D01*
G01X55658Y729816D02*
X56175Y729922D01*
G01X55658Y726666D02*
X56175Y726772D01*
G01X55658Y723517D02*
X56175Y723622D01*
G01X55658Y720367D02*
X56175Y720473D01*
G01X55193Y734496D02*
X55217Y734501D01*
G01X55193Y731346D02*
X55217Y731352D01*
G01X55193Y728197D02*
X55217Y728202D01*
G01X55193Y725047D02*
X55217Y725052D01*
G01X55193Y721898D02*
X55217Y721903D01*
G01X49108Y734449D02*
X49843Y734646D01*
G01X54319Y711972D02*
X53420Y711811D01*
G01X54319Y708823D02*
X53420Y708662D01*
G01X54319Y705673D02*
X53420Y705512D01*
G01X54319Y702524D02*
X53420Y702363D01*
G01X54319Y699374D02*
X53420Y699213D01*
G01X53270Y716536D02*
X53864Y716650D01*
G01X53270Y713386D02*
X53864Y713501D01*
G01X53270Y710237D02*
X53864Y710351D01*
G01X53270Y707087D02*
X53864Y707202D01*
G01X53270Y703937D02*
X53864Y704052D01*
G01X53270Y700788D02*
X53864Y700902D01*
G01X53270Y697638D02*
X53864Y697753D01*
G01X55658Y717218D02*
X56175Y717323D01*
G01X55658Y714068D02*
X56175Y714174D01*
G01X55658Y710918D02*
X56175Y711024D01*
G01X55658Y707769D02*
X56175Y707874D01*
G01X55658Y704619D02*
X56175Y704725D01*
G01X55658Y701470D02*
X56175Y701575D01*
G01X55658Y698320D02*
X56175Y698426D01*
G01X55193Y718748D02*
X55217Y718753D01*
G01X55193Y715598D02*
X55217Y715603D01*
G01X55193Y712449D02*
X55217Y712454D01*
G01X55193Y709299D02*
X55217Y709304D01*
G01X55193Y706150D02*
X55217Y706155D01*
G01X55193Y703000D02*
X55217Y703005D01*
G01X55193Y699850D02*
X55217Y699855D01*
G01X49108Y731300D02*
X49843Y731496D01*
G01X49109Y728150D02*
X49843Y728347D01*
G01X49109Y725000D02*
X49843Y725197D01*
G01X49108Y721851D02*
X49843Y722048D01*
G01X49108Y718701D02*
X49843Y718898D01*
G01X49109Y715552D02*
X49843Y715748D01*
G01X49109Y712402D02*
X49843Y712599D01*
G01X49109Y709252D02*
X49843Y709449D01*
G01X49109Y706103D02*
X49843Y706300D01*
G01X49109Y702953D02*
X49843Y703150D01*
G01X49109Y699803D02*
X49843Y700000D01*
G01X49117Y718305D02*
X49118Y718703D01*
G01X49117Y721455D02*
X49118Y721853D01*
G01X49117Y730903D02*
X49118Y731302D01*
G01X49117Y734053D02*
X49118Y734452D01*
G01X49117Y699407D02*
X49118Y699806D01*
G01X49117Y702557D02*
X49118Y702955D01*
G01X49117Y705707D02*
X49118Y706105D01*
G01X49117Y708856D02*
X49118Y709255D01*
G01X49117Y712006D02*
X49118Y712404D01*
G01X49117Y715155D02*
X49118Y715554D01*
G01X49117Y724604D02*
X49118Y725003D01*
G01X49117Y727754D02*
X49118Y728152D01*
G01X77756Y703150D02*
Y702363D01*
G01Y700000D02*
Y699213D01*
G01Y706300D02*
Y705512D01*
G01Y712599D02*
Y711811D01*
G01Y709449D02*
Y708662D01*
G01Y715748D02*
Y714961D01*
G01Y722048D02*
Y721260D01*
G01Y718898D02*
Y718111D01*
G01Y725197D02*
Y724410D01*
G01Y731496D02*
Y730709D01*
G01Y728347D02*
Y727559D01*
G01Y734646D02*
Y733859D01*
G01X77480Y732284D02*
Y733071D01*
G01Y729134D02*
Y729922D01*
G01Y725985D02*
Y726772D01*
G01Y722835D02*
Y723622D01*
G01Y719685D02*
Y720473D01*
G01Y716536D02*
Y717323D01*
G01Y713386D02*
Y714174D01*
G01Y710237D02*
Y711024D01*
G01Y707087D02*
Y707874D01*
G01Y703937D02*
Y704725D01*
G01Y700788D02*
Y701575D01*
G01Y697638D02*
Y698426D01*
G01X76890Y732284D02*
Y733071D01*
G01Y729134D02*
Y729922D01*
G01Y725985D02*
Y726772D01*
G01Y722835D02*
Y723622D01*
G01Y719685D02*
Y720473D01*
G01Y716536D02*
Y717323D01*
G01Y713386D02*
Y714174D01*
G01Y710237D02*
Y711024D01*
G01Y707087D02*
Y707874D01*
G01Y703937D02*
Y704725D01*
G01Y700788D02*
Y701575D01*
G01Y697638D02*
Y698426D01*
G01X76771Y703248D02*
Y702264D01*
G01Y700099D02*
Y699115D01*
G01Y706398D02*
Y705414D01*
G01Y712697D02*
Y711713D01*
G01Y709548D02*
Y708563D01*
G01Y715847D02*
Y714863D01*
G01Y722146D02*
Y721162D01*
G01Y718996D02*
Y718012D01*
G01Y725296D02*
Y724311D01*
G01Y731595D02*
Y730611D01*
G01Y728445D02*
Y727461D01*
G01Y734744D02*
Y733760D01*
G01X76594Y731654D02*
Y733701D01*
G01Y728504D02*
Y730552D01*
G01Y725355D02*
Y727402D01*
G01Y722205D02*
Y724252D01*
G01Y719055D02*
Y721103D01*
G01Y715906D02*
Y717953D01*
G01Y712756D02*
Y714803D01*
G01Y709607D02*
Y711654D01*
G01Y706457D02*
Y708504D01*
G01Y703307D02*
Y705355D01*
G01Y700158D02*
Y702205D01*
G01Y697008D02*
Y699055D01*
G01X76575Y733859D02*
Y734646D01*
G01Y730709D02*
Y731496D01*
G01Y727559D02*
Y728347D01*
G01Y724410D02*
Y725197D01*
G01Y721260D02*
Y722048D01*
G01Y718111D02*
Y718898D01*
G01Y714961D02*
Y715748D01*
G01Y711811D02*
Y712599D01*
G01Y708662D02*
Y709449D01*
G01Y705512D02*
Y706300D01*
G01Y702363D02*
Y703150D01*
G01Y699213D02*
Y700000D01*
G01X76063Y698524D02*
Y697540D01*
G01Y701674D02*
Y700689D01*
G01Y707973D02*
Y706989D01*
G01Y704823D02*
Y703839D01*
G01Y711122D02*
Y710138D01*
G01Y717422D02*
Y716437D01*
G01Y714272D02*
Y713288D01*
G01Y720571D02*
Y719587D01*
G01Y726870D02*
Y725886D01*
G01Y723721D02*
Y722737D01*
G01Y730020D02*
Y729036D01*
G01Y733170D02*
Y732185D01*
G01X75984Y732284D02*
Y733071D01*
G01Y729134D02*
Y729922D01*
G01Y725985D02*
Y726772D01*
G01Y722835D02*
Y723622D01*
G01Y719685D02*
Y720473D01*
G01Y716536D02*
Y717323D01*
G01Y713386D02*
Y714174D01*
G01Y710237D02*
Y711024D01*
G01Y707087D02*
Y707874D01*
G01Y703937D02*
Y704725D01*
G01Y700788D02*
Y701575D01*
G01Y697638D02*
Y698426D01*
G01X75787Y703150D02*
Y702363D01*
G01Y700000D02*
Y699213D01*
G01Y706300D02*
Y705512D01*
G01Y712599D02*
Y711811D01*
G01Y709449D02*
Y708662D01*
G01Y715748D02*
Y714961D01*
G01Y722048D02*
Y721260D01*
G01Y718898D02*
Y718111D01*
G01Y725197D02*
Y724410D01*
G01Y731496D02*
Y730709D01*
G01Y728347D02*
Y727559D01*
G01Y734646D02*
Y733859D01*
G01X75748Y698426D02*
Y697638D01*
G01Y701575D02*
Y700788D01*
G01Y707874D02*
Y707087D01*
G01Y704725D02*
Y703937D01*
G01Y711024D02*
Y710237D01*
G01Y717323D02*
Y716536D01*
G01Y714174D02*
Y713386D01*
G01Y720473D02*
Y719685D01*
G01Y726772D02*
Y725985D01*
G01Y723622D02*
Y722835D01*
G01Y729922D02*
Y729134D01*
G01Y733071D02*
Y732284D01*
G01X75669Y733859D02*
Y734646D01*
G01Y730709D02*
Y731496D01*
G01Y727559D02*
Y728347D01*
G01Y724410D02*
Y725197D01*
G01Y721260D02*
Y722048D01*
G01Y718111D02*
Y718898D01*
G01Y714961D02*
Y715748D01*
G01Y711811D02*
Y712599D01*
G01Y708662D02*
Y709449D01*
G01Y705512D02*
Y706300D01*
G01Y702363D02*
Y703150D01*
G01Y699213D02*
Y700000D01*
G01X75571Y732284D02*
Y733071D01*
G01Y729134D02*
Y729922D01*
G01Y725985D02*
Y726772D01*
G01Y722835D02*
Y723622D01*
G01Y719685D02*
Y720473D01*
G01Y716536D02*
Y717323D01*
G01Y713386D02*
Y714174D01*
G01Y710237D02*
Y711024D01*
G01Y707087D02*
Y707874D01*
G01Y703937D02*
Y704725D01*
G01Y700788D02*
Y701575D01*
G01Y697638D02*
Y698426D01*
G01X75197Y732284D02*
Y733071D01*
G01Y729134D02*
Y729922D01*
G01Y725985D02*
Y726772D01*
G01Y722835D02*
Y723622D01*
G01Y719685D02*
Y720473D01*
G01Y716536D02*
Y717323D01*
G01Y713386D02*
Y714174D01*
G01Y710237D02*
Y711024D01*
G01Y707087D02*
Y707874D01*
G01Y703937D02*
Y704725D01*
G01Y700788D02*
Y701575D01*
G01Y697638D02*
Y698426D01*
G01Y700394D02*
Y698819D01*
G01Y703544D02*
Y701969D01*
G01Y706693D02*
Y705118D01*
G01Y709843D02*
Y708268D01*
G01Y712992D02*
Y711418D01*
G01Y716142D02*
Y714567D01*
G01Y719292D02*
Y717717D01*
G01Y722441D02*
Y720866D01*
G01Y725591D02*
Y724016D01*
G01Y728740D02*
Y727166D01*
G01Y731890D02*
Y730315D01*
G01Y735040D02*
Y733465D01*
G01X75157Y698426D02*
Y697638D01*
G01Y701575D02*
Y700788D01*
G01Y707874D02*
Y707087D01*
G01Y704725D02*
Y703937D01*
G01Y711024D02*
Y710237D01*
G01Y717323D02*
Y716536D01*
G01Y714174D02*
Y713386D01*
G01Y720473D02*
Y719685D01*
G01Y726772D02*
Y725985D01*
G01Y723622D02*
Y722835D01*
G01Y729922D02*
Y729134D01*
G01Y733071D02*
Y732284D01*
G01X74055Y698426D02*
Y697638D01*
G01Y701575D02*
Y700788D01*
G01Y707874D02*
Y707087D01*
G01Y704725D02*
Y703937D01*
G01Y711024D02*
Y710237D01*
G01Y717323D02*
Y716536D01*
G01Y714174D02*
Y713386D01*
G01Y720473D02*
Y719685D01*
G01Y726772D02*
Y725985D01*
G01Y723622D02*
Y722835D01*
G01Y729922D02*
Y729134D01*
G01Y733071D02*
Y732284D01*
G01X73819D02*
Y733071D01*
G01Y729134D02*
Y729922D01*
G01Y725985D02*
Y726772D01*
G01Y722835D02*
Y723622D01*
G01Y719685D02*
Y720473D01*
G01Y716536D02*
Y717323D01*
G01Y713386D02*
Y714174D01*
G01Y710237D02*
Y711024D01*
G01Y707087D02*
Y707874D01*
G01Y703937D02*
Y704725D01*
G01Y700788D02*
Y701575D01*
G01Y697638D02*
Y698426D01*
G01X73779Y703150D02*
Y702363D01*
G01Y700000D02*
Y699213D01*
G01Y706300D02*
Y705512D01*
G01Y712599D02*
Y711811D01*
G01Y709449D02*
Y708662D01*
G01Y715748D02*
Y714961D01*
G01Y722048D02*
Y721260D01*
G01Y718898D02*
Y718111D01*
G01Y725197D02*
Y724410D01*
G01Y731496D02*
Y730709D01*
G01Y728347D02*
Y727559D01*
G01Y734646D02*
Y733859D01*
G01X73740Y703150D02*
Y702363D01*
G01Y700000D02*
Y699213D01*
G01Y706300D02*
Y705512D01*
G01Y712599D02*
Y711811D01*
G01Y709449D02*
Y708662D01*
G01Y715748D02*
Y714961D01*
G01Y722048D02*
Y721260D01*
G01Y718898D02*
Y718111D01*
G01Y725197D02*
Y724410D01*
G01Y731496D02*
Y730709D01*
G01Y728347D02*
Y727559D01*
G01Y734646D02*
Y733859D01*
G01X73641Y732284D02*
Y733071D01*
G01Y729134D02*
Y729922D01*
G01Y725985D02*
Y726772D01*
G01Y722835D02*
Y723622D01*
G01Y719685D02*
Y720473D01*
G01Y716536D02*
Y717323D01*
G01Y713386D02*
Y714174D01*
G01Y710237D02*
Y711024D01*
G01Y707087D02*
Y707874D01*
G01Y703937D02*
Y704725D01*
G01Y700788D02*
Y701575D01*
G01Y697638D02*
Y698426D01*
G01X73501Y733859D02*
Y734646D01*
G01Y730709D02*
Y731496D01*
G01Y727559D02*
Y728347D01*
G01Y724410D02*
Y725197D01*
G01Y721260D02*
Y722048D01*
G01Y718111D02*
Y718898D01*
G01Y714961D02*
Y715748D01*
G01Y711811D02*
Y712599D01*
G01Y708662D02*
Y709449D01*
G01Y705512D02*
Y706300D01*
G01Y702363D02*
Y703150D01*
G01Y699213D02*
Y700000D01*
G01X73464Y698426D02*
Y697638D01*
G01Y701575D02*
Y700788D01*
G01Y707874D02*
Y707087D01*
G01Y704725D02*
Y703937D01*
G01Y711024D02*
Y710237D01*
G01Y717323D02*
Y716536D01*
G01Y714174D02*
Y713386D01*
G01Y720473D02*
Y719685D01*
G01Y726772D02*
Y725985D01*
G01Y723622D02*
Y722835D01*
G01Y729922D02*
Y729134D01*
G01Y733071D02*
Y732284D01*
G01X73228Y733701D02*
Y740945D01*
G01Y732284D02*
Y733071D01*
G01Y729134D02*
Y729922D01*
G01Y730552D02*
Y731654D01*
G01Y727402D02*
Y728504D01*
G01Y725985D02*
Y726772D01*
G01Y722835D02*
Y723622D01*
G01Y724252D02*
Y725355D01*
G01Y719685D02*
Y720473D01*
G01Y721103D02*
Y722205D01*
G01Y717953D02*
Y719055D01*
G01Y716536D02*
Y717323D01*
G01Y713386D02*
Y714174D01*
G01Y714803D02*
Y715906D01*
G01Y710237D02*
Y711024D01*
G01Y711654D02*
Y712756D01*
G01Y708504D02*
Y709607D01*
G01Y707087D02*
Y707874D01*
G01Y703937D02*
Y704725D01*
G01Y705355D02*
Y706457D01*
G01Y700788D02*
Y701575D01*
G01Y702205D02*
Y703307D01*
G01Y699055D02*
Y700158D01*
G01Y697638D02*
Y698426D01*
G01X73208Y732185D02*
Y733170D01*
G01Y729036D02*
Y730020D01*
G01Y725886D02*
Y726870D01*
G01Y722737D02*
Y723721D01*
G01Y719587D02*
Y720571D01*
G01Y716437D02*
Y717422D01*
G01Y713288D02*
Y714272D01*
G01Y710138D02*
Y711122D01*
G01Y706989D02*
Y707973D01*
G01Y703839D02*
Y704823D01*
G01Y700689D02*
Y701674D01*
G01Y697540D02*
Y698524D01*
G01X73149Y698426D02*
Y697638D01*
G01Y701575D02*
Y700788D01*
G01Y707874D02*
Y707087D01*
G01Y704725D02*
Y703937D01*
G01Y711024D02*
Y710237D01*
G01Y717323D02*
Y716536D01*
G01Y714174D02*
Y713386D01*
G01Y720473D02*
Y719685D01*
G01Y726772D02*
Y725985D01*
G01Y723622D02*
Y722835D01*
G01Y729922D02*
Y729134D01*
G01Y733071D02*
Y732284D01*
G01X72893Y732185D02*
Y733170D01*
G01Y729036D02*
Y730020D01*
G01Y725886D02*
Y726870D01*
G01Y722737D02*
Y723721D01*
G01Y719587D02*
Y720571D01*
G01Y716437D02*
Y717422D01*
G01Y713288D02*
Y714272D01*
G01Y710138D02*
Y711122D01*
G01Y706989D02*
Y707973D01*
G01Y703839D02*
Y704823D01*
G01Y700689D02*
Y701674D01*
G01Y697540D02*
Y698524D01*
G01X72855Y698426D02*
Y697638D01*
G01Y701575D02*
Y700788D01*
G01Y707874D02*
Y707087D01*
G01Y704725D02*
Y703937D01*
G01Y711024D02*
Y710237D01*
G01Y717323D02*
Y716536D01*
G01Y714174D02*
Y713386D01*
G01Y720473D02*
Y719685D01*
G01Y726772D02*
Y725985D01*
G01Y723622D02*
Y722835D01*
G01Y729922D02*
Y729134D01*
G01Y733071D02*
Y732284D01*
G01X72834Y698426D02*
Y697638D01*
G01Y701575D02*
Y700788D01*
G01Y707874D02*
Y707087D01*
G01Y704725D02*
Y703937D01*
G01Y711024D02*
Y710237D01*
G01Y717323D02*
Y716536D01*
G01Y714174D02*
Y713386D01*
G01Y720473D02*
Y719685D01*
G01Y726772D02*
Y725985D01*
G01Y723622D02*
Y722835D01*
G01Y729922D02*
Y729134D01*
G01Y733071D02*
Y732284D01*
G01X72795Y732293D02*
Y733062D01*
G01Y729143D02*
Y729913D01*
G01Y725994D02*
Y726763D01*
G01Y722844D02*
Y723613D01*
G01Y719694D02*
Y720464D01*
G01Y716545D02*
Y717314D01*
G01Y713395D02*
Y714165D01*
G01Y710246D02*
Y711015D01*
G01Y707096D02*
Y707865D01*
G01Y703946D02*
Y704716D01*
G01Y700797D02*
Y701566D01*
G01Y697647D02*
Y698416D01*
G01X72783Y732284D02*
Y733071D01*
G01Y729134D02*
Y729922D01*
G01Y725985D02*
Y726772D01*
G01Y722835D02*
Y723622D01*
G01Y719685D02*
Y720473D01*
G01Y716536D02*
Y717323D01*
G01Y713386D02*
Y714174D01*
G01Y710237D02*
Y711024D01*
G01Y707087D02*
Y707874D01*
G01Y703937D02*
Y704725D01*
G01Y700788D02*
Y701575D01*
G01Y697638D02*
Y698426D01*
G01X72748D02*
Y697638D01*
G01Y701575D02*
Y700788D01*
G01Y707874D02*
Y707087D01*
G01Y704725D02*
Y703937D01*
G01Y711024D02*
Y710237D01*
G01Y717323D02*
Y716536D01*
G01Y714174D02*
Y713386D01*
G01Y720473D02*
Y719685D01*
G01Y726772D02*
Y725985D01*
G01Y723622D02*
Y722835D01*
G01Y729922D02*
Y729134D01*
G01Y733071D02*
Y732284D01*
G01X72693Y698314D02*
Y697750D01*
G01Y701463D02*
Y700899D01*
G01Y707763D02*
Y707198D01*
G01Y704613D02*
Y704049D01*
G01Y710912D02*
Y710348D01*
G01Y717211D02*
Y716647D01*
G01Y714062D02*
Y713498D01*
G01Y720361D02*
Y719797D01*
G01Y726660D02*
Y726096D01*
G01Y723511D02*
Y722946D01*
G01Y729810D02*
Y729246D01*
G01Y732959D02*
Y732395D01*
G01X72680Y703150D02*
Y702363D01*
G01Y700000D02*
Y699213D01*
G01Y706300D02*
Y705512D01*
G01Y712599D02*
Y711811D01*
G01Y709449D02*
Y708662D01*
G01Y715748D02*
Y714961D01*
G01Y722048D02*
Y721260D01*
G01Y718898D02*
Y718111D01*
G01Y725197D02*
Y724410D01*
G01Y731496D02*
Y730709D01*
G01Y728347D02*
Y727559D01*
G01Y734646D02*
Y733859D01*
G01X72667Y698426D02*
Y697638D01*
G01Y701575D02*
Y700788D01*
G01Y707874D02*
Y707087D01*
G01Y704725D02*
Y703937D01*
G01Y711024D02*
Y710237D01*
G01Y717323D02*
Y716536D01*
G01Y714174D02*
Y713386D01*
G01Y720473D02*
Y719685D01*
G01Y726772D02*
Y725985D01*
G01Y723622D02*
Y722835D01*
G01Y729922D02*
Y729134D01*
G01Y733071D02*
Y732284D01*
G01X72562Y733859D02*
Y734646D01*
G01Y730709D02*
Y731496D01*
G01Y727559D02*
Y728347D01*
G01Y724410D02*
Y725197D01*
G01Y721260D02*
Y722048D01*
G01Y718111D02*
Y718898D01*
G01Y714961D02*
Y715748D01*
G01Y711811D02*
Y712599D01*
G01Y708662D02*
Y709449D01*
G01Y705512D02*
Y706300D01*
G01Y702363D02*
Y703150D01*
G01Y699213D02*
Y700000D01*
G01X72441Y703307D02*
Y702205D01*
G01Y700158D02*
Y699055D01*
G01Y706457D02*
Y705355D01*
G01Y712756D02*
Y711654D01*
G01Y709607D02*
Y708504D01*
G01Y715906D02*
Y714803D01*
G01Y722205D02*
Y721103D01*
G01Y719055D02*
Y717953D01*
G01Y725355D02*
Y724252D01*
G01Y731654D02*
Y730552D01*
G01Y728504D02*
Y727402D01*
G01Y740945D02*
Y733701D01*
G01X72437Y732481D02*
Y732874D01*
G01Y729331D02*
Y729725D01*
G01Y726181D02*
Y726575D01*
G01Y723032D02*
Y723426D01*
G01Y719882D02*
Y720276D01*
G01Y716733D02*
Y717126D01*
G01Y713583D02*
Y713977D01*
G01Y710433D02*
Y710827D01*
G01Y707284D02*
Y707677D01*
G01Y704134D02*
Y704528D01*
G01Y700985D02*
Y701378D01*
G01Y697835D02*
Y698229D01*
G01X71653Y700689D02*
Y698524D01*
G01Y703839D02*
Y701674D01*
G01Y706989D02*
Y704823D01*
G01Y710138D02*
Y707973D01*
G01Y713288D02*
Y711122D01*
G01Y716437D02*
Y714272D01*
G01Y719587D02*
Y717422D01*
G01Y722737D02*
Y720571D01*
G01Y725886D02*
Y723721D01*
G01Y729036D02*
Y726870D01*
G01Y732185D02*
Y730020D01*
G01Y740945D02*
Y733170D01*
G01X71407Y703150D02*
Y702363D01*
G01Y700000D02*
Y699213D01*
G01Y706300D02*
Y705512D01*
G01Y712599D02*
Y711811D01*
G01Y709449D02*
Y708662D01*
G01Y715748D02*
Y714961D01*
G01Y722048D02*
Y721260D01*
G01Y718898D02*
Y718111D01*
G01Y725197D02*
Y724410D01*
G01Y731496D02*
Y730709D01*
G01Y728347D02*
Y727559D01*
G01Y734646D02*
Y733859D01*
G01X71385Y703150D02*
Y702363D01*
G01Y700000D02*
Y699213D01*
G01Y706300D02*
Y705512D01*
G01Y712599D02*
Y711811D01*
G01Y709449D02*
Y708662D01*
G01Y715748D02*
Y714961D01*
G01Y722048D02*
Y721260D01*
G01Y718898D02*
Y718111D01*
G01Y725197D02*
Y724410D01*
G01Y731496D02*
Y730709D01*
G01Y728347D02*
Y727559D01*
G01Y734646D02*
Y733859D01*
G01X71131D02*
Y734646D01*
G01Y730709D02*
Y731496D01*
G01Y727559D02*
Y728347D01*
G01Y724410D02*
Y725197D01*
G01Y721260D02*
Y722048D01*
G01Y718111D02*
Y718898D01*
G01Y714961D02*
Y715748D01*
G01Y711811D02*
Y712599D01*
G01Y708662D02*
Y709449D01*
G01Y705512D02*
Y706300D01*
G01Y702363D02*
Y703150D01*
G01Y699213D02*
Y700000D01*
G01X70472Y733859D02*
Y734646D01*
G01Y730709D02*
Y731496D01*
G01Y727559D02*
Y728347D01*
G01Y724410D02*
Y725197D01*
G01Y721260D02*
Y722048D01*
G01Y718111D02*
Y718898D01*
G01Y714961D02*
Y715748D01*
G01Y711811D02*
Y712599D01*
G01Y708662D02*
Y709449D01*
G01Y705512D02*
Y706300D01*
G01Y702363D02*
Y703150D01*
G01Y699213D02*
Y700000D01*
G01X70280Y698229D02*
Y697835D01*
G01Y701378D02*
Y700985D01*
G01Y707677D02*
Y707284D01*
G01Y704528D02*
Y704134D01*
G01Y710827D02*
Y710433D01*
G01Y717126D02*
Y716733D01*
G01Y713977D02*
Y713583D01*
G01Y720276D02*
Y719882D01*
G01Y726575D02*
Y726181D01*
G01Y723426D02*
Y723032D01*
G01Y729725D02*
Y729331D01*
G01Y732874D02*
Y732481D01*
G01X70024Y732395D02*
Y732959D01*
G01Y729246D02*
Y729810D01*
G01Y726096D02*
Y726660D01*
G01Y722946D02*
Y723511D01*
G01Y719797D02*
Y720361D01*
G01Y716647D02*
Y717211D01*
G01Y713498D02*
Y714062D01*
G01Y710348D02*
Y710912D01*
G01Y707198D02*
Y707763D01*
G01Y704049D02*
Y704613D01*
G01Y700899D02*
Y701463D01*
G01Y697750D02*
Y698314D01*
G01X69921Y698416D02*
Y697647D01*
G01Y701566D02*
Y700797D01*
G01Y707865D02*
Y707096D01*
G01Y704716D02*
Y703946D01*
G01Y711015D02*
Y710246D01*
G01Y717314D02*
Y716545D01*
G01Y714165D02*
Y713395D01*
G01Y720464D02*
Y719694D01*
G01Y726763D02*
Y725994D01*
G01Y723613D02*
Y722844D01*
G01Y729913D02*
Y729143D01*
G01Y733062D02*
Y732293D01*
G01X69882Y732185D02*
Y733170D01*
G01Y729036D02*
Y730020D01*
G01Y725886D02*
Y726870D01*
G01Y722737D02*
Y723721D01*
G01Y719587D02*
Y720571D01*
G01Y716437D02*
Y717422D01*
G01Y713288D02*
Y714272D01*
G01Y710138D02*
Y711122D01*
G01Y706989D02*
Y707973D01*
G01Y703839D02*
Y704823D01*
G01Y700689D02*
Y701674D01*
G01Y697540D02*
Y698524D01*
G01Y703150D02*
Y702363D01*
G01Y700000D02*
Y699213D01*
G01Y706300D02*
Y705512D01*
G01Y712599D02*
Y711811D01*
G01Y709449D02*
Y708662D01*
G01Y715748D02*
Y714961D01*
G01Y722048D02*
Y721260D01*
G01Y718898D02*
Y718111D01*
G01Y725197D02*
Y724410D01*
G01Y731496D02*
Y730709D01*
G01Y728347D02*
Y727559D01*
G01Y734646D02*
Y733859D01*
G01X69669Y732284D02*
Y733071D01*
G01Y729134D02*
Y729922D01*
G01Y725985D02*
Y726772D01*
G01Y722835D02*
Y723622D01*
G01Y719685D02*
Y720473D01*
G01Y716536D02*
Y717323D01*
G01Y713386D02*
Y714174D01*
G01Y710237D02*
Y711024D01*
G01Y707087D02*
Y707874D01*
G01Y703937D02*
Y704725D01*
G01Y700788D02*
Y701575D01*
G01Y697638D02*
Y698426D01*
G01X69567Y732185D02*
Y733170D01*
G01Y729036D02*
Y730020D01*
G01Y725886D02*
Y726870D01*
G01Y722737D02*
Y723721D01*
G01Y719587D02*
Y720571D01*
G01Y716437D02*
Y717422D01*
G01Y713288D02*
Y714272D01*
G01Y710138D02*
Y711122D01*
G01Y706989D02*
Y707973D01*
G01Y703839D02*
Y704823D01*
G01Y700689D02*
Y701674D01*
G01Y697540D02*
Y698524D01*
G01X69291Y733859D02*
Y734646D01*
G01Y730709D02*
Y731496D01*
G01Y727559D02*
Y728347D01*
G01Y724410D02*
Y725197D01*
G01Y721260D02*
Y722048D01*
G01Y718111D02*
Y718898D01*
G01Y714961D02*
Y715748D01*
G01Y711811D02*
Y712599D01*
G01Y708662D02*
Y709449D01*
G01Y705512D02*
Y706300D01*
G01Y702363D02*
Y703150D01*
G01Y699213D02*
Y700000D01*
G01X69252Y732185D02*
Y733170D01*
G01Y729036D02*
Y730020D01*
G01Y725886D02*
Y726870D01*
G01Y722737D02*
Y723721D01*
G01Y719587D02*
Y720571D01*
G01Y716437D02*
Y717422D01*
G01Y713288D02*
Y714272D01*
G01Y710138D02*
Y711122D01*
G01Y706989D02*
Y707973D01*
G01Y703839D02*
Y704823D01*
G01Y700689D02*
Y701674D01*
G01Y697540D02*
Y698524D01*
G01X69236Y698426D02*
Y697638D01*
G01Y701575D02*
Y700788D01*
G01Y707874D02*
Y707087D01*
G01Y704725D02*
Y703937D01*
G01Y711024D02*
Y710237D01*
G01Y717323D02*
Y716536D01*
G01Y714174D02*
Y713386D01*
G01Y720473D02*
Y719685D01*
G01Y726772D02*
Y725985D01*
G01Y723622D02*
Y722835D01*
G01Y729922D02*
Y729134D01*
G01Y733071D02*
Y732284D01*
G01X69012Y698426D02*
Y697638D01*
G01Y701575D02*
Y700788D01*
G01Y707874D02*
Y707087D01*
G01Y704725D02*
Y703937D01*
G01Y711024D02*
Y710237D01*
G01Y717323D02*
Y716536D01*
G01Y714174D02*
Y713386D01*
G01Y720473D02*
Y719685D01*
G01Y726772D02*
Y725985D01*
G01Y723622D02*
Y722835D01*
G01Y729922D02*
Y729134D01*
G01Y733071D02*
Y732284D01*
G01X68701Y703150D02*
Y702363D01*
G01Y700000D02*
Y699213D01*
G01Y706300D02*
Y705512D01*
G01Y712599D02*
Y711811D01*
G01Y709449D02*
Y708662D01*
G01Y715748D02*
Y714961D01*
G01Y722048D02*
Y721260D01*
G01Y718898D02*
Y718111D01*
G01Y725197D02*
Y724410D01*
G01Y731496D02*
Y730709D01*
G01Y728347D02*
Y727559D01*
G01Y734646D02*
Y733859D01*
G01X68578Y732284D02*
Y733071D01*
G01Y729134D02*
Y729922D01*
G01Y725985D02*
Y726772D01*
G01Y722835D02*
Y723622D01*
G01Y719685D02*
Y720473D01*
G01Y716536D02*
Y717323D01*
G01Y713386D02*
Y714174D01*
G01Y710237D02*
Y711024D01*
G01Y707087D02*
Y707874D01*
G01Y703937D02*
Y704725D01*
G01Y700788D02*
Y701575D01*
G01Y697638D02*
Y698426D01*
G01X68110Y733859D02*
Y734646D01*
G01Y730709D02*
Y731496D01*
G01Y727559D02*
Y728347D01*
G01Y724410D02*
Y725197D01*
G01Y721260D02*
Y722048D01*
G01Y718111D02*
Y718898D01*
G01Y714961D02*
Y715748D01*
G01Y711811D02*
Y712599D01*
G01Y708662D02*
Y709449D01*
G01Y705512D02*
Y706300D01*
G01Y702363D02*
Y703150D01*
G01Y699213D02*
Y700000D01*
G01X67382Y740945D02*
Y739961D01*
G01X67283Y740945D02*
Y739961D01*
G01X66201Y740945D02*
Y739961D01*
G01X65807D02*
Y740945D01*
G01X65019D02*
Y739831D01*
G01X60197Y739961D02*
Y738977D01*
G01X59704Y740945D02*
Y739961D01*
G01X59055Y735689D02*
Y740945D01*
G01X58267D02*
Y735689D01*
G01X57677Y731654D02*
Y732185D01*
G01Y733170D02*
Y733701D01*
G01Y728504D02*
Y729036D01*
G01Y730020D02*
Y730552D01*
G01Y723721D02*
Y724252D01*
G01Y725355D02*
Y725886D01*
G01Y726870D02*
Y727402D01*
G01Y719055D02*
Y719587D01*
G01Y720571D02*
Y721103D01*
G01Y722205D02*
Y722737D01*
G01Y714272D02*
Y714803D01*
G01Y715906D02*
Y716437D01*
G01Y717422D02*
Y717953D01*
G01Y709607D02*
Y710138D01*
G01Y711122D02*
Y711654D01*
G01Y712756D02*
Y713288D01*
G01Y704823D02*
Y705355D01*
G01Y706457D02*
Y706989D01*
G01Y707973D02*
Y708504D01*
G01Y700158D02*
Y700689D01*
G01Y701674D02*
Y702205D01*
G01Y703307D02*
Y703839D01*
G01Y697008D02*
Y697540D01*
G01Y698524D02*
Y699055D01*
G01X55658Y698320D02*
Y697744D01*
G01Y701470D02*
Y700893D01*
G01Y707769D02*
Y707192D01*
G01Y704619D02*
Y704043D01*
G01Y710918D02*
Y710342D01*
G01Y717218D02*
Y716641D01*
G01Y714068D02*
Y713492D01*
G01Y720367D02*
Y719791D01*
G01Y726666D02*
Y726090D01*
G01Y723517D02*
Y722940D01*
G01Y729816D02*
Y729240D01*
G01Y732966D02*
Y732389D01*
G01X55417Y733973D02*
Y734531D01*
G01Y730824D02*
Y731382D01*
G01Y727674D02*
Y728232D01*
G01Y724524D02*
Y725083D01*
G01Y721375D02*
Y721933D01*
G01Y718225D02*
Y718783D01*
G01Y715076D02*
Y715634D01*
G01Y711926D02*
Y712484D01*
G01Y708776D02*
Y709335D01*
G01Y705627D02*
Y706185D01*
G01Y702477D02*
Y703035D01*
G01Y699327D02*
Y699886D01*
G01X55314Y732284D02*
Y733071D01*
G01Y729134D02*
Y729922D01*
G01Y725985D02*
Y726772D01*
G01Y722835D02*
Y723622D01*
G01Y719685D02*
Y720473D01*
G01Y716536D02*
Y717323D01*
G01Y713386D02*
Y714174D01*
G01Y710237D02*
Y711024D01*
G01Y707087D02*
Y707874D01*
G01Y703937D02*
Y704725D01*
G01Y700788D02*
Y701575D01*
G01Y697638D02*
Y698426D01*
G01X55217Y703005D02*
Y702507D01*
G01Y699855D02*
Y699358D01*
G01Y706155D02*
Y705657D01*
G01Y712454D02*
Y711956D01*
G01Y709304D02*
Y708807D01*
G01Y715603D02*
Y715106D01*
G01Y721903D02*
Y721405D01*
G01Y718753D02*
Y718255D01*
G01Y725052D02*
Y724555D01*
G01Y731352D02*
Y730854D01*
G01Y728202D02*
Y727704D01*
G01Y734501D02*
Y734003D01*
G01X55193Y734009D02*
Y734496D01*
G01Y730859D02*
Y731346D01*
G01Y727709D02*
Y728197D01*
G01Y724560D02*
Y725047D01*
G01Y721410D02*
Y721898D01*
G01Y718261D02*
Y718748D01*
G01Y715111D02*
Y715598D01*
G01Y711961D02*
Y712449D01*
G01Y708812D02*
Y709299D01*
G01Y705662D02*
Y706150D01*
G01Y702513D02*
Y703000D01*
G01Y699363D02*
Y699850D01*
G01X55160Y703150D02*
Y702363D01*
G01Y700000D02*
Y699213D01*
G01Y706300D02*
Y705512D01*
G01Y712599D02*
Y711811D01*
G01Y709449D02*
Y708662D01*
G01Y715748D02*
Y714961D01*
G01Y722048D02*
Y721260D01*
G01Y718898D02*
Y718111D01*
G01Y725197D02*
Y724410D01*
G01Y731496D02*
Y730709D01*
G01Y728347D02*
Y727559D01*
G01Y734646D02*
Y733859D01*
G01X54977D02*
Y734646D01*
G01Y730709D02*
Y731496D01*
G01Y727559D02*
Y728347D01*
G01Y724410D02*
Y725197D01*
G01Y721260D02*
Y722048D01*
G01Y718111D02*
Y718898D01*
G01Y714961D02*
Y715748D01*
G01Y711811D02*
Y712599D01*
G01Y708662D02*
Y709449D01*
G01Y705512D02*
Y706300D01*
G01Y702363D02*
Y703150D01*
G01Y699213D02*
Y700000D01*
G01X54836Y703150D02*
Y702363D01*
G01Y700000D02*
Y699213D01*
G01Y706300D02*
Y705512D01*
G01Y712599D02*
Y711811D01*
G01Y709449D02*
Y708662D01*
G01Y715748D02*
Y714961D01*
G01Y722048D02*
Y721260D01*
G01Y718898D02*
Y718111D01*
G01Y725197D02*
Y724410D01*
G01Y731496D02*
Y730709D01*
G01Y728347D02*
Y727559D01*
G01Y734646D02*
Y733859D01*
G01X54619D02*
Y734646D01*
G01Y730709D02*
Y731496D01*
G01Y727559D02*
Y728347D01*
G01Y724410D02*
Y725197D01*
G01Y721260D02*
Y722048D01*
G01Y718111D02*
Y718898D01*
G01Y714961D02*
Y715748D01*
G01Y711811D02*
Y712599D01*
G01Y708662D02*
Y709449D01*
G01Y705512D02*
Y706300D01*
G01Y702363D02*
Y703150D01*
G01Y699213D02*
Y700000D01*
G01X54319Y702989D02*
Y702524D01*
G01Y699839D02*
Y699374D01*
G01Y706139D02*
Y705673D01*
G01Y712438D02*
Y711972D01*
G01Y709288D02*
Y708823D01*
G01Y715587D02*
Y715122D01*
G01Y721887D02*
Y721421D01*
G01Y718737D02*
Y718272D01*
G01Y725036D02*
Y724571D01*
G01Y731335D02*
Y730870D01*
G01Y728186D02*
Y727720D01*
G01Y734485D02*
Y734020D01*
G01X54289Y698426D02*
Y697638D01*
G01Y701575D02*
Y700788D01*
G01Y707874D02*
Y707087D01*
G01Y704725D02*
Y703937D01*
G01Y711024D02*
Y710237D01*
G01Y717323D02*
Y716536D01*
G01Y714174D02*
Y713386D01*
G01Y720473D02*
Y719685D01*
G01Y726772D02*
Y725985D01*
G01Y723622D02*
Y722835D01*
G01Y729922D02*
Y729134D01*
G01Y733071D02*
Y732284D01*
G01X53864Y732398D02*
Y732957D01*
G01Y729249D02*
Y729807D01*
G01Y726099D02*
Y726657D01*
G01Y722950D02*
Y723508D01*
G01Y719800D02*
Y720358D01*
G01Y716650D02*
Y717209D01*
G01Y713501D02*
Y714059D01*
G01Y710351D02*
Y710909D01*
G01Y707202D02*
Y707760D01*
G01Y704052D02*
Y704610D01*
G01Y700902D02*
Y701461D01*
G01Y697753D02*
Y698311D01*
G01X52756Y740945D02*
Y735689D01*
G01X52657Y740945D02*
Y737402D01*
G01X51771Y697540D02*
Y697008D01*
G01Y699055D02*
Y698524D01*
G01Y700689D02*
Y700158D01*
G01Y702205D02*
Y701674D01*
G01Y703839D02*
Y703307D01*
G01Y705355D02*
Y704823D01*
G01Y706989D02*
Y706457D01*
G01Y708504D02*
Y707973D01*
G01Y710138D02*
Y709607D01*
G01Y711654D02*
Y711122D01*
G01Y713288D02*
Y712756D01*
G01Y714803D02*
Y714272D01*
G01Y716437D02*
Y715906D01*
G01Y717953D02*
Y717422D01*
G01Y719587D02*
Y719055D01*
G01Y721103D02*
Y720571D01*
G01Y722737D02*
Y722205D01*
G01Y724252D02*
Y723721D01*
G01Y725886D02*
Y725355D01*
G01Y727402D02*
Y726870D01*
G01Y729036D02*
Y728504D01*
G01Y730552D02*
Y730020D01*
G01Y732185D02*
Y731654D01*
G01Y733701D02*
Y733170D01*
G01X50939Y698426D02*
Y697638D01*
G01Y701575D02*
Y700788D01*
G01Y707874D02*
Y707087D01*
G01Y704725D02*
Y703937D01*
G01Y711024D02*
Y710237D01*
G01Y717323D02*
Y716536D01*
G01Y714174D02*
Y713386D01*
G01Y720473D02*
Y719685D01*
G01Y726772D02*
Y725985D01*
G01Y723622D02*
Y722835D01*
G01Y729922D02*
Y729134D01*
G01Y733071D02*
Y732284D01*
G01X50468Y733859D02*
Y734646D01*
G01Y730709D02*
Y731496D01*
G01Y727559D02*
Y728347D01*
G01Y724410D02*
Y725197D01*
G01Y721260D02*
Y722048D01*
G01Y718111D02*
Y718898D01*
G01Y714961D02*
Y715748D01*
G01Y711811D02*
Y712599D01*
G01Y708662D02*
Y709449D01*
G01Y705512D02*
Y706300D01*
G01Y702363D02*
Y703150D01*
G01Y699213D02*
Y700000D01*
G01X50393Y735689D02*
Y740945D01*
G01X49656Y732284D02*
Y733071D01*
G01Y729134D02*
Y729922D01*
G01Y725985D02*
Y726772D01*
G01Y722835D02*
Y723622D01*
G01Y719685D02*
Y720473D01*
G01Y716536D02*
Y717323D01*
G01Y713386D02*
Y714174D01*
G01Y710237D02*
Y711024D01*
G01Y707087D02*
Y707874D01*
G01Y703937D02*
Y704725D01*
G01Y700788D02*
Y701575D01*
G01Y697638D02*
Y698426D01*
G01X49629Y703092D02*
Y702420D01*
G01Y699943D02*
Y699270D01*
G01Y706242D02*
Y705570D01*
G01Y712541D02*
Y711869D01*
G01Y709392D02*
Y708719D01*
G01Y715691D02*
Y715018D01*
G01Y721990D02*
Y721318D01*
G01Y718840D02*
Y718168D01*
G01Y725140D02*
Y724467D01*
G01Y731439D02*
Y730766D01*
G01Y728289D02*
Y727617D01*
G01Y734589D02*
Y733916D01*
G01X49606Y740945D02*
Y735689D01*
G01X49406Y698426D02*
Y697638D01*
G01Y701575D02*
Y700788D01*
G01Y707874D02*
Y707087D01*
G01Y704725D02*
Y703937D01*
G01Y711024D02*
Y710237D01*
G01Y717323D02*
Y716536D01*
G01Y714174D02*
Y713386D01*
G01Y720473D02*
Y719685D01*
G01Y726772D02*
Y725985D01*
G01Y723622D02*
Y722835D01*
G01Y729922D02*
Y729134D01*
G01Y733071D02*
Y732284D01*
G01X49366Y703022D02*
Y702490D01*
G01Y699872D02*
Y699341D01*
G01Y706172D02*
Y705640D01*
G01Y712471D02*
Y711939D01*
G01Y709321D02*
Y708790D01*
G01Y715620D02*
Y715089D01*
G01Y721920D02*
Y721388D01*
G01Y718770D02*
Y718239D01*
G01Y725069D02*
Y724538D01*
G01Y731368D02*
Y730837D01*
G01Y728219D02*
Y727687D01*
G01Y734518D02*
Y733987D01*
G01X49361Y733988D02*
Y734517D01*
G01Y730838D02*
Y731367D01*
G01Y727689D02*
Y728218D01*
G01Y724539D02*
Y725068D01*
G01Y721389D02*
Y721918D01*
G01Y718240D02*
Y718769D01*
G01Y715090D02*
Y715619D01*
G01Y711940D02*
Y712470D01*
G01Y708791D02*
Y709320D01*
G01Y705641D02*
Y706170D01*
G01Y702492D02*
Y703021D01*
G01Y699342D02*
Y699871D01*
G01X49353Y732284D02*
Y733071D01*
G01Y729134D02*
Y729922D01*
G01Y725985D02*
Y726772D01*
G01Y722835D02*
Y723622D01*
G01Y719685D02*
Y720473D01*
G01Y716536D02*
Y717323D01*
G01Y713386D02*
Y714174D01*
G01Y710237D02*
Y711024D01*
G01Y707087D02*
Y707874D01*
G01Y703937D02*
Y704725D01*
G01Y700788D02*
Y701575D01*
G01Y697638D02*
Y698426D01*
G01X49325Y732284D02*
Y733071D01*
G01Y729134D02*
Y729922D01*
G01Y725985D02*
Y726772D01*
G01Y722835D02*
Y723622D01*
G01Y719685D02*
Y720473D01*
G01Y716536D02*
Y717323D01*
G01Y713386D02*
Y714174D01*
G01Y710237D02*
Y711024D01*
G01Y707087D02*
Y707874D01*
G01Y703937D02*
Y704725D01*
G01Y700788D02*
Y701575D01*
G01Y697638D02*
Y698426D01*
G01X49109Y702953D02*
Y702559D01*
G01Y699803D02*
Y699410D01*
G01Y706103D02*
Y705709D01*
G01Y712402D02*
Y712008D01*
G01Y709252D02*
Y708859D01*
G01Y715552D02*
Y715158D01*
G01Y721852D02*
Y721457D01*
G01Y718702D02*
Y718307D01*
G01Y725000D02*
Y724607D01*
G01Y731301D02*
Y730906D01*
G01Y728150D02*
Y727756D01*
G01Y734450D02*
Y734055D01*
G01X48031Y698524D02*
Y697540D01*
G01Y701674D02*
Y700689D01*
G01Y704823D02*
Y703839D01*
G01Y707973D02*
Y706989D01*
G01Y711122D02*
Y710138D01*
G01Y714272D02*
Y713288D01*
G01Y717422D02*
Y716437D01*
G01Y720571D02*
Y719587D01*
G01Y723721D02*
Y722737D01*
G01Y726870D02*
Y725886D01*
G01Y730020D02*
Y729036D01*
G01Y733170D02*
Y732185D01*
G01X47500Y699055D02*
Y697008D01*
G01Y702205D02*
Y700158D01*
G01Y708504D02*
Y706457D01*
G01Y705355D02*
Y703307D01*
G01Y711654D02*
Y709607D01*
G01Y717953D02*
Y715906D01*
G01Y714803D02*
Y712756D01*
G01Y721103D02*
Y719055D01*
G01Y727402D02*
Y725355D01*
G01Y724252D02*
Y722205D01*
G01Y730552D02*
Y728504D01*
G01Y733701D02*
Y731654D01*
G01X46456Y746654D02*
Y780906D01*
G01X46063Y698819D02*
Y697244D01*
G01Y701969D02*
Y700394D01*
G01Y705118D02*
Y703544D01*
G01Y708268D02*
Y706693D01*
G01Y711418D02*
Y709843D01*
G01Y714567D02*
Y712992D01*
G01Y717717D02*
Y716142D01*
G01Y720866D02*
Y719292D01*
G01Y724016D02*
Y722441D01*
G01Y727166D02*
Y725591D01*
G01Y730315D02*
Y728740D01*
G01Y733465D02*
Y731890D01*
G01X44291Y740945D02*
Y735689D01*
G01X43996Y740945D02*
Y737402D01*
G01X42519Y750591D02*
Y752796D01*
G01Y753927D02*
Y753681D01*
G01Y762796D02*
Y754764D01*
G01Y772796D02*
Y764764D01*
G01X42126Y754764D02*
Y752796D01*
G01Y764764D02*
Y762796D01*
G01X41378Y754764D02*
Y752796D01*
G01Y764764D02*
Y762796D01*
G01X40551Y753681D02*
Y753927D01*
G01X40157Y762796D02*
Y764764D01*
G01Y754764D02*
Y752796D01*
G01Y755827D02*
Y752205D01*
G01Y766063D02*
Y761496D01*
G01X39390Y742225D02*
Y727559D01*
G01X38582Y775355D02*
Y752205D01*
G01X37401Y770792D02*
Y757612D01*
G01X34764Y741240D02*
Y742225D01*
G01X33582D02*
Y741240D01*
G01X33477Y742225D02*
Y741240D01*
G01X33182D02*
Y742225D01*
G01X31818D02*
Y741240D01*
G01X31523D02*
Y742225D01*
G01X31417D02*
Y741240D01*
G01X30236Y742225D02*
Y741240D01*
G01X49477Y732284D02*
Y733071D01*
G01Y729134D02*
Y729922D01*
G01Y725985D02*
Y726772D01*
G01Y722835D02*
Y723622D01*
G01Y719685D02*
Y720473D01*
G01Y716536D02*
Y717323D01*
G01Y713386D02*
Y714174D01*
G01Y710237D02*
Y711024D01*
G01Y707087D02*
Y707874D01*
G01Y703937D02*
Y704725D01*
G01Y700788D02*
Y701575D01*
G01Y697638D02*
Y698426D01*
G01X73449Y697540D02*
X73228Y697008D01*
G01X73449Y700689D02*
X73228Y700158D01*
G01X73449Y703839D02*
X73228Y703307D01*
G01X73449Y706989D02*
X73228Y706457D01*
G01X73449Y710138D02*
X73228Y709607D01*
G01X73449Y713288D02*
X73228Y712756D01*
G01X73449Y716437D02*
X73228Y715906D01*
G01X29350Y741240D02*
Y742225D01*
G01X28366D02*
Y741240D01*
G01X27362Y760473D02*
Y755355D01*
G01X21260Y761063D02*
Y758857D01*
G01Y764764D02*
Y762796D01*
G01X21063Y757677D02*
Y771223D01*
G01Y771810D02*
Y757612D01*
G01X20984Y741240D02*
Y742225D01*
G01X19803D02*
Y741240D01*
G01X19697Y742225D02*
Y741240D01*
G01X19685Y774213D02*
Y753347D01*
G01X19402Y741240D02*
Y742225D01*
G01X18038D02*
Y741240D01*
G01X17743D02*
Y742225D01*
G01X17638D02*
Y741240D01*
G01X17126Y757677D02*
Y771223D01*
G01X16456Y742225D02*
Y741240D01*
G01X16338Y757677D02*
Y770639D01*
G01X15748Y776969D02*
Y750591D01*
G01X13110Y741240D02*
Y742225D01*
G01X11929D02*
Y741240D01*
G01X11823Y742225D02*
Y741240D01*
G01X11528D02*
Y742225D01*
G01X10177D02*
Y741240D01*
G01X10164Y742225D02*
Y741240D01*
G01X9869D02*
Y742225D01*
G01X9764D02*
Y741240D01*
G01X8878Y720886D02*
Y714075D01*
G01X8582Y742225D02*
Y741240D01*
G01X7815Y742225D02*
Y741240D01*
G01X73449Y719587D02*
X73228Y719055D01*
G01X73449Y722737D02*
X73228Y722205D01*
G01X73449Y725886D02*
X73228Y725355D01*
G01X73449Y729036D02*
X73228Y728504D01*
G01X73449Y732185D02*
X73228Y731654D01*
G01X76594Y699055D02*
X76063Y698524D01*
G01X77165Y700492D02*
X76771Y700099D01*
G01X72972Y697540D02*
X72441Y697008D01*
G01D02*
X72972Y697540D01*
G01X76594Y702205D02*
X76063Y701674D01*
G01X72693Y698314D02*
X72795Y698416D01*
G01X77165Y703642D02*
X76771Y703248D01*
G01X72972Y700689D02*
X72441Y700158D01*
G01D02*
X72972Y700689D01*
G01X70024Y697750D02*
X69921Y697647D01*
G01X76594Y705355D02*
X76063Y704823D01*
G01X72693Y701463D02*
X72795Y701566D01*
G01X77165Y706792D02*
X76771Y706398D01*
G01X72972Y703839D02*
X72441Y703307D01*
G01D02*
X72972Y703839D01*
G01X70024Y700899D02*
X69921Y700797D01*
G01X76594Y708504D02*
X76063Y707973D01*
G01X72693Y704613D02*
X72795Y704716D01*
G01X77165Y709941D02*
X76771Y709548D01*
G01X72972Y706989D02*
X72441Y706457D01*
G01D02*
X72972Y706989D01*
G01X70024Y704049D02*
X69921Y703946D01*
G01X76594Y711654D02*
X76063Y711122D01*
G01X72693Y707763D02*
X72795Y707865D01*
G01X77165Y713091D02*
X76771Y712697D01*
G01X72972Y710138D02*
X72441Y709607D01*
G01D02*
X72972Y710138D01*
G01X70024Y707198D02*
X69921Y707096D01*
G01X76594Y714803D02*
X76063Y714272D01*
G01X72693Y710912D02*
X72795Y711015D01*
G01X77165Y716240D02*
X76771Y715847D01*
G01X72972Y713288D02*
X72441Y712756D01*
G01D02*
X72972Y713288D01*
G01X70024Y710348D02*
X69921Y710246D01*
G01X76594Y717953D02*
X76063Y717422D01*
G01X72693Y714062D02*
X72795Y714165D01*
G01X77165Y719390D02*
X76771Y718996D01*
G01X72972Y716437D02*
X72441Y715906D01*
G01D02*
X72972Y716437D01*
G01X70024Y713498D02*
X69921Y713395D01*
G01X76594Y721103D02*
X76063Y720571D01*
G01X72693Y717211D02*
X72795Y717314D01*
G01X77165Y722540D02*
X76771Y722146D01*
G01X72972Y719587D02*
X72441Y719055D01*
G01X70024Y716647D02*
X69921Y716545D01*
G01X72441Y719055D02*
X72972Y719587D01*
G01X76594Y724252D02*
X76063Y723721D01*
G01X72693Y720361D02*
X72795Y720464D01*
G01X77165Y725689D02*
X76771Y725296D01*
G01X48031Y697540D02*
X47500Y697008D01*
G01X72972Y722737D02*
X72441Y722205D01*
G01X70024Y719797D02*
X69921Y719694D01*
G01X72441Y722205D02*
X72972Y722737D01*
G01X76594Y727402D02*
X76063Y726870D01*
G01X72693Y723511D02*
X72795Y723613D01*
G01X77165Y728839D02*
X76771Y728445D01*
G01X48031Y700689D02*
X47500Y700158D01*
G01X72972Y725886D02*
X72441Y725355D01*
G01X70024Y722946D02*
X69921Y722844D01*
G01X72441Y725355D02*
X72972Y725886D01*
G01X76594Y730552D02*
X76063Y730020D01*
G01X72693Y726660D02*
X72795Y726763D01*
G01X77165Y731989D02*
X76771Y731595D01*
G01X48031Y703839D02*
X47500Y703307D01*
G01X72972Y729036D02*
X72441Y728504D01*
G01X70024Y726096D02*
X69921Y725994D01*
G01X72441Y728504D02*
X72972Y729036D01*
G01X76594Y733701D02*
X76063Y733170D01*
G01X72693Y729810D02*
X72795Y729913D01*
G01X77165Y735138D02*
X76771Y734744D01*
G01X48031Y706989D02*
X47500Y706457D01*
G01X72972Y732185D02*
X72441Y731654D01*
G01X70024Y729246D02*
X69921Y729143D01*
G01X72441Y731654D02*
X72972Y732185D01*
G01X72693Y732959D02*
X72795Y733062D01*
G01X48031Y710138D02*
X47500Y709607D01*
G01X70024Y732395D02*
X69921Y732293D01*
G01X48031Y713288D02*
X47500Y712756D01*
G01X13553Y740331D02*
X13045Y739487D01*
G01X11865Y741345D02*
X11358Y740501D01*
G01X40551Y762205D02*
X38582Y758662D01*
G01X48031Y716437D02*
X47500Y715906D01*
G01X48031Y719587D02*
X47500Y719055D01*
G01X48031Y722737D02*
X47500Y722205D01*
G01X48031Y725886D02*
X47500Y725355D01*
G01X48031Y729036D02*
X47500Y728504D01*
G01X48031Y732185D02*
X47500Y731654D01*
G01X17582Y740422D02*
X16383Y739223D01*
G01X16886Y741118D02*
X15687Y739919D01*
G01X26343Y768859D02*
X23031Y766496D01*
G01X46063Y835827D02*
G03X47244Y834646I1181J0D01*
G01Y838583D02*
G03X46063Y837402I0J-1181D01*
G01X27721Y772796D02*
G03X27131Y772205I1J-591D01*
G01X51575Y804843D02*
G03X50000Y803268I0J-1575D01*
G01X74803Y787402D02*
G03X78740Y791339I0J3937D01*
G01X30315Y795276D02*
G03X34252Y799213I0J3937D01*
G01X24409Y795276D02*
G03Y787402I0J-3937D01*
G01X8661D02*
G03Y795276I0J3937D01*
G01X74803Y787402D02*
G03X78740Y791339I0J3937D01*
G01X84606Y834646D02*
X47244D01*
G01X57874Y822441D02*
X50000D01*
G01X46063Y799922D02*
X47244Y798740D01*
G01X50000Y816536D02*
X57874D01*
G01X84606Y804843D02*
X51575D01*
G01X84606Y803662D02*
X46063D01*
G01X84606Y801693D02*
X46063D01*
G01X77559Y799823D02*
X73622D01*
G01X80669Y799607D02*
X77559D01*
G01X198701Y799331D02*
X77559D01*
G01X73622Y798740D02*
X47244D01*
G01X80669Y797835D02*
X77559D01*
G01Y797048D02*
X198701D01*
G01X77559Y795866D02*
X198701D01*
G01X77559Y795807D02*
X101535D01*
G01X24409Y795276D02*
X30315D01*
G01X73622Y794981D02*
X77559D01*
G01X198701Y791437D02*
X73622D01*
G01X206575Y787500D02*
X77559D01*
G01X24409Y787402D02*
X8661D01*
G01X15748Y776969D02*
X42519D01*
G01X38582Y775355D02*
X42519D01*
G01X15748Y774961D02*
X40157D01*
G01X23976Y774764D02*
X42126D01*
G01X42519D02*
X40157D01*
G01Y774213D02*
X19685D01*
G01X27721Y772796D02*
X42126D01*
G01X42519D02*
X40157D01*
G01X42519Y772205D02*
X40551D01*
G01X21063Y771810D02*
X15748D01*
G01X17126Y771260D02*
X21063D01*
G01X37401Y770792D02*
X21063D01*
G01X16338Y770670D02*
X17126D01*
G01X27131Y768859D02*
X26343D01*
G01X77559Y791437D02*
Y881792D01*
G01Y885729D02*
Y787500D01*
G01X73622Y881792D02*
Y791437D01*
G01X57874Y816536D02*
Y822441D01*
G01X51575Y804843D02*
Y801693D01*
G01X50000Y803268D02*
Y801693D01*
G01Y822441D02*
Y816536D01*
G01X47244Y874489D02*
Y798740D01*
G01X46063Y873307D02*
Y799922D01*
G01X42519Y774764D02*
Y776969D01*
G01X42126Y774764D02*
Y772796D01*
G01X41378Y774764D02*
Y772796D01*
G01X40157Y774764D02*
Y772796D01*
G01Y775355D02*
Y771811D01*
G01X34252Y799213D02*
Y889666D01*
G01X27131Y772205D02*
Y768859D01*
G01X21063Y768071D02*
X23976Y774764D01*
G01X40551Y772205D02*
X38582Y770237D01*
G01X34252Y893603D02*
Y1015079D01*
G01X38189Y893603D02*
G03X34252Y889666I0J-3937D01*
G01X66929Y893603D02*
G03X70866Y897540I0J3937D01*
G01X50000Y869961D02*
G03X51575Y868386I1575J0D01*
G01X38189Y893603D02*
X66929D01*
G01X77559Y885729D02*
X206575D01*
G01X73622Y881792D02*
X198701D01*
G01X77559Y878248D02*
X73622D01*
G01X101535Y877422D02*
X77559D01*
G01Y877363D02*
X198701D01*
G01Y876181D02*
X77559D01*
G01Y875394D02*
X80669D01*
G01X73622Y874489D02*
X47244D01*
G01X77559Y873898D02*
X198701D01*
G01X77559Y873622D02*
X80669D01*
G01X73622Y873406D02*
X77559D01*
G01X84606Y871536D02*
X46063D01*
G01X84606Y869567D02*
X46063D01*
G01X84606Y868386D02*
X51575D01*
G01X57874Y856693D02*
X50000D01*
G01Y850788D02*
X57874D01*
G01X47244Y838583D02*
X84606D01*
G01X70866Y897540D02*
Y929134D01*
G01X57874Y850788D02*
Y856693D01*
G01X51575Y871536D02*
Y868386D01*
G01X50000Y856693D02*
Y850788D01*
G01Y871536D02*
Y869961D01*
G01X46063Y873307D02*
X47244Y874489D01*
G01X74803Y933071D02*
G03X70866Y929134I0J-3937D01*
G01X74803Y933071D02*
X88582D01*
G01X68045Y1020817D02*
X67022Y1021585D01*
X66510Y1022481D01*
X66339Y1023504D01*
X66680Y1024784D01*
X67533Y1025680D01*
X68557Y1025935D01*
X69581Y1025808D01*
X70433Y1025296D01*
X72139Y1022737D01*
X73334Y1021585D01*
X75040Y1020817D01*
X76575Y1020562D01*
Y1025935D01*
G01X66339Y1033484D02*
X66680Y1032461D01*
X67533Y1031693D01*
X68557Y1031181D01*
X69922Y1030798D01*
X71457Y1030670D01*
X72993Y1030798D01*
X74357Y1031181D01*
X75381Y1031693D01*
X76234Y1032461D01*
X76575Y1033484D01*
X76234Y1034508D01*
X75381Y1035276D01*
X74357Y1035788D01*
X72993Y1036171D01*
X71457Y1036299D01*
X69922Y1036171D01*
X68557Y1035788D01*
X67533Y1035276D01*
X66680Y1034508D01*
X66339Y1033484D01*
G01X76916Y1043720D02*
X76746Y1043465D01*
X76404D01*
X76234Y1043720D01*
X76404Y1043976D01*
X76746D01*
X76916Y1043720D01*
G01X66339Y1053956D02*
X66680Y1052933D01*
X67533Y1052165D01*
X68557Y1051653D01*
X69922Y1051270D01*
X71457Y1051142D01*
X72993Y1051270D01*
X74357Y1051653D01*
X75381Y1052165D01*
X76234Y1052933D01*
X76575Y1053956D01*
X76234Y1054980D01*
X75381Y1055748D01*
X74357Y1056260D01*
X72993Y1056643D01*
X71457Y1056771D01*
X69922Y1056643D01*
X68557Y1056260D01*
X67533Y1055748D01*
X66680Y1054980D01*
X66339Y1053956D01*
G01Y1064192D02*
X66680Y1063169D01*
X67533Y1062401D01*
X68557Y1061889D01*
X69922Y1061506D01*
X71457Y1061378D01*
X72993Y1061506D01*
X74357Y1061889D01*
X75381Y1062401D01*
X76234Y1063169D01*
X76575Y1064192D01*
X76234Y1065216D01*
X75381Y1065984D01*
X74357Y1066496D01*
X72993Y1066879D01*
X71457Y1067007D01*
X69922Y1066879D01*
X68557Y1066496D01*
X67533Y1065984D01*
X66680Y1065216D01*
X66339Y1064192D01*
G01X32086Y1023248D02*
X31915Y1024144D01*
X31404Y1025168D01*
X30551Y1025808D01*
X29356Y1026063D01*
X28162Y1025808D01*
X27139Y1025040D01*
X26627Y1023888D01*
Y1022609D01*
X26286Y1021841D01*
X25433Y1021201D01*
X24239Y1020945D01*
X23044Y1021329D01*
X22191Y1022225D01*
X21850Y1023248D01*
X22191Y1024272D01*
X23044Y1025168D01*
X24239Y1025552D01*
X25433Y1025296D01*
X26286Y1024656D01*
X26627Y1023888D01*
Y1022609D01*
X27139Y1021457D01*
X28162Y1020689D01*
X29356Y1020434D01*
X30551Y1020689D01*
X31404Y1021329D01*
X31915Y1022353D01*
X32086Y1023248D01*
G01X32427Y1033484D02*
X32257Y1033229D01*
X31915D01*
X31745Y1033484D01*
X31915Y1033740D01*
X32257D01*
X32427Y1033484D01*
G01X32086Y1043465D02*
X29868Y1043720D01*
X27992Y1044104D01*
X26286Y1044616D01*
X24409Y1045256D01*
X21850Y1046280D01*
Y1041161D01*
G01Y1053956D02*
X22191Y1052933D01*
X23044Y1052165D01*
X24068Y1051653D01*
X25433Y1051270D01*
X26968Y1051142D01*
X28504Y1051270D01*
X29868Y1051653D01*
X30892Y1052165D01*
X31745Y1052933D01*
X32086Y1053956D01*
X31745Y1054980D01*
X30892Y1055748D01*
X29868Y1056260D01*
X28504Y1056643D01*
X26968Y1056771D01*
X25433Y1056643D01*
X24068Y1056260D01*
X23044Y1055748D01*
X22191Y1054980D01*
X21850Y1053956D01*
G01X81924Y-403774D02*
G03X82515Y-404364I590J0D01*
G01X87554Y-407238D02*
G03X86963Y-406648I-591J-1D01*
G01X82515D02*
G03X81924Y-407238I-1J-590D01*
G01X83302Y-392573D02*
G03X84286Y-393557I984J0D01*
G01X82318Y-388597D02*
X83302D01*
G01X82318Y-388636D02*
X78381D01*
G01X84286Y-393557D02*
X186180D01*
G01X85428Y-394541D02*
X82318D01*
G01X85428Y-395565D02*
X186180D01*
G01X82318Y-396510D02*
X85428D01*
G01X78381Y-397022D02*
X82318D01*
G01X85428Y-402337D02*
X82318D01*
G01X186180Y-402809D02*
X85428D01*
G01X82318Y-403518D02*
X85428D01*
G01X82515Y-404364D02*
X89089D01*
G01X89542Y-404817D02*
X186180D01*
G01X89798Y-405290D02*
X186180D01*
G01X86963Y-406648D02*
X82515D01*
G01X81534Y-411982D02*
X164211D01*
G01X89089Y-404364D02*
X89798Y-405073D01*
G01X122042Y-411982D02*
Y-405290D01*
G01X106294D02*
Y-411982D01*
G01X89798Y-405073D02*
Y-411982D01*
G01X87554D02*
Y-407238D01*
G01X85471Y-415329D02*
Y-411982D01*
G01X85428Y-404364D02*
Y-393557D01*
G01X83302Y-392573D02*
Y-388597D01*
G01X82318Y-388637D02*
Y-388597D01*
G01Y-404325D02*
Y-388639D01*
G01Y-411982D02*
Y-406688D01*
G01X81924Y-411982D02*
Y-401353D01*
G01X81534Y-411982D02*
Y-415329D01*
G01X78381Y-401353D02*
Y-388636D01*
G01X145627Y226688D02*
X144396Y226269D01*
G01Y227945D02*
X145627Y228363D01*
G01X111998Y227945D02*
X106256Y225013D01*
G01X103386D02*
X111178Y229201D01*
G01X133323Y215380D02*
X135374Y216636D01*
G01X128402Y234227D02*
X126352Y232971D01*
G01X132913Y217474D02*
X134143Y218312D01*
G01X128812Y232133D02*
X127582Y231295D01*
G01X135374Y216636D02*
X136604Y217893D01*
G01X144396Y226269D02*
X143576Y225432D01*
G01Y227107D02*
X144396Y227945D01*
G01X126352Y232971D02*
X125121Y231714D01*
G01X117740Y231295D02*
X115279Y228363D01*
G01Y231714D02*
X117740Y234646D01*
G01X134143Y218312D02*
X135784Y220825D01*
G01X127582Y231295D02*
X125941Y228782D01*
G01X111998Y222081D02*
X111178Y220825D01*
G01X136604Y217893D02*
X137425Y219568D01*
G01X125121Y231714D02*
X124301Y230039D01*
G01X137425Y219568D02*
X137834Y220825D01*
G01X124301Y230039D02*
X123891Y228782D01*
G01X137834Y220825D02*
X138245Y222919D01*
G01X135784Y220825D02*
X136194Y223338D01*
G01X123891Y228782D02*
X123481Y226688D01*
G01X125941Y228782D02*
X125531Y226269D01*
G01X148087Y214961D02*
Y225013D01*
G01X143576Y225432D02*
Y214961D01*
G01Y228363D02*
Y227107D01*
G01X141525Y214961D02*
Y228363D01*
G01X138245Y222919D02*
Y226688D01*
G01X136194Y223338D02*
Y226269D01*
G01X125531D02*
Y223338D01*
G01X123481Y226688D02*
Y222919D01*
G01X120200Y234646D02*
Y214961D01*
G01X117740D02*
Y231295D01*
G01X115279Y228363D02*
Y231714D01*
G01X100105Y234646D02*
Y214961D01*
G01X136194Y226269D02*
X135784Y228782D01*
G01X125531Y223338D02*
X125941Y220825D01*
G01X138245Y226688D02*
X137834Y228782D01*
G01X123481Y222919D02*
X123891Y220825D01*
G01X137834Y228782D02*
X137425Y230039D01*
G01X123891Y220825D02*
X124301Y219568D01*
G01X97644Y226688D02*
Y234646D01*
G01Y214961D02*
Y224175D01*
G01X86161D02*
Y214961D01*
G01Y234646D02*
Y226688D01*
G01X83701Y214961D02*
Y234646D01*
G01X148087Y225013D02*
X147677Y225850D01*
G01X137425Y230039D02*
X136604Y231714D01*
G01X124301Y219568D02*
X125121Y217893D01*
G01X135784Y228782D02*
X134143Y231295D01*
G01X125941Y220825D02*
X127582Y218312D01*
G01X111178Y229201D02*
X111998Y227945D01*
G01X147677Y225850D02*
X147267Y226269D01*
G01X136604Y231714D02*
X135374Y232971D01*
G01X125121Y217893D02*
X126352Y216636D01*
G01X134143Y231295D02*
X132913Y232133D01*
G01X127582Y218312D02*
X128812Y217474D01*
G01X135374Y232971D02*
X133323Y234227D01*
G01X126352Y216636D02*
X128402Y215380D01*
G01X111178Y220825D02*
X103386Y225013D01*
G01X147267Y226269D02*
X146447Y226688D01*
G01X106256Y225013D02*
X111998Y222081D01*
G01X147267Y228363D02*
X148497Y227945D01*
G01X132913Y232133D02*
X130863Y232552D01*
G01X128812Y217474D02*
X130863Y217055D01*
G01X133323Y234227D02*
X130863Y234646D01*
G01X128402Y215380D02*
X130863Y214961D01*
G01X117740Y234646D02*
X120200D01*
G01X97644D02*
X100105D01*
G01X83701D02*
X86161D01*
G01X145627Y228363D02*
X147267D01*
G01X141525D02*
X143576D01*
G01X86161Y226688D02*
X97644D01*
G01X146447D02*
X145627D01*
G01X97644Y224175D02*
X86161D01*
G01Y214961D02*
X83701D01*
G01X100105D02*
X97644D01*
G01X120200D02*
X117740D01*
G01X143576D02*
X141525D01*
G01X150138D02*
X148087D01*
G01X130863Y234646D02*
X128402Y234227D01*
G01X130863Y214961D02*
X133323Y215380D01*
G01X130863Y232552D02*
X128812Y232133D01*
G01X130863Y217055D02*
X132913Y217474D01*
G01X80712Y400321D02*
X155515D01*
G01Y482998D02*
X80712D01*
G01X138478Y517328D02*
X138888Y516072D01*
G01X140938Y516490D02*
X140118Y518585D01*
G01X129455Y512721D02*
X128635Y514396D01*
G01X126175D02*
X126995Y512721D01*
G01X137657Y518585D02*
X138478Y517328D01*
G01X108540Y523611D02*
X109360Y522354D01*
G01X140118Y518585D02*
X138888Y520260D01*
G01X126995Y512721D02*
X128225Y511046D01*
G01X140118Y512721D02*
X140938Y514815D01*
G01X138888Y515234D02*
X138478Y513977D01*
G01X146269Y519841D02*
Y509370D01*
G01Y522773D02*
Y521516D01*
G01X144219Y509370D02*
Y522773D01*
G01X140938Y514815D02*
Y516490D01*
G01X140118Y526961D02*
Y529055D01*
G01X138888Y516072D02*
Y515234D01*
G01X128225Y520260D02*
Y526961D01*
G01X126175Y529055D02*
Y518166D01*
G01X122893Y511465D02*
Y509370D01*
G01X120843D02*
Y511465D01*
G01X117562Y529055D02*
Y509370D01*
G01X115102D02*
Y525705D01*
G01X112641Y522773D02*
Y526124D01*
G01X136427Y519422D02*
X137657Y518585D01*
G01X130686Y511883D02*
X129455Y512721D01*
G01X138888Y520260D02*
X136837Y521516D01*
G01X128225Y511046D02*
X130275Y509789D01*
G01X108540Y515234D02*
X100748Y519422D01*
G01X103619D02*
X109360Y516490D01*
G01X147090Y520679D02*
X146269Y519841D01*
G01X138888Y511046D02*
X140118Y512721D01*
G01X138478Y513977D02*
X137657Y512721D01*
G01X109360Y516490D02*
X108540Y515234D01*
G01X97467Y529055D02*
Y509370D01*
G01X95006Y521098D02*
Y529055D01*
G01Y509370D02*
Y518585D01*
G01X90590Y551181D02*
Y625985D01*
G01X88582Y554331D02*
Y557481D01*
G01X87795D02*
Y554331D01*
G01X85039Y561496D02*
Y554331D01*
G01X84252Y557481D02*
Y554331D01*
G01X83858Y557481D02*
Y554331D01*
G01X83523Y518585D02*
Y509370D01*
G01Y529055D02*
Y521098D01*
G01X83071Y557481D02*
Y554331D01*
G01X82283Y557481D02*
Y554331D01*
G01X81063Y509370D02*
Y529055D01*
G01X134787Y519841D02*
X136427Y519422D01*
G01X132326Y511465D02*
X130686Y511883D01*
G01X136837Y521516D02*
X134787Y521935D01*
G01X130275Y509789D02*
X132326Y509370D01*
G01X136837Y509789D02*
X138888Y511046D01*
G01X130275Y521516D02*
X128225Y520260D01*
G01X137657Y512721D02*
X136427Y511883D01*
G01X129045Y518166D02*
X130686Y519422D01*
G01X146269Y521516D02*
X147090Y522354D01*
G01X115102Y525705D02*
X112641Y522773D01*
G01Y526124D02*
X115102Y529055D01*
G01D02*
X117562D01*
G01X95006D02*
X97467D01*
G01X81063D02*
X83523D01*
G01X140118D02*
X126175D01*
G01X128225Y526961D02*
X140118D01*
G01X148320Y522773D02*
X149960D01*
G01X144219D02*
X146269D01*
G01X134787Y521935D02*
X132326D01*
G01X83523Y521098D02*
X95006D01*
G01X149140D02*
X148320D01*
G01X132326Y519841D02*
X134787D01*
G01X95006Y518585D02*
X83523D01*
G01X126175Y518166D02*
X129045D01*
G01X128635Y514396D02*
X126175D01*
G01X120843Y511465D02*
X122893D01*
G01X134787D02*
X132326D01*
G01Y509370D02*
X134787D01*
G01X83523D02*
X81063D01*
G01X97467D02*
X95006D01*
G01X117562D02*
X115102D01*
G01X122893D02*
X120843D01*
G01X146269D02*
X144219D01*
G01X148320Y521098D02*
X147090Y520679D01*
G01Y522354D02*
X148320Y522773D01*
G01X109360Y522354D02*
X103619Y519422D01*
G01X100748D02*
X108540Y523611D01*
G01X132326Y521935D02*
X130275Y521516D01*
G01X134787Y509370D02*
X136837Y509789D01*
G01X130686Y519422D02*
X132326Y519841D01*
G01X136427Y511883D02*
X134787Y511465D01*
G01X87462Y616099D02*
X87441Y616201D01*
G01X88006Y616181D02*
X88027Y616119D01*
G01X87588D02*
X87567Y616181D01*
G01X87964Y616016D02*
X87943Y616057D01*
G01X87525Y616016D02*
X87462Y616099D01*
G01X85039Y615040D02*
X84449Y615630D01*
G01X85039Y611890D02*
X84449Y612481D01*
G01X85039Y608740D02*
X84449Y609331D01*
G01X85039Y605591D02*
X84449Y606181D01*
G01X85039Y602441D02*
X84449Y603032D01*
G01X85039Y599292D02*
X84449Y599882D01*
G01X85039Y596142D02*
X84449Y596733D01*
G01X85039Y592992D02*
X84449Y593583D01*
G01X85039Y589843D02*
X84449Y590433D01*
G01X85039Y586693D02*
X84449Y587284D01*
G01X85039Y583544D02*
X84449Y584134D01*
G01X85039Y580394D02*
X84449Y580985D01*
G01X85039Y577244D02*
X84449Y577835D01*
G01X85039Y574095D02*
X84449Y574685D01*
G01X85039Y570945D02*
X84449Y571536D01*
G01X85039Y567796D02*
X84449Y568386D01*
G01X88027Y616119D02*
X88069Y616078D01*
G01X87629D02*
X87588Y616119D01*
G01X88278Y615770D02*
X88425Y615648D01*
G01X88258D02*
X88111Y615770D01*
G01X88048Y615955D02*
X87964Y616016D01*
G01X87608Y615955D02*
X87525Y616016D01*
G01X85039Y564646D02*
X84449Y565237D01*
G01X85039Y561496D02*
X84449Y562087D01*
G01X88069Y616078D02*
X88132Y616057D01*
G01X88111Y615935D02*
X88048Y615955D01*
G01X87692Y616057D02*
X87629Y616078D01*
G01X87671Y615935D02*
X87608Y615955D01*
G01X78740Y619685D02*
X83858D01*
G01X88582D02*
X84252D01*
G01X87441Y616693D02*
X88425D01*
G01X84449Y616654D02*
X82795D01*
G01X87567Y616570D02*
X87880D01*
G01X88299D02*
X88006D01*
G01X88132Y616057D02*
X88174D01*
G01X87755D02*
X87692D01*
G01X87776Y615935D02*
X87671D01*
G01X88195D02*
X88111D01*
G01Y615770D02*
X88278D01*
G01X87441Y615648D02*
X88258D01*
G01X82795Y615630D02*
X84449D01*
G01X88425Y615524D02*
X87441D01*
G01X84449Y613504D02*
X82795D01*
G01Y612481D02*
X84449D01*
G01X88425Y616201D02*
X88404Y616099D01*
G01X88582Y622835D02*
Y619685D01*
G01X88425Y615648D02*
Y615524D01*
G01Y616693D02*
Y616201D01*
G01X88299Y616181D02*
Y616570D01*
G01X88006D02*
Y616181D01*
G01X87880Y616570D02*
Y616181D01*
G01X87795Y622835D02*
Y619685D01*
G01X87567Y616181D02*
Y616570D01*
G01X87441Y615524D02*
Y615648D01*
G01Y616201D02*
Y616693D01*
G01X87126Y615748D02*
Y616536D01*
G01Y612599D02*
Y613386D01*
G01Y609449D02*
Y610237D01*
G01Y606300D02*
Y607087D01*
G01Y603150D02*
Y603937D01*
G01Y600000D02*
Y600788D01*
G01Y596851D02*
Y597638D01*
G01Y593701D02*
Y594489D01*
G01Y590552D02*
Y591339D01*
G01Y587402D02*
Y588189D01*
G01Y584252D02*
Y585040D01*
G01Y581103D02*
Y581890D01*
G01Y577953D02*
Y578740D01*
G01Y574803D02*
Y575591D01*
G01Y571654D02*
Y572441D01*
G01Y568504D02*
Y569292D01*
G01Y565355D02*
Y566142D01*
G01Y562205D02*
Y562992D01*
G01X86535Y615748D02*
Y616536D01*
G01Y612599D02*
Y613386D01*
G01Y609449D02*
Y610237D01*
G01Y606300D02*
Y607087D01*
G01Y603150D02*
Y603937D01*
G01Y600000D02*
Y600788D01*
G01Y596851D02*
Y597638D01*
G01Y593701D02*
Y594489D01*
G01Y590552D02*
Y591339D01*
G01Y587402D02*
Y588189D01*
G01Y584252D02*
Y585040D01*
G01Y581103D02*
Y581890D01*
G01Y577953D02*
Y578740D01*
G01Y574803D02*
Y575591D01*
G01Y571654D02*
Y572441D01*
G01Y568504D02*
Y569292D01*
G01Y565355D02*
Y566142D01*
G01Y562205D02*
Y562992D01*
G01X85630D02*
Y562205D01*
G01Y566142D02*
Y565355D01*
G01Y572441D02*
Y571654D01*
G01Y569292D02*
Y568504D01*
G01Y575591D02*
Y574803D01*
G01Y581890D02*
Y581103D01*
G01Y578740D02*
Y577953D01*
G01Y585040D02*
Y584252D01*
G01Y591339D02*
Y590552D01*
G01Y588189D02*
Y587402D01*
G01Y594489D02*
Y593701D01*
G01Y600788D02*
Y600000D01*
G01Y597638D02*
Y596851D01*
G01Y603937D02*
Y603150D01*
G01Y610237D02*
Y609449D01*
G01Y607087D02*
Y606300D01*
G01Y613386D02*
Y612599D01*
G01Y616536D02*
Y615748D01*
G01X85039Y562992D02*
Y562205D01*
G01Y566142D02*
Y565355D01*
G01Y564646D02*
Y563701D01*
G01Y567796D02*
Y566851D01*
G01Y572441D02*
Y571654D01*
G01Y569292D02*
Y568504D01*
G01Y570945D02*
Y570000D01*
G01Y575591D02*
Y574803D01*
G01Y574095D02*
Y573150D01*
G01Y577244D02*
Y576300D01*
G01Y581890D02*
Y581103D01*
G01Y578740D02*
Y577953D01*
G01Y580394D02*
Y579449D01*
G01Y585040D02*
Y584252D01*
G01Y583544D02*
Y582599D01*
G01Y586693D02*
Y585748D01*
G01Y591339D02*
Y590552D01*
G01Y588189D02*
Y587402D01*
G01Y589843D02*
Y588898D01*
G01Y594489D02*
Y593701D01*
G01Y592992D02*
Y592048D01*
G01Y596142D02*
Y595197D01*
G01Y600788D02*
Y600000D01*
G01Y597638D02*
Y596851D01*
G01Y599292D02*
Y598347D01*
G01Y603937D02*
Y603150D01*
G01Y602441D02*
Y601496D01*
G01Y605591D02*
Y604646D01*
G01Y610237D02*
Y609449D01*
G01Y607087D02*
Y606300D01*
G01Y608740D02*
Y607796D01*
G01Y613386D02*
Y612599D01*
G01Y611890D02*
Y610945D01*
G01Y615040D02*
Y614095D01*
G01Y616536D02*
Y615748D01*
G01Y622835D02*
Y617244D01*
G01X84330Y615748D02*
Y616536D01*
G01Y612599D02*
Y613386D01*
G01Y609449D02*
Y610237D01*
G01Y606300D02*
Y607087D01*
G01Y603150D02*
Y603937D01*
G01Y600000D02*
Y600788D01*
G01Y596851D02*
Y597638D01*
G01Y593701D02*
Y594489D01*
G01Y590552D02*
Y591339D01*
G01Y587402D02*
Y588189D01*
G01Y584252D02*
Y585040D01*
G01Y581103D02*
Y581890D01*
G01Y577953D02*
Y578740D01*
G01Y574803D02*
Y575591D01*
G01Y571654D02*
Y572441D01*
G01Y568504D02*
Y569292D01*
G01Y565355D02*
Y566142D01*
G01Y562205D02*
Y562992D01*
G01X84252Y622835D02*
Y619685D01*
G01X83858Y622835D02*
Y619685D01*
G01X83386Y615748D02*
Y616536D01*
G01Y612599D02*
Y613386D01*
G01Y609449D02*
Y610237D01*
G01Y606300D02*
Y607087D01*
G01Y603150D02*
Y603937D01*
G01Y600000D02*
Y600788D01*
G01Y596851D02*
Y597638D01*
G01Y593701D02*
Y594489D01*
G01Y590552D02*
Y591339D01*
G01Y587402D02*
Y588189D01*
G01Y584252D02*
Y585040D01*
G01Y581103D02*
Y581890D01*
G01Y577953D02*
Y578740D01*
G01Y574803D02*
Y575591D01*
G01Y571654D02*
Y572441D01*
G01Y568504D02*
Y569292D01*
G01Y565355D02*
Y566142D01*
G01Y562205D02*
Y562992D01*
G01X83071Y622835D02*
Y619685D01*
G01X82795Y563111D02*
Y562087D01*
G01Y566260D02*
Y565237D01*
G01Y569410D02*
Y568386D01*
G01Y572559D02*
Y571536D01*
G01Y575709D02*
Y574685D01*
G01Y578859D02*
Y577835D01*
G01Y582008D02*
Y580985D01*
G01Y585158D02*
Y584134D01*
G01Y588307D02*
Y587284D01*
G01Y591457D02*
Y590433D01*
G01Y594607D02*
Y593583D01*
G01Y597756D02*
Y596733D01*
G01Y600906D02*
Y599882D01*
G01Y604055D02*
Y603032D01*
G01Y607205D02*
Y606181D01*
G01Y610355D02*
Y609331D01*
G01Y613504D02*
Y612481D01*
G01Y616654D02*
Y615630D01*
G01X82283Y622835D02*
Y619685D01*
G01X82204Y562992D02*
Y562205D01*
G01Y566142D02*
Y565355D01*
G01Y572441D02*
Y571654D01*
G01Y569292D02*
Y568504D01*
G01Y575591D02*
Y574803D01*
G01Y581890D02*
Y581103D01*
G01Y578740D02*
Y577953D01*
G01Y585040D02*
Y584252D01*
G01Y591339D02*
Y590552D01*
G01Y588189D02*
Y587402D01*
G01Y594489D02*
Y593701D01*
G01Y600788D02*
Y600000D01*
G01Y597638D02*
Y596851D01*
G01Y603937D02*
Y603150D01*
G01Y610237D02*
Y609449D01*
G01Y607087D02*
Y606300D01*
G01Y613386D02*
Y612599D01*
G01Y616536D02*
Y615748D01*
G01X78740Y557481D02*
Y619685D01*
G01X84449Y610355D02*
X82795D01*
G01Y609331D02*
X84449D01*
G01Y607205D02*
X82795D01*
G01Y606181D02*
X84449D01*
G01Y604055D02*
X82795D01*
G01Y603032D02*
X84449D01*
G01Y600906D02*
X82795D01*
G01Y599882D02*
X84449D01*
G01Y597756D02*
X82795D01*
G01Y596733D02*
X84449D01*
G01Y594607D02*
X82795D01*
G01Y593583D02*
X84449D01*
G01Y591457D02*
X82795D01*
G01Y590433D02*
X84449D01*
G01Y588307D02*
X82795D01*
G01Y587284D02*
X84449D01*
G01Y585158D02*
X82795D01*
G01Y584134D02*
X84449D01*
G01Y582008D02*
X82795D01*
G01Y580985D02*
X84449D01*
G01Y578859D02*
X82795D01*
G01Y577835D02*
X84449D01*
G01Y575709D02*
X82795D01*
G01Y574685D02*
X84449D01*
G01Y572559D02*
X82795D01*
G01Y571536D02*
X84449D01*
G01Y569410D02*
X82795D01*
G01Y568386D02*
X84449D01*
G01Y566260D02*
X82795D01*
G01Y565237D02*
X84449D01*
G01Y563111D02*
X82795D01*
G01Y562087D02*
X84449D01*
G01X84252Y557481D02*
X88582D01*
G01X83858D02*
X78740D01*
G01X87943Y616057D02*
X87923Y616016D01*
G01X88278Y616119D02*
X88299Y616181D01*
G01X87880D02*
X87860Y616119D01*
G01X88237Y616078D02*
X88278Y616119D01*
G01X87860D02*
X87818Y616078D01*
G01X85039Y563701D02*
X84449Y563111D01*
G01X85039Y566851D02*
X84449Y566260D01*
G01X85039Y570000D02*
X84449Y569410D01*
G01X85039Y573150D02*
X84449Y572559D01*
G01X85039Y576300D02*
X84449Y575709D01*
G01X85039Y579449D02*
X84449Y578859D01*
G01X85039Y582599D02*
X84449Y582008D01*
G01X85039Y585748D02*
X84449Y585158D01*
G01X85039Y588898D02*
X84449Y588307D01*
G01X85039Y592048D02*
X84449Y591457D01*
G01X85039Y595197D02*
X84449Y594607D01*
G01X85039Y598347D02*
X84449Y597756D01*
G01X85039Y601496D02*
X84449Y600906D01*
G01X85039Y604646D02*
X84449Y604055D01*
G01X85039Y607796D02*
X84449Y607205D01*
G01X85039Y610945D02*
X84449Y610355D01*
G01X85039Y614095D02*
X84449Y613504D01*
G01X85039Y617244D02*
X84449Y616654D01*
G01X88404Y616099D02*
X88341Y616016D01*
G01D02*
X88258Y615955D01*
G01X87923Y616016D02*
X87839Y615955D01*
G01X88258D02*
X88195Y615935D01*
G01X88174Y616057D02*
X88237Y616078D01*
G01X87839Y615955D02*
X87776Y615935D01*
G01X87818Y616078D02*
X87755Y616057D01*
G01X142966Y648356D02*
X142556Y650869D01*
G01X145016Y648775D02*
X144606Y650869D01*
G01D02*
X144196Y652126D01*
G01X130663Y642911D02*
X131073Y641655D01*
G01X144196Y652126D02*
X143376Y653801D01*
G01X131073Y641655D02*
X131893Y639979D01*
G01X142556Y650869D02*
X140915Y653382D01*
G01X132713Y642911D02*
X134354Y640398D01*
G01X117949Y651288D02*
X118769Y650031D01*
G01X143376Y653801D02*
X142145Y655057D01*
G01X131893Y639979D02*
X133123Y638723D01*
G01X85039Y695355D02*
X84449Y695945D01*
G01X85039Y692205D02*
X84449Y692796D01*
G01X85039Y689055D02*
X84449Y689646D01*
G01X85039Y685906D02*
X84449Y686496D01*
G01X85039Y682756D02*
X84449Y683347D01*
G01X85039Y679607D02*
X84449Y680197D01*
G01X140915Y653382D02*
X139685Y654220D01*
G01X134354Y640398D02*
X135584Y639561D01*
G01X142145Y655057D02*
X140095Y656314D01*
G01X132303Y645424D02*
X132713Y642911D01*
G01X130253Y645005D02*
X130663Y642911D01*
G01X133123Y638723D02*
X135174Y637466D01*
G01X117949Y642911D02*
X110157Y647100D01*
G01X113028D02*
X118769Y644168D01*
G01X139685Y654220D02*
X137634Y654639D01*
G01X135584Y639561D02*
X137634Y639142D01*
G01X140095Y656314D02*
X137634Y656733D01*
G01X84449Y696969D02*
X82795D01*
G01Y695945D02*
X84449D01*
G01Y693819D02*
X82795D01*
G01Y692796D02*
X84449D01*
G01Y690670D02*
X82795D01*
G01Y689646D02*
X84449D01*
G01Y687520D02*
X82795D01*
G01Y686496D02*
X84449D01*
G01Y684370D02*
X82795D01*
G01Y683347D02*
X84449D01*
G01Y681221D02*
X82795D01*
G01Y680197D02*
X84449D01*
G01X144606Y642911D02*
X145016Y645005D01*
G01X142556Y642911D02*
X142966Y645424D01*
G01X148297Y637048D02*
Y650450D01*
G01X145016Y645005D02*
Y648775D01*
G01X142966Y645424D02*
Y648356D01*
G01X132303D02*
Y645424D01*
G01X130253Y648775D02*
Y645005D01*
G01X126972Y656733D02*
Y637048D01*
G01X124511D02*
Y653382D01*
G01X122051Y650450D02*
Y653801D01*
G01X106877Y656733D02*
Y637048D01*
G01X104416Y648775D02*
Y656733D01*
G01Y637048D02*
Y646262D01*
G01X135174Y637466D02*
X137634Y637048D01*
G01X84252Y675591D02*
X88582D01*
G01X83858D02*
X78740D01*
G01X124511Y656733D02*
X126972D01*
G01X104416D02*
X106877D01*
G01X90472D02*
X92933D01*
G01X148297Y650450D02*
X150348D01*
G01X92933Y648775D02*
X104416D01*
G01Y646262D02*
X92933D01*
G01Y637048D02*
X90472D01*
G01X106877D02*
X104416D01*
G01X126972D02*
X124511D01*
G01X150348D02*
X148297D01*
G01X137634Y656733D02*
X135174Y656314D01*
G01X143376Y639979D02*
X144196Y641655D01*
G01D02*
X144606Y642911D01*
G01X131073Y652126D02*
X130663Y650869D01*
G01D02*
X130253Y648775D01*
G01X132713Y650869D02*
X132303Y648356D01*
G01X92933Y646262D02*
Y637048D01*
G01Y656733D02*
Y648775D01*
G01X90590Y669292D02*
Y744095D01*
G01X90472Y637048D02*
Y656733D01*
G01X88582Y672441D02*
Y675591D01*
G01X87795D02*
Y672441D01*
G01X87126Y696063D02*
Y696851D01*
G01Y692914D02*
Y693701D01*
G01Y689764D02*
Y690552D01*
G01Y686615D02*
Y687402D01*
G01Y683465D02*
Y684252D01*
G01Y680315D02*
Y681103D01*
G01X86535Y696063D02*
Y696851D01*
G01Y692914D02*
Y693701D01*
G01Y689764D02*
Y690552D01*
G01Y686615D02*
Y687402D01*
G01Y683465D02*
Y684252D01*
G01Y680315D02*
Y681103D01*
G01X85630Y684252D02*
Y683465D01*
G01Y681103D02*
Y680315D01*
G01Y687402D02*
Y686615D01*
G01Y693701D02*
Y692914D01*
G01Y690552D02*
Y689764D01*
G01Y696851D02*
Y696063D01*
G01X85039Y679607D02*
Y672441D01*
G01Y684252D02*
Y683465D01*
G01Y681103D02*
Y680315D01*
G01Y682756D02*
Y681811D01*
G01Y687402D02*
Y686615D01*
G01Y685906D02*
Y684961D01*
G01Y689055D02*
Y688111D01*
G01Y693701D02*
Y692914D01*
G01Y690552D02*
Y689764D01*
G01Y692205D02*
Y691260D01*
G01Y696851D02*
Y696063D01*
G01Y695355D02*
Y694410D01*
G01X84330Y696063D02*
Y696851D01*
G01Y692914D02*
Y693701D01*
G01Y689764D02*
Y690552D01*
G01Y686615D02*
Y687402D01*
G01Y683465D02*
Y684252D01*
G01Y680315D02*
Y681103D01*
G01X84252Y675591D02*
Y672441D01*
G01X83858Y675591D02*
Y672441D01*
G01X83386Y696063D02*
Y696851D01*
G01Y692914D02*
Y693701D01*
G01Y689764D02*
Y690552D01*
G01Y686615D02*
Y687402D01*
G01Y683465D02*
Y684252D01*
G01Y680315D02*
Y681103D01*
G01X83071Y675591D02*
Y672441D01*
G01X82795Y681221D02*
Y680197D01*
G01Y684370D02*
Y683347D01*
G01Y687520D02*
Y686496D01*
G01Y690670D02*
Y689646D01*
G01Y693819D02*
Y692796D01*
G01Y696969D02*
Y695945D01*
G01X82283Y675591D02*
Y672441D01*
G01X82204Y684252D02*
Y683465D01*
G01Y681103D02*
Y680315D01*
G01Y687402D02*
Y686615D01*
G01Y693701D02*
Y692914D01*
G01Y690552D02*
Y689764D01*
G01Y696851D02*
Y696063D01*
G01X78740Y675591D02*
Y737796D01*
G01X137634Y637048D02*
X140095Y637466D01*
G01X137634Y654639D02*
X135584Y654220D01*
G01X137634Y639142D02*
X139685Y639561D01*
G01X140915Y640398D02*
X142556Y642911D01*
G01X134354Y653382D02*
X132713Y650869D01*
G01X118769Y644168D02*
X117949Y642911D01*
G01X131893Y653801D02*
X131073Y652126D01*
G01X142145Y638723D02*
X143376Y639979D01*
G01X133123Y655057D02*
X131893Y653801D01*
G01X124511Y653382D02*
X122051Y650450D01*
G01Y653801D02*
X124511Y656733D01*
G01X118769Y650031D02*
X113028Y647100D01*
G01X110157D02*
X117949Y651288D01*
G01X140095Y637466D02*
X142145Y638723D01*
G01X135174Y656314D02*
X133123Y655057D01*
G01X139685Y639561D02*
X140915Y640398D01*
G01X135584Y654220D02*
X134354Y653382D01*
G01X85039Y681811D02*
X84449Y681221D01*
G01X85039Y684961D02*
X84449Y684370D01*
G01X85039Y688111D02*
X84449Y687520D01*
G01X85039Y691260D02*
X84449Y690670D01*
G01X85039Y694410D02*
X84449Y693819D01*
G01X85039Y697559D02*
X84449Y696969D01*
G01X87964Y734127D02*
X87943Y734168D01*
G01X87525Y734127D02*
X87462Y734209D01*
G01X85039Y733150D02*
X84449Y733740D01*
G01X85039Y730000D02*
X84449Y730591D01*
G01X85039Y726851D02*
X84449Y727441D01*
G01X85039Y723701D02*
X84449Y724292D01*
G01X85039Y720552D02*
X84449Y721142D01*
G01X85039Y717402D02*
X84449Y717992D01*
G01X85039Y714252D02*
X84449Y714843D01*
G01X85039Y711103D02*
X84449Y711693D01*
G01X85039Y707953D02*
X84449Y708544D01*
G01X85039Y704803D02*
X84449Y705394D01*
G01X85039Y701654D02*
X84449Y702244D01*
G01X85039Y698504D02*
X84449Y699095D01*
G01X88027Y734229D02*
X88069Y734188D01*
G01X87629D02*
X87588Y734229D01*
G01X88278Y733881D02*
X88425Y733758D01*
G01X88258D02*
X88111Y733881D01*
G01X88048Y734065D02*
X87964Y734127D01*
G01X87608Y734065D02*
X87525Y734127D01*
G01X88069Y734188D02*
X88132Y734168D01*
G01X88111Y734045D02*
X88048Y734065D01*
G01X87692Y734168D02*
X87629Y734188D01*
G01X87671Y734045D02*
X87608Y734065D01*
G01X87462Y734209D02*
X87441Y734311D01*
G01X88006Y734291D02*
X88027Y734229D01*
G01X87588D02*
X87567Y734291D01*
G01X78740Y737796D02*
X83858D01*
G01X88582D02*
X84252D01*
G01X87441Y734803D02*
X88425D01*
G01X84449Y734764D02*
X82795D01*
G01X87567Y734680D02*
X87880D01*
G01X88299D02*
X88006D01*
G01X88132Y734168D02*
X88174D01*
G01X87755D02*
X87692D01*
G01X87776Y734045D02*
X87671D01*
G01X88195D02*
X88111D01*
G01Y733881D02*
X88278D01*
G01X87441Y733758D02*
X88258D01*
G01X82795Y733740D02*
X84449D01*
G01X88425Y733635D02*
X87441D01*
G01X84449Y731615D02*
X82795D01*
G01Y730591D02*
X84449D01*
G01Y728465D02*
X82795D01*
G01Y727441D02*
X84449D01*
G01Y725315D02*
X82795D01*
G01Y724292D02*
X84449D01*
G01Y722166D02*
X82795D01*
G01Y721142D02*
X84449D01*
G01Y719016D02*
X82795D01*
G01Y717992D02*
X84449D01*
G01Y715866D02*
X82795D01*
G01Y714843D02*
X84449D01*
G01Y712717D02*
X82795D01*
G01Y711693D02*
X84449D01*
G01Y709567D02*
X82795D01*
G01Y708544D02*
X84449D01*
G01Y706418D02*
X82795D01*
G01Y705394D02*
X84449D01*
G01Y703268D02*
X82795D01*
G01Y702244D02*
X84449D01*
G01Y700118D02*
X82795D01*
G01Y699095D02*
X84449D01*
G01X88582Y740945D02*
Y737796D01*
G01X88425Y733758D02*
Y733635D01*
G01Y734803D02*
Y734311D01*
G01X88299Y734291D02*
Y734680D01*
G01X88006D02*
Y734291D01*
G01X87880Y734680D02*
Y734291D01*
G01X87795Y740945D02*
Y737796D01*
G01X87567Y734291D02*
Y734680D01*
G01X87441Y733635D02*
Y733758D01*
G01Y734311D02*
Y734803D01*
G01X87126Y733859D02*
Y734646D01*
G01Y730709D02*
Y731496D01*
G01Y727559D02*
Y728347D01*
G01Y724410D02*
Y725197D01*
G01Y721260D02*
Y722048D01*
G01Y718111D02*
Y718898D01*
G01Y714961D02*
Y715748D01*
G01Y711811D02*
Y712599D01*
G01Y708662D02*
Y709449D01*
G01Y705512D02*
Y706300D01*
G01Y702363D02*
Y703150D01*
G01Y699213D02*
Y700000D01*
G01X86535Y733859D02*
Y734646D01*
G01Y730709D02*
Y731496D01*
G01Y727559D02*
Y728347D01*
G01Y724410D02*
Y725197D01*
G01Y721260D02*
Y722048D01*
G01Y718111D02*
Y718898D01*
G01Y714961D02*
Y715748D01*
G01Y711811D02*
Y712599D01*
G01Y708662D02*
Y709449D01*
G01Y705512D02*
Y706300D01*
G01Y702363D02*
Y703150D01*
G01Y699213D02*
Y700000D01*
G01X85630Y703150D02*
Y702363D01*
G01Y700000D02*
Y699213D01*
G01Y706300D02*
Y705512D01*
G01Y712599D02*
Y711811D01*
G01Y709449D02*
Y708662D01*
G01Y715748D02*
Y714961D01*
G01Y722048D02*
Y721260D01*
G01Y718898D02*
Y718111D01*
G01Y725197D02*
Y724410D01*
G01Y731496D02*
Y730709D01*
G01Y728347D02*
Y727559D01*
G01Y734646D02*
Y733859D01*
G01X85039Y698504D02*
Y697559D01*
G01Y703150D02*
Y702363D01*
G01Y700000D02*
Y699213D01*
G01Y701654D02*
Y700709D01*
G01Y706300D02*
Y705512D01*
G01Y704803D02*
Y703859D01*
G01Y707953D02*
Y707008D01*
G01Y712599D02*
Y711811D01*
G01Y709449D02*
Y708662D01*
G01Y711103D02*
Y710158D01*
G01Y715748D02*
Y714961D01*
G01Y714252D02*
Y713307D01*
G01Y717402D02*
Y716457D01*
G01Y722048D02*
Y721260D01*
G01Y718898D02*
Y718111D01*
G01Y720552D02*
Y719607D01*
G01Y725197D02*
Y724410D01*
G01Y723701D02*
Y722756D01*
G01Y726851D02*
Y725906D01*
G01Y731496D02*
Y730709D01*
G01Y728347D02*
Y727559D01*
G01Y730000D02*
Y729055D01*
G01Y734646D02*
Y733859D01*
G01Y733150D02*
Y732205D01*
G01Y740945D02*
Y735355D01*
G01X84330Y733859D02*
Y734646D01*
G01Y730709D02*
Y731496D01*
G01Y727559D02*
Y728347D01*
G01Y724410D02*
Y725197D01*
G01Y721260D02*
Y722048D01*
G01Y718111D02*
Y718898D01*
G01Y714961D02*
Y715748D01*
G01Y711811D02*
Y712599D01*
G01Y708662D02*
Y709449D01*
G01Y705512D02*
Y706300D01*
G01Y702363D02*
Y703150D01*
G01Y699213D02*
Y700000D01*
G01X84252Y740945D02*
Y737796D01*
G01X83858Y740945D02*
Y737796D01*
G01X83386Y733859D02*
Y734646D01*
G01Y730709D02*
Y731496D01*
G01Y727559D02*
Y728347D01*
G01Y724410D02*
Y725197D01*
G01Y721260D02*
Y722048D01*
G01Y718111D02*
Y718898D01*
G01Y714961D02*
Y715748D01*
G01Y711811D02*
Y712599D01*
G01Y708662D02*
Y709449D01*
G01Y705512D02*
Y706300D01*
G01Y702363D02*
Y703150D01*
G01Y699213D02*
Y700000D01*
G01X83071Y740945D02*
Y737796D01*
G01X82795Y700118D02*
Y699095D01*
G01Y703268D02*
Y702244D01*
G01Y706418D02*
Y705394D01*
G01Y709567D02*
Y708544D01*
G01Y712717D02*
Y711693D01*
G01Y715866D02*
Y714843D01*
G01Y719016D02*
Y717992D01*
G01Y722166D02*
Y721142D01*
G01Y725315D02*
Y724292D01*
G01Y728465D02*
Y727441D01*
G01Y731615D02*
Y730591D01*
G01Y734764D02*
Y733740D01*
G01X82283Y740945D02*
Y737796D01*
G01X82204Y703150D02*
Y702363D01*
G01Y700000D02*
Y699213D01*
G01Y706300D02*
Y705512D01*
G01Y712599D02*
Y711811D01*
G01Y709449D02*
Y708662D01*
G01Y715748D02*
Y714961D01*
G01Y722048D02*
Y721260D01*
G01Y718898D02*
Y718111D01*
G01Y725197D02*
Y724410D01*
G01Y731496D02*
Y730709D01*
G01Y728347D02*
Y727559D01*
G01Y734646D02*
Y733859D01*
G01X88278Y734229D02*
X88299Y734291D01*
G01X87880D02*
X87860Y734229D01*
G01X88425Y734311D02*
X88404Y734209D01*
G01X87943Y734168D02*
X87923Y734127D01*
G01X88237Y734188D02*
X88278Y734229D01*
G01X87860D02*
X87818Y734188D01*
G01X85039Y700709D02*
X84449Y700118D01*
G01X85039Y703859D02*
X84449Y703268D01*
G01X85039Y707008D02*
X84449Y706418D01*
G01X85039Y710158D02*
X84449Y709567D01*
G01X85039Y713307D02*
X84449Y712717D01*
G01X85039Y716457D02*
X84449Y715866D01*
G01X85039Y719607D02*
X84449Y719016D01*
G01X85039Y722756D02*
X84449Y722166D01*
G01X85039Y725906D02*
X84449Y725315D01*
G01X85039Y729055D02*
X84449Y728465D01*
G01X85039Y732205D02*
X84449Y731615D01*
G01X85039Y735355D02*
X84449Y734764D01*
G01X88404Y734209D02*
X88341Y734127D01*
G01D02*
X88258Y734065D01*
G01X87923Y734127D02*
X87839Y734065D01*
G01X88258D02*
X88195Y734045D01*
G01X88174Y734168D02*
X88237Y734188D01*
G01X87839Y734065D02*
X87776Y734045D01*
G01X87818Y734188D02*
X87755Y734168D01*
G01X146732Y798780D02*
G03I-1890J0D01*
G01X143738Y814855D02*
G03X145947I1104J-1863D01*
G01X145601Y810343D02*
G03X146874Y814855I-759J2650D01*
G01X142811D02*
G03X144084Y810343I2031J-1862D01*
G01X147716Y798780D02*
G03I-2874J0D01*
G01X147893Y812992D02*
G03I-3051J0D01*
G01Y798780D02*
G03I-3051J0D01*
G01X113346Y796851D02*
G03I-3937J0D01*
G01X114330D02*
G03I-4921J0D01*
G01X117283D02*
G03I-7874J0D01*
G01X138191Y814834D02*
X139372Y811783D01*
G01X138388Y815720D02*
X139618Y812570D01*
G01X143014Y815720D02*
X143998Y814243D01*
G01Y813308D02*
X145032Y811783D01*
G01X144293Y813800D02*
X145671Y811783D01*
G01X142374Y815720D02*
X143703Y813800D01*
G01X148424Y837008D02*
X140147D01*
G01X148424Y836221D02*
X140147D01*
G01X148424Y835433D02*
X140147D01*
G01X148424Y834646D02*
X140147D01*
G01X148424Y833859D02*
X140147D01*
G01X148424Y833071D02*
X140147D01*
G01X148424Y832284D02*
X140147D01*
G01X148424Y831496D02*
X140147D01*
G01X148424Y830709D02*
X140147D01*
G01X148424Y829922D02*
X140147D01*
G01X148424Y829134D02*
X140147D01*
G01X148424Y828347D02*
X140147D01*
G01X148424Y827559D02*
X140147D01*
G01X148424Y826772D02*
X140147D01*
G01X148424Y825985D02*
X140147D01*
G01X148424Y825197D02*
X140147D01*
G01X148424Y824410D02*
X140147D01*
G01X148424Y823622D02*
X140147D01*
G01X148424Y822835D02*
X140147D01*
G01X148424Y822048D02*
X140147D01*
G01X148424Y821260D02*
X140147D01*
G01X148424Y820473D02*
X140147D01*
G01X148424Y819685D02*
X140147D01*
G01X148424Y818898D02*
X140147D01*
G01X148424Y818111D02*
X140147D01*
G01X148424Y817323D02*
X140147D01*
G01X145112Y816929D02*
X164797D01*
G01X148424Y816536D02*
X140147D01*
G01X149264Y816113D02*
X137305D01*
G01X141538Y815720D02*
X140849D01*
G01X138388D02*
X137699D01*
G01X143014D02*
X142374D01*
G01X145622D02*
X144982D01*
G01X148706Y815498D02*
X133412D01*
G01X147541Y815031D02*
X147443D01*
G01X142811Y814855D02*
X146874D01*
G01X147443Y814637D02*
X148378D01*
G01X157534Y813386D02*
X136912D01*
G01X148378Y811783D02*
X148870D01*
G01X145032D02*
X145671D01*
G01X142325D02*
X142965D01*
G01X141045D02*
X141538D01*
G01X139372D02*
X139864D01*
G01X137699D02*
X138191D01*
G01X137305Y811389D02*
X149264D01*
G01X145601Y810343D02*
X144084D01*
G01X133412Y810237D02*
X178705D01*
G01X95236Y801693D02*
X190393D01*
G01X194764Y798642D02*
X80669D01*
G01X194764Y797835D02*
X80669D01*
G01X194764Y796674D02*
X80669D01*
G01X117283Y795807D02*
X160590D01*
G01X80669Y795650D02*
X194764D01*
G01X80669Y794666D02*
X194764D01*
G01X147788Y815080D02*
X147541Y815031D01*
G01X148424Y835433D02*
Y836221D01*
G01Y832284D02*
Y833071D01*
G01Y829134D02*
Y829922D01*
G01Y825985D02*
Y826772D01*
G01Y822835D02*
Y823622D01*
G01Y816536D02*
Y817323D01*
G01Y819685D02*
Y820473D01*
G01Y818898D02*
Y818111D01*
G01Y825197D02*
Y824410D01*
G01Y822048D02*
Y821260D01*
G01Y828347D02*
Y827559D01*
G01Y831496D02*
Y830709D01*
G01Y834646D02*
Y833859D01*
G01Y837796D02*
Y837008D01*
G01X148378Y814637D02*
Y811783D01*
G01X147456Y835433D02*
Y836221D01*
G01Y832284D02*
Y833071D01*
G01Y829134D02*
Y829922D01*
G01Y825985D02*
Y826772D01*
G01Y822835D02*
Y823622D01*
G01Y816536D02*
Y817323D01*
G01Y819685D02*
Y820473D01*
G01Y818898D02*
Y818111D01*
G01Y825197D02*
Y824410D01*
G01Y822048D02*
Y821260D01*
G01Y828347D02*
Y827559D01*
G01Y831496D02*
Y830709D01*
G01Y834646D02*
Y833859D01*
G01Y837796D02*
Y837008D01*
G01X147443Y815031D02*
Y814637D01*
G01X146552Y837008D02*
Y837796D01*
G01Y835433D02*
Y836221D01*
G01Y830709D02*
Y831496D01*
G01Y827559D02*
Y828347D01*
G01Y829134D02*
Y829922D01*
G01Y824410D02*
Y825197D01*
G01Y818898D02*
Y818111D01*
G01Y817323D02*
Y816536D01*
G01Y820473D02*
Y819685D01*
G01Y822048D02*
Y821260D01*
G01Y823622D02*
Y822835D01*
G01Y826772D02*
Y825985D01*
G01Y834646D02*
Y833859D01*
G01Y833071D02*
Y832284D01*
G01X145112Y856300D02*
Y816929D01*
G01X143910Y837008D02*
Y837796D01*
G01Y830709D02*
Y831496D01*
G01Y833859D02*
Y834646D01*
G01Y827559D02*
Y828347D01*
G01Y824410D02*
Y825197D01*
G01Y821260D02*
Y822048D01*
G01Y818111D02*
Y818898D01*
G01Y817323D02*
Y816536D01*
G01Y820473D02*
Y819685D01*
G01Y823622D02*
Y822835D01*
G01Y829922D02*
Y829134D01*
G01Y826772D02*
Y825985D01*
G01Y833071D02*
Y832284D01*
G01Y836221D02*
Y835433D01*
G01X141538Y811783D02*
Y815720D01*
G01X141045Y814834D02*
Y811783D01*
G01X140147Y837008D02*
Y837796D01*
G01Y830709D02*
Y831496D01*
G01Y833859D02*
Y834646D01*
G01Y827559D02*
Y828347D01*
G01Y821260D02*
Y822048D01*
G01Y818111D02*
Y818898D01*
G01Y817323D02*
Y816536D01*
G01Y820473D02*
Y819685D01*
G01Y825197D02*
Y824410D01*
G01Y823622D02*
Y822835D01*
G01Y829922D02*
Y829134D01*
G01Y826772D02*
Y825985D01*
G01Y833071D02*
Y832284D01*
G01Y836221D02*
Y835433D01*
G01X138569Y815498D02*
Y810237D01*
G01X138191Y811783D02*
Y814834D01*
G01X137699Y815720D02*
Y811783D01*
G01X137305Y816113D02*
Y811389D01*
G01X137191Y810237D02*
Y815498D01*
G01X136401Y860222D02*
Y813007D01*
G01X133412Y862992D02*
Y810237D01*
G01X117283Y791437D02*
Y795807D01*
G01X101535D02*
Y791437D01*
G01X95236Y871536D02*
Y801693D01*
G01X84606Y871536D02*
Y801693D01*
G01X80669Y799607D02*
Y794666D01*
G01X79527Y799607D02*
Y873622D01*
G01X78740Y791339D02*
Y921260D01*
G01Y791339D02*
Y921260D01*
G01X78543Y873622D02*
Y799607D01*
G01X140849Y815720D02*
X139618Y812570D01*
G01X141045Y814834D02*
X139864Y811783D01*
G01X148477Y815720D02*
X148427Y815572D01*
G01X145622Y815720D02*
X144293Y813800D01*
G01X143703D02*
X142325Y811783D01*
G01X143998Y813308D02*
X142965Y811783D01*
G01X144982Y815720D02*
X143998Y814243D01*
G01X148427Y815572D02*
X148280Y815375D01*
G01D02*
X148132Y815227D01*
G01D02*
X147935Y815129D01*
G01X136912Y813386D02*
X133412Y810786D01*
G01X147935Y815129D02*
X147788Y815080D01*
G01X165354Y905512D02*
G03I-9842J0D01*
G01X118110D02*
G03I-9843J0D01*
G01X174212D02*
G03I-18700J0D01*
G01X126968D02*
G03I-18701J0D01*
G01X146732Y874449D02*
G03I-1890J0D01*
G01X145947Y858374D02*
G03X143738I-1104J1863D01*
G01X144084Y862886D02*
G03X142811Y858374I758J-2650D01*
G01X146874D02*
G03X145601Y862886I-2032J1862D01*
G01X147716Y874449D02*
G03I-2874J0D01*
G01X147893Y860237D02*
G03I-3051J0D01*
G01Y874449D02*
G03I-3051J0D01*
G01X113346Y876378D02*
G03I-3937J0D01*
G01X114330D02*
G03I-4921J0D01*
G01X117283D02*
G03I-7874J0D01*
G01X136912Y859843D02*
X133412Y862443D01*
G01X78740Y885847D02*
X210512D01*
G01X80669Y878563D02*
X194764D01*
G01X80669Y877579D02*
X194764D01*
G01X160590Y877422D02*
X117283D01*
G01X194764Y876555D02*
X80669D01*
G01Y875394D02*
X194764D01*
G01X80669Y874587D02*
X194764D01*
G01X190393Y871536D02*
X95236D01*
G01X178705Y862992D02*
X133412D01*
G01X144084Y862886D02*
X145601D01*
G01X157534Y859843D02*
X136912D01*
G01X146874Y858374D02*
X142811D01*
G01X148706Y857731D02*
X133412D01*
G01X148424Y856693D02*
X140147D01*
G01X164797Y856300D02*
X145112D01*
G01X148424Y855906D02*
X140147D01*
G01X148424Y855118D02*
X140147D01*
G01X148424Y854331D02*
X140147D01*
G01X148424Y853544D02*
X140147D01*
G01X148424Y852756D02*
X140147D01*
G01X148424Y851969D02*
X140147D01*
G01X148424Y851181D02*
X140147D01*
G01X148424Y850394D02*
X140147D01*
G01X148424Y849607D02*
X140147D01*
G01X148424Y848819D02*
X140147D01*
G01X148424Y848032D02*
X140147D01*
G01X148424Y847244D02*
X140147D01*
G01X148424Y846457D02*
X140147D01*
G01X148424Y845670D02*
X140147D01*
G01X148424Y844882D02*
X140147D01*
G01X148424Y844095D02*
X140147D01*
G01X148424Y843307D02*
X140147D01*
G01X148424Y842520D02*
X140147D01*
G01X148424Y841733D02*
X140147D01*
G01X148424Y840945D02*
X140147D01*
G01X148424Y840158D02*
X140147D01*
G01X148424Y839370D02*
X140147D01*
G01X148424Y838583D02*
X140147D01*
G01X148424Y837796D02*
X140147D01*
G01X148424Y854331D02*
Y855118D01*
G01Y851181D02*
Y851969D01*
G01Y844882D02*
Y845670D01*
G01Y848032D02*
Y848819D01*
G01Y841733D02*
Y842520D01*
G01Y838583D02*
Y839370D01*
G01Y840945D02*
Y840158D01*
G01Y844095D02*
Y843307D01*
G01Y847244D02*
Y846457D01*
G01Y853544D02*
Y852756D01*
G01Y850394D02*
Y849607D01*
G01Y856693D02*
Y855906D01*
G01X147456Y854331D02*
Y855118D01*
G01Y851181D02*
Y851969D01*
G01Y844882D02*
Y845670D01*
G01Y848032D02*
Y848819D01*
G01Y841733D02*
Y842520D01*
G01Y838583D02*
Y839370D01*
G01Y840945D02*
Y840158D01*
G01Y844095D02*
Y843307D01*
G01Y847244D02*
Y846457D01*
G01Y853544D02*
Y852756D01*
G01Y850394D02*
Y849607D01*
G01Y856693D02*
Y855906D01*
G01X146552D02*
Y856693D01*
G01Y854331D02*
Y855118D01*
G01Y852756D02*
Y853544D01*
G01Y846457D02*
Y847244D01*
G01Y848032D02*
Y848819D01*
G01Y840158D02*
Y840945D01*
G01Y839370D02*
Y838583D01*
G01Y844095D02*
Y843307D01*
G01Y842520D02*
Y841733D01*
G01Y845670D02*
Y844882D01*
G01Y850394D02*
Y849607D01*
G01Y851969D02*
Y851181D01*
G01X143910Y855906D02*
Y856693D01*
G01Y852756D02*
Y853544D01*
G01Y849607D02*
Y850394D01*
G01Y846457D02*
Y847244D01*
G01Y840158D02*
Y840945D01*
G01Y843307D02*
Y844095D01*
G01Y839370D02*
Y838583D01*
G01Y842520D02*
Y841733D01*
G01Y845670D02*
Y844882D01*
G01Y848819D02*
Y848032D01*
G01Y851969D02*
Y851181D01*
G01Y855118D02*
Y854331D01*
G01X140147Y855906D02*
Y856693D01*
G01Y852756D02*
Y853544D01*
G01Y849607D02*
Y850394D01*
G01Y846457D02*
Y847244D01*
G01Y840158D02*
Y840945D01*
G01Y843307D02*
Y844095D01*
G01Y839370D02*
Y838583D01*
G01Y842520D02*
Y841733D01*
G01Y845670D02*
Y844882D01*
G01Y848819D02*
Y848032D01*
G01Y851969D02*
Y851181D01*
G01Y855118D02*
Y854331D01*
G01X138569Y857731D02*
Y862992D01*
G01X137191Y857731D02*
Y862992D01*
G01X117283Y877422D02*
Y881792D01*
G01X101535D02*
Y877422D01*
G01X80669Y878563D02*
Y873622D01*
G01X78740Y925197D02*
Y1015079D01*
G01X119291Y933071D02*
G03Y925197I0J-3937D01*
G01X82677D02*
G03X78740Y921260I0J-3937D01*
G01X88582Y925197D02*
G03Y933071I0J3937D01*
G01X82677Y925197D02*
G03X78740Y921260I0J-3937D01*
G01X119291Y933071D02*
X305118D01*
G01X82677Y925197D02*
X755905D01*
G01X82677D02*
X755905D01*
G01X119291D02*
X88582D01*
G01X183905Y-436039D02*
X186180Y-436786D01*
G01D02*
X188700Y-429108D01*
G01X186180D02*
X183905Y-436039D01*
G01X207487Y-399736D02*
G03X204178Y-394541I-3309J1544D01*
G01X205180Y-407014D02*
G03X204962Y-409503I3309J-1544D01*
G01X204287Y-406598D02*
G03X204011Y-409757I4202J-1959D01*
G01X208380Y-400152D02*
G03X204178Y-393557I-4201J1959D01*
G01X188700Y-391786D02*
X186180D01*
G01X204178Y-393557D02*
X188700D01*
G01X199522Y-394541D02*
X204178D01*
G01X188700Y-395565D02*
X199522D01*
G01Y-396510D02*
X203459D01*
G01Y-402337D02*
X199522D01*
G01Y-402809D02*
X188700D01*
G01X186180Y-403045D02*
X188700D01*
G01X199522Y-403518D02*
X203459D01*
G01X188700Y-404817D02*
X199522D01*
G01X203459Y-405290D02*
X188700D01*
G01X204602Y-411963D02*
X205553Y-411708D01*
G01X182440Y-411982D02*
X192440D01*
G01Y-417730D02*
X203459D01*
G01X181097D02*
X182440D01*
G01X205553Y-411708D02*
X204962Y-409503D01*
G01X205180Y-407014D02*
X208380Y-400152D01*
G01X207487Y-399736D02*
X204287Y-406598D01*
G01X204011Y-409757D02*
X204602Y-411963D01*
G01X203459Y-422612D02*
Y-394541D01*
G01X199522Y-393557D02*
Y-404817D01*
G01X192440Y-422612D02*
Y-411982D01*
G01X191076D02*
Y-422612D01*
G01X188700Y-411982D02*
Y-391786D01*
G01X186180Y-411982D02*
Y-391786D01*
G01X183804Y-422612D02*
Y-411982D01*
G01X182440D02*
Y-422612D01*
G01X181097Y-417730D02*
Y-405290D01*
G01X179959Y-415329D02*
Y-422612D01*
G01X176022Y-415329D02*
Y-422612D01*
G01X165349Y-405290D02*
Y-415329D01*
G01X164211Y-411982D02*
Y-415329D01*
G01X160274Y-411982D02*
Y-415329D01*
G01X200787Y45276D02*
Y783563D01*
G01Y9843D02*
Y0D01*
G01X759842Y9843D02*
X200787D01*
G01X218307Y202559D02*
Y191142D01*
G01X214370Y210138D02*
Y183563D01*
G01X230512Y202559D02*
X218307D01*
G01Y191142D02*
X230512D01*
G01X214370Y183563D02*
X234449D01*
G01X169413Y226269D02*
X169003Y225850D01*
G01X168182Y226688D02*
X169413Y227945D01*
G01X162851Y226269D02*
X162031Y225432D01*
G01Y227107D02*
X162851Y227945D01*
G01X150958Y226269D02*
X150548Y225850D01*
G01X149728Y226688D02*
X150958Y227945D01*
G01X169003Y225850D02*
X168592Y225013D01*
G01X169413Y227945D02*
X170643Y228363D01*
G01X164081Y226688D02*
X162851Y226269D01*
G01Y227945D02*
X164081Y228363D01*
G01X150958Y227945D02*
X152188Y228363D01*
G01X170233Y226688D02*
X169413Y226269D01*
G01X151778Y226688D02*
X150958Y226269D01*
G01X150548Y225850D02*
X150138Y225013D01*
G01X175154D02*
Y214961D01*
G01X173104D02*
Y225013D01*
G01X168592D02*
Y214961D01*
G01X166542D02*
Y225013D01*
G01X162031Y225432D02*
Y214961D01*
G01Y228363D02*
Y227107D01*
G01X159980Y214961D02*
Y228363D01*
G01X156699Y225013D02*
Y214961D01*
G01X154649D02*
Y225013D01*
G01X150138D02*
Y214961D01*
G01X174334Y227107D02*
X175154Y225013D01*
G01X155879Y227107D02*
X156699Y225013D01*
G01X173104D02*
X172693Y225850D01*
G01X166542Y225013D02*
X166132Y225850D01*
G01X154649Y225013D02*
X154239Y225850D01*
G01X173514Y227945D02*
X174334Y227107D01*
G01X172693Y225850D02*
X172283Y226269D01*
G01X166952Y227945D02*
X168182Y226688D01*
G01X166132Y225850D02*
X165722Y226269D01*
G01X155059Y227945D02*
X155879Y227107D01*
G01X154239Y225850D02*
X153828Y226269D01*
G01X148497Y227945D02*
X149728Y226688D01*
G01X172283Y226269D02*
X171463Y226688D01*
G01X165722Y226269D02*
X164901Y226688D01*
G01X153828Y226269D02*
X153008Y226688D01*
G01X172283Y228363D02*
X173514Y227945D01*
G01X165722Y228363D02*
X166952Y227945D01*
G01X153828Y228363D02*
X155059Y227945D01*
G01X170643Y228363D02*
X172283D01*
G01X164081D02*
X165722D01*
G01X159980D02*
X162031D01*
G01X152188D02*
X153828D01*
G01X153008Y226688D02*
X151778D01*
G01X164901D02*
X164081D01*
G01X171463D02*
X170233D01*
G01X156699Y214961D02*
X154649D01*
G01X162031D02*
X159980D01*
G01X168592D02*
X166542D01*
G01X175154D02*
X173104D01*
G01X214370Y210138D02*
X234449D01*
G01X171264Y384573D02*
G03X175201Y388510I0J3937D01*
G01X155515Y400321D02*
G03X159453Y404258I1J3937D01*
G01X175201Y388510D02*
Y494809D01*
G01X159453Y404258D02*
Y479061D01*
G01D02*
G03X155515Y482998I-3937J0D01*
G01X175201Y494809D02*
G03X171264Y498746I-3937J0D01*
G01X177027Y521516D02*
X177848Y519422D01*
G01X175797D02*
X175387Y520260D01*
G01X191618Y551896D02*
Y589770D01*
G01X177848Y519422D02*
Y509370D01*
G01X175797D02*
Y519422D01*
G01X173744Y589770D02*
Y551896D01*
G01X171286Y519422D02*
Y509370D01*
G01X169236D02*
Y519422D01*
G01X158573Y521516D02*
X159393Y519422D01*
G01X169236D02*
X168825Y520260D01*
G01X157342Y519422D02*
X156932Y520260D01*
G01X150781Y519422D02*
X150371Y520260D01*
G01X176207Y522354D02*
X177027Y521516D01*
G01X175387Y520260D02*
X174977Y520679D01*
G01X169645Y522354D02*
X170876Y521098D01*
G01X168825Y520260D02*
X168415Y520679D01*
G01X157753Y522354D02*
X158573Y521516D01*
G01X156932Y520260D02*
X156522Y520679D01*
G01X151191Y522354D02*
X152421Y521098D01*
G01X150371Y520260D02*
X149960Y520679D01*
G01X179045Y555833D02*
X177681Y556620D01*
G01X171696Y520260D02*
X171286Y519422D01*
G01X153241Y520260D02*
X152831Y519422D01*
G01X164724Y519841D02*
Y509370D01*
G01Y522773D02*
Y521516D01*
G01X162674Y509370D02*
Y522773D01*
G01X159393Y519422D02*
Y509370D01*
G01X157342D02*
Y519422D01*
G01X152831D02*
Y509370D01*
G01X150781D02*
Y519422D01*
G01X174977Y520679D02*
X174157Y521098D01*
G01X168415Y520679D02*
X167595Y521098D01*
G01X156522Y520679D02*
X155702Y521098D01*
G01X149960Y520679D02*
X149140Y521098D01*
G01X174977Y522773D02*
X176207Y522354D01*
G01X168415Y522773D02*
X169645Y522354D01*
G01X172106Y520679D02*
X171696Y520260D01*
G01X170876Y521098D02*
X172106Y522354D01*
G01X165545Y520679D02*
X164724Y519841D01*
G01Y521516D02*
X165545Y522354D01*
G01X153651Y520679D02*
X153241Y520260D01*
G01X152421Y521098D02*
X153651Y522354D01*
G01X156522Y522773D02*
X157753Y522354D01*
G01X149960Y522773D02*
X151191Y522354D01*
G01X179045Y555833D02*
X186317D01*
G01X173744Y551896D02*
X191618D01*
G01X172927Y521098D02*
X172106Y520679D01*
G01X173336Y522773D02*
X174977D01*
G01X166775D02*
X168415D01*
G01X162674D02*
X164724D01*
G01X154882D02*
X156522D01*
G01X155702Y521098D02*
X154472D01*
G01X167595D02*
X166775D01*
G01X174157D02*
X172927D01*
G01X152831Y509370D02*
X150781D01*
G01X159393D02*
X157342D01*
G01X164724D02*
X162674D01*
G01X171286D02*
X169236D01*
G01X177848D02*
X175797D01*
G01X172106Y522354D02*
X173336Y522773D01*
G01X166775Y521098D02*
X165545Y520679D01*
G01Y522354D02*
X166775Y522773D01*
G01X153651Y522354D02*
X154882Y522773D01*
G01X154472Y521098D02*
X153651Y520679D01*
G01X187681Y556620D02*
X186317Y555833D01*
G01X184571Y580833D02*
G03I-1890J0D01*
G01Y560833D02*
G03I-1890J0D01*
G01X184149Y561082D02*
X184216Y560623D01*
G01X183881Y560688D02*
X183814Y561016D01*
G01X184015Y561344D02*
X184149Y561082D01*
G01X183814Y561016D02*
X183680Y561213D01*
G01X182876Y559573D02*
X181402Y561213D01*
G01Y561738D02*
X183077Y559901D01*
G01X187681Y576620D02*
Y585045D01*
G01Y566620D02*
Y575045D01*
G01Y556620D02*
Y565045D01*
G01X184216Y560623D02*
Y560360D01*
G01Y580793D02*
Y580400D01*
G01X183941Y582092D02*
Y559573D01*
G01X183881Y560426D02*
Y560688D01*
G01X183479Y561344D02*
Y561672D01*
G01X181421Y582092D02*
Y559573D01*
G01X181402Y561213D02*
Y559376D01*
G01X181067Y580400D02*
Y580793D01*
G01Y559376D02*
Y561738D01*
G01X179147Y579573D02*
Y582092D01*
G01Y559573D02*
Y562092D01*
G01X177681Y565045D02*
Y556620D01*
G01Y575045D02*
Y566620D01*
G01Y585045D02*
Y576620D01*
G01X183747Y561607D02*
X184015Y561344D01*
G01X183747Y581187D02*
X184216Y580793D01*
G01X183680D02*
X183211Y581187D01*
G01X183680Y561213D02*
X183479Y561344D01*
G01X183077Y559442D02*
X182876Y559573D01*
G01X187681Y585045D02*
X186317Y585833D01*
G01X187681Y575045D02*
X186317Y575833D01*
G01X179045D02*
X177681Y576620D01*
G01X187681Y565045D02*
X186317Y565833D01*
G01X179045D02*
X177681Y566620D01*
G01X183077Y559901D02*
X183345Y559770D01*
G01X184149Y559966D02*
X184015Y559704D01*
G01X183814Y560098D02*
X183881Y560426D01*
G01X184216Y560360D02*
X184149Y559966D01*
G01X183479Y561672D02*
X183747Y561607D01*
G01X183345Y559376D02*
X183077Y559442D01*
G01X183680Y559901D02*
X183814Y560098D01*
G01X191618Y589770D02*
X173744D01*
G01X186317Y585833D02*
X179045D01*
G01X183941Y582092D02*
X179147D01*
G01X183211Y581187D02*
X183747D01*
G01X181067Y580793D02*
X183680D01*
G01X184216Y580400D02*
X181067D01*
G01X183941Y579573D02*
X179147D01*
G01X183941Y562092D02*
X179147D01*
G01X181067Y561738D02*
X181402D01*
G01X183345Y559770D02*
X183479D01*
G01X183941Y559573D02*
X179147D01*
G01X183479Y559376D02*
X183345D01*
G01X181402D02*
X181067D01*
G01X183479Y559770D02*
X183680Y559901D01*
G01X184015Y559704D02*
X183747Y559442D01*
G01D02*
X183479Y559376D01*
G01X187681Y566620D02*
X186317Y565833D01*
G01X179045D02*
X177681Y565045D01*
G01X187681Y576620D02*
X186317Y575833D01*
G01X179045D02*
X177681Y575045D01*
G01X179045Y585833D02*
X177681Y585045D01*
G01X181106Y649194D02*
X181926Y647100D01*
G01X162651Y649194D02*
X163471Y647100D01*
G01X179875D02*
X179465Y647937D01*
G01X173314Y647100D02*
X172903Y647937D01*
G01X161421Y647100D02*
X161010Y647937D01*
G01X154859Y647100D02*
X154449Y647937D01*
G01X180285Y650031D02*
X181106Y649194D01*
G01X179465Y647937D02*
X179055Y648356D01*
G01X173724Y650031D02*
X174954Y648775D01*
G01X172903Y647937D02*
X172493Y648356D01*
G01X161830Y650031D02*
X162651Y649194D01*
G01X161010Y647937D02*
X160600Y648356D01*
G01X155269Y650031D02*
X156499Y648775D01*
G01X154449Y647937D02*
X154039Y648356D01*
G01X179055D02*
X178235Y648775D01*
G01X172493Y648356D02*
X171673Y648775D01*
G01X160600Y648356D02*
X159780Y648775D01*
G01X154039Y648356D02*
X153218Y648775D01*
G01X181926Y647100D02*
Y637048D01*
G01X179875D02*
Y647100D01*
G01X175364D02*
Y637048D01*
G01X173314D02*
Y647100D01*
G01X168803Y647518D02*
Y637048D01*
G01Y650450D02*
Y649194D01*
G01X179055Y650450D02*
X180285Y650031D01*
G01X172493Y650450D02*
X173724Y650031D01*
G01X160600Y650450D02*
X161830Y650031D01*
G01X154039Y650450D02*
X155269Y650031D01*
G01X166752Y637048D02*
Y650450D01*
G01X163471Y647100D02*
Y637048D01*
G01X161421D02*
Y647100D01*
G01X156909D02*
Y637048D01*
G01X154859D02*
Y647100D01*
G01X150348Y647518D02*
Y637048D01*
G01Y650450D02*
Y649194D01*
G01X177415Y650450D02*
X179055D01*
G01X170853D02*
X172493D01*
G01X166752D02*
X168803D01*
G01X158960D02*
X160600D01*
G01X152398D02*
X154039D01*
G01X153218Y648775D02*
X152398D01*
G01X159780D02*
X158550D01*
G01X171673D02*
X170853D01*
G01X178235D02*
X177004D01*
G01X156909Y637048D02*
X154859D01*
G01X163471D02*
X161421D01*
G01X168803D02*
X166752D01*
G01X175364D02*
X173314D01*
G01X181926D02*
X179875D01*
G01X175774Y647937D02*
X175364Y647100D01*
G01X157319Y647937D02*
X156909Y647100D01*
G01X176184Y648356D02*
X175774Y647937D01*
G01X174954Y648775D02*
X176184Y650031D01*
G01X169623Y648356D02*
X168803Y647518D01*
G01Y649194D02*
X169623Y650031D01*
G01X157730Y648356D02*
X157319Y647937D01*
G01X156499Y648775D02*
X157730Y650031D01*
G01X151168Y648356D02*
X150348Y647518D01*
G01Y649194D02*
X151168Y650031D01*
G01X177004Y648775D02*
X176184Y648356D01*
G01X158550Y648775D02*
X157730Y648356D01*
G01X176184Y650031D02*
X177415Y650450D01*
G01X170853Y648775D02*
X169623Y648356D01*
G01Y650031D02*
X170853Y650450D01*
G01X157730Y650031D02*
X158960Y650450D01*
G01X152398Y648775D02*
X151168Y648356D01*
G01Y650031D02*
X152398Y650450D01*
G01X218307Y758071D02*
X230512D01*
G01X214370Y750492D02*
X234449D01*
G01X218307Y769489D02*
Y758071D01*
G01X214370Y777067D02*
Y750492D01*
G01X172401Y796851D02*
G03I-3937J0D01*
G01X173386D02*
G03I-4922J0D01*
G01X176338D02*
G03I-7874J0D01*
G01X167189Y830065D02*
X166401Y830853D01*
G01X177186Y837008D02*
X173004D01*
G01X163556Y836221D02*
X167815D01*
G01X190393Y835630D02*
X198701D01*
G01X187244D02*
X198701D01*
G01X163556Y835433D02*
X167815D01*
G01X173004Y834646D02*
X177186D01*
G01Y833859D02*
X173004D01*
G01X163556Y833071D02*
X167815D01*
G01X163556Y832284D02*
X167815D01*
G01X170839Y832140D02*
X167189D01*
G01X173004Y831496D02*
X177186D01*
G01X170839Y831353D02*
X166401D01*
G01Y830853D02*
X170839D01*
G01X177186Y830709D02*
X173004D01*
G01X170839Y830065D02*
X167189D01*
G01X163556Y829922D02*
X167815D01*
G01X190393Y829725D02*
X198701D01*
G01X187244D02*
X198701D01*
G01X163556Y829134D02*
X167815D01*
G01X173004Y828347D02*
X177186D01*
G01Y827559D02*
X173004D01*
G01X163556Y826772D02*
X167815D01*
G01X190393Y826181D02*
X198701D01*
G01X187244D02*
X198701D01*
G01X163556Y825985D02*
X167815D01*
G01X173004Y825197D02*
X177186D01*
G01Y824410D02*
X173004D01*
G01X163556Y823622D02*
X167815D01*
G01X163556Y822835D02*
X167815D01*
G01X173004Y822048D02*
X177186D01*
G01Y821260D02*
X173004D01*
G01X163556Y820473D02*
X167815D01*
G01X187244Y820276D02*
X198701D01*
G01X163556Y819685D02*
X167815D01*
G01X173004Y818898D02*
X177186D01*
G01X164797Y818111D02*
X177186D01*
G01X163556Y817323D02*
X167815D01*
G01X163556Y816536D02*
X167815D01*
G01X148870Y815720D02*
X148477D01*
G01X178705Y813189D02*
X165614D01*
G01X204052Y802737D02*
X194764D01*
G01X198701Y797835D02*
X194764D01*
G01X198701Y795807D02*
X176338D01*
G01X210512Y783563D02*
X200787D01*
G01X214370Y777067D02*
X234449D01*
G01X230512Y769489D02*
X218307D01*
G01X210512Y885847D02*
Y783563D01*
G01X206575Y885729D02*
Y787500D01*
G01X204055Y870492D02*
Y802737D01*
G01X203621D02*
Y870492D01*
G01X203071D02*
Y802737D01*
G01X202728Y870492D02*
Y802737D01*
G01X200794Y870492D02*
Y802737D01*
G01X200421Y870492D02*
Y802737D01*
G01X200203D02*
Y870492D01*
G01X200078D02*
Y802737D01*
G01X199843Y870492D02*
Y802737D01*
G01X199529D02*
Y870492D01*
G01X199419D02*
Y802737D01*
G01X199253Y870492D02*
Y802737D01*
G01X199094Y870492D02*
Y802737D01*
G01X198701Y881792D02*
Y791437D01*
G01Y829725D02*
Y826181D01*
G01Y839174D02*
Y835630D01*
G01X194764Y802737D02*
Y794666D01*
G01X190393Y835630D02*
Y839174D01*
G01Y835630D02*
Y839174D01*
G01Y826181D02*
Y829725D01*
G01Y826181D02*
Y829725D01*
G01Y801693D02*
Y820276D01*
G01X187244Y829725D02*
Y835630D01*
G01Y820276D02*
Y826181D01*
G01X186456Y871536D02*
Y801693D01*
G01X178705Y813189D02*
Y810237D01*
G01X177186Y818898D02*
Y818111D01*
G01Y825197D02*
Y824410D01*
G01Y822048D02*
Y821260D01*
G01Y828347D02*
Y827559D01*
G01Y834646D02*
Y833859D01*
G01Y831496D02*
Y830709D01*
G01Y837796D02*
Y837008D01*
G01X176586Y818898D02*
Y818111D01*
G01Y825197D02*
Y824410D01*
G01Y822048D02*
Y821260D01*
G01Y828347D02*
Y827559D01*
G01Y834646D02*
Y833859D01*
G01Y831496D02*
Y830709D01*
G01Y837796D02*
Y837008D01*
G01X176338Y791437D02*
Y795807D01*
G01X175179Y837008D02*
Y837796D01*
G01Y833859D02*
Y834646D01*
G01Y830709D02*
Y831496D01*
G01Y827559D02*
Y828347D01*
G01Y824410D02*
Y825197D01*
G01Y821260D02*
Y822048D01*
G01Y818111D02*
Y818898D01*
G01X174982Y860040D02*
Y813189D01*
G01X174616Y818898D02*
Y818111D01*
G01Y825197D02*
Y824410D01*
G01Y822048D02*
Y821260D01*
G01Y828347D02*
Y827559D01*
G01Y834646D02*
Y833859D01*
G01Y831496D02*
Y830709D01*
G01Y837796D02*
Y837008D01*
G01X173604Y818898D02*
Y818111D01*
G01Y825197D02*
Y824410D01*
G01Y822048D02*
Y821260D01*
G01Y828347D02*
Y827559D01*
G01Y834646D02*
Y833859D01*
G01Y831496D02*
Y830709D01*
G01Y837796D02*
Y837008D01*
G01X173004Y818898D02*
Y818111D01*
G01Y825197D02*
Y824410D01*
G01Y822048D02*
Y821260D01*
G01Y828347D02*
Y827559D01*
G01Y834646D02*
Y833859D01*
G01Y831496D02*
Y830709D01*
G01Y837796D02*
Y837008D01*
G01X172414Y813189D02*
Y810237D01*
G01X172020Y813189D02*
Y810237D01*
G01X171627Y813189D02*
Y810237D01*
G01X170839D02*
Y862992D01*
G01X167815Y817323D02*
Y816536D01*
G01Y820473D02*
Y819685D01*
G01Y823622D02*
Y822835D01*
G01Y826772D02*
Y825985D01*
G01Y829922D02*
Y829134D01*
G01Y833071D02*
Y832284D01*
G01Y836221D02*
Y835433D01*
G01X167804D02*
Y836221D01*
G01Y832284D02*
Y833071D01*
G01Y825985D02*
Y826772D01*
G01Y829134D02*
Y829922D01*
G01Y816536D02*
Y817323D01*
G01Y819685D02*
Y820473D01*
G01Y823622D02*
Y822835D01*
G01X167784Y856693D02*
Y818111D01*
G01X167583Y835433D02*
Y836221D01*
G01Y832284D02*
Y833071D01*
G01Y825985D02*
Y826772D01*
G01Y829134D02*
Y829922D01*
G01Y822835D02*
Y823622D01*
G01Y816536D02*
Y817323D01*
G01Y819685D02*
Y820473D01*
G01X167304Y817323D02*
Y816536D01*
G01Y820473D02*
Y819685D01*
G01Y823622D02*
Y822835D01*
G01Y826772D02*
Y825985D01*
G01Y829922D02*
Y829134D01*
G01Y833071D02*
Y832284D01*
G01Y836221D02*
Y835433D01*
G01X167232D02*
Y836221D01*
G01Y832284D02*
Y833071D01*
G01Y825985D02*
Y826772D01*
G01Y829134D02*
Y829922D01*
G01Y816536D02*
Y817323D01*
G01Y819685D02*
Y820473D01*
G01Y823622D02*
Y822835D01*
G01X167189Y830065D02*
Y813189D01*
G01Y842664D02*
Y832140D01*
G01X166945Y835433D02*
Y836221D01*
G01Y832284D02*
Y833071D01*
G01Y825985D02*
Y826772D01*
G01Y829134D02*
Y829922D01*
G01Y822835D02*
Y823622D01*
G01Y816536D02*
Y817323D01*
G01Y819685D02*
Y820473D01*
G01X166666Y817323D02*
Y816536D01*
G01Y820473D02*
Y819685D01*
G01Y823622D02*
Y822835D01*
G01Y826772D02*
Y825985D01*
G01Y829922D02*
Y829134D01*
G01Y833071D02*
Y832284D01*
G01Y836221D02*
Y835433D01*
G01X166649D02*
Y836221D01*
G01Y832284D02*
Y833071D01*
G01Y825985D02*
Y826772D01*
G01Y829134D02*
Y829922D01*
G01Y822835D02*
Y823622D01*
G01Y816536D02*
Y817323D01*
G01Y819685D02*
Y820473D01*
G01X166401Y831353D02*
Y843451D01*
G01Y813189D02*
Y830853D01*
G01X165614Y813189D02*
Y860040D01*
G01X165190Y835433D02*
Y836221D01*
G01Y832284D02*
Y833071D01*
G01Y825985D02*
Y826772D01*
G01Y829134D02*
Y829922D01*
G01Y822835D02*
Y823622D01*
G01Y816536D02*
Y817323D01*
G01Y819685D02*
Y820473D01*
G01X164797Y862992D02*
Y810237D01*
G01X164156Y817323D02*
Y816536D01*
G01Y820473D02*
Y819685D01*
G01Y823622D02*
Y822835D01*
G01Y826772D02*
Y825985D01*
G01Y829922D02*
Y829134D01*
G01Y833071D02*
Y832284D01*
G01Y836221D02*
Y835433D01*
G01X163556Y817323D02*
Y816536D01*
G01Y820473D02*
Y819685D01*
G01Y823622D02*
Y822835D01*
G01Y826772D02*
Y825985D01*
G01Y829922D02*
Y829134D01*
G01Y833071D02*
Y832284D01*
G01Y836221D02*
Y835433D01*
G01X162486Y862992D02*
Y810237D01*
G01X160590Y795807D02*
Y791437D01*
G01X157534Y813386D02*
Y859843D01*
G01X156747D02*
Y813386D01*
G01X149264Y811389D02*
Y816113D01*
G01X148870Y811783D02*
Y815720D01*
G01X148706Y815498D02*
Y810237D01*
G01X148528Y815498D02*
Y810237D01*
G01X167189Y832140D02*
X166401Y831353D01*
G01X172401Y876378D02*
G03I-3937J0D01*
G01X173386D02*
G03I-4922J0D01*
G01X176338D02*
G03I-7874J0D01*
G01X174819Y856550D02*
X174861Y856468D01*
G01X175699Y856550D02*
X175824Y856387D01*
G01X167189Y842664D02*
X166401Y843451D01*
G01X175489Y856427D02*
X175573Y856346D01*
G01X174693D02*
X174610Y856427D01*
G01X174232Y857289D02*
X174526Y857042D01*
G01X174191D02*
X173897Y857289D01*
G01X164547Y855561D02*
X164841Y855315D01*
G01X164506D02*
X164212Y855561D01*
G01X175531Y856674D02*
X175699Y856550D01*
G01X174651Y856674D02*
X174819Y856550D01*
G01X166181Y853347D02*
X164212Y854003D01*
G01X175405Y856715D02*
X175531Y856674D01*
G01X175364Y856468D02*
X175489Y856427D01*
G01X174526Y856715D02*
X174651Y856674D01*
G01X174610Y856427D02*
X174484Y856468D01*
G01X165678Y853757D02*
X166181Y853593D01*
G01X165511Y853798D02*
X164380Y854167D01*
G01X175824Y856387D02*
X175866Y856181D01*
G01X175573Y856346D02*
X175615Y856222D01*
G01X174735D02*
X174693Y856346D01*
G01X176338Y877422D02*
X198701D01*
G01X194764Y875394D02*
X198701D01*
G01X194764Y870492D02*
X204052D01*
G01X165614Y860040D02*
X178705D01*
G01X173897Y857535D02*
X175866D01*
G01Y857289D02*
X174232D01*
G01X174526Y857042D02*
X174191D01*
G01X175196Y856715D02*
X175405D01*
G01X174358D02*
X174526D01*
G01X164797Y856693D02*
X177186D01*
G01X175238Y856468D02*
X175364D01*
G01X174484D02*
X174400D01*
G01X177186Y855906D02*
X173004D01*
G01X164212Y855807D02*
X166181D01*
G01Y855561D02*
X164547D01*
G01X174149Y855443D02*
X174735D01*
G01X175615D02*
X174986D01*
G01X164841Y855315D02*
X164506D01*
G01X175866Y855197D02*
X173897D01*
G01X163556Y855118D02*
X167815D01*
G01X198701Y854528D02*
X187244D01*
G01X163556Y854331D02*
X167815D01*
G01X173004Y853544D02*
X177186D01*
G01Y852756D02*
X173004D01*
G01X163556Y851969D02*
X167815D01*
G01X163556Y851181D02*
X167815D01*
G01X173004Y850394D02*
X177186D01*
G01Y849607D02*
X173004D01*
G01X163556Y848819D02*
X167815D01*
G01X198701Y848622D02*
X187244D01*
G01X198701D02*
X190393D01*
G01X163556Y848032D02*
X167815D01*
G01X173004Y847244D02*
X177186D01*
G01Y846457D02*
X173004D01*
G01X163556Y845670D02*
X167815D01*
G01X198701Y845079D02*
X187244D01*
G01X198701D02*
X190393D01*
G01X163556Y844882D02*
X167815D01*
G01X170839Y844739D02*
X167189D01*
G01X173004Y844095D02*
X177186D01*
G01X170839Y843951D02*
X166401D01*
G01Y843451D02*
X170839D01*
G01X177186Y843307D02*
X173004D01*
G01X170839Y842664D02*
X167189D01*
G01X163556Y842520D02*
X167815D01*
G01X163556Y841733D02*
X167815D01*
G01X173004Y840945D02*
X177186D01*
G01Y840158D02*
X173004D01*
G01X163556Y839370D02*
X167815D01*
G01X198701Y839174D02*
X187244D01*
G01X198701D02*
X190393D01*
G01X163556Y838583D02*
X167815D01*
G01X173004Y837796D02*
X177186D01*
G01X198701Y848622D02*
Y845079D01*
G01X194764Y878563D02*
Y870492D01*
G01X190393Y854528D02*
Y871536D01*
G01Y845079D02*
Y848622D01*
G01Y845079D02*
Y848622D01*
G01X187244D02*
Y854528D01*
G01Y839174D02*
Y845079D01*
G01X178705Y860040D02*
Y862992D01*
G01X177186Y844095D02*
Y843307D01*
G01Y840945D02*
Y840158D01*
G01Y847244D02*
Y846457D01*
G01Y853544D02*
Y852756D01*
G01Y850394D02*
Y849607D01*
G01Y856693D02*
Y855906D01*
G01X176586Y844095D02*
Y843307D01*
G01Y840945D02*
Y840158D01*
G01Y847244D02*
Y846457D01*
G01Y853544D02*
Y852756D01*
G01Y850394D02*
Y849607D01*
G01Y856693D02*
Y855906D01*
G01X176338Y877422D02*
Y881792D01*
G01X175866Y857535D02*
Y857289D01*
G01Y856181D02*
Y855197D01*
G01X175615Y856222D02*
Y855443D01*
G01X175179Y855906D02*
Y856693D01*
G01Y852756D02*
Y853544D01*
G01Y849607D02*
Y850394D01*
G01Y846457D02*
Y847244D01*
G01Y843307D02*
Y844095D01*
G01Y840158D02*
Y840945D01*
G01X174986Y855443D02*
Y856222D01*
G01X174735Y855443D02*
Y856222D01*
G01X174616Y844095D02*
Y843307D01*
G01Y840945D02*
Y840158D01*
G01Y847244D02*
Y846457D01*
G01Y853544D02*
Y852756D01*
G01Y850394D02*
Y849607D01*
G01Y856693D02*
Y855906D01*
G01X174149Y856222D02*
Y855443D01*
G01X173897Y857289D02*
Y857535D01*
G01Y855197D02*
Y856181D01*
G01X173604Y844095D02*
Y843307D01*
G01Y840945D02*
Y840158D01*
G01Y847244D02*
Y846457D01*
G01Y853544D02*
Y852756D01*
G01Y850394D02*
Y849607D01*
G01Y856693D02*
Y855906D01*
G01X173004Y844095D02*
Y843307D01*
G01Y840945D02*
Y840158D01*
G01Y847244D02*
Y846457D01*
G01Y853544D02*
Y852756D01*
G01Y850394D02*
Y849607D01*
G01Y856693D02*
Y855906D01*
G01X172414Y860040D02*
Y862992D01*
G01X172020Y860040D02*
Y862992D01*
G01X171627Y860040D02*
Y862992D01*
G01X167815Y839370D02*
Y838583D01*
G01Y842520D02*
Y841733D01*
G01Y845670D02*
Y844882D01*
G01Y848819D02*
Y848032D01*
G01Y851969D02*
Y851181D01*
G01Y855118D02*
Y854331D01*
G01X167804Y851181D02*
Y851969D01*
G01Y844882D02*
Y845670D01*
G01Y848032D02*
Y848819D01*
G01Y841733D02*
Y842520D01*
G01Y838583D02*
Y839370D01*
G01Y855118D02*
Y854331D01*
G01X167583D02*
Y855118D01*
G01Y851181D02*
Y851969D01*
G01Y844882D02*
Y845670D01*
G01Y848032D02*
Y848819D01*
G01Y841733D02*
Y842520D01*
G01Y838583D02*
Y839370D01*
G01X167304D02*
Y838583D01*
G01Y842520D02*
Y841733D01*
G01Y845670D02*
Y844882D01*
G01Y848819D02*
Y848032D01*
G01Y851969D02*
Y851181D01*
G01Y855118D02*
Y854331D01*
G01X167232Y851181D02*
Y851969D01*
G01Y844882D02*
Y845670D01*
G01Y848032D02*
Y848819D01*
G01Y841733D02*
Y842520D01*
G01Y838583D02*
Y839370D01*
G01Y855118D02*
Y854331D01*
G01X167189Y860040D02*
Y844739D01*
G01X166945Y854331D02*
Y855118D01*
G01Y851181D02*
Y851969D01*
G01Y844882D02*
Y845670D01*
G01Y848032D02*
Y848819D01*
G01Y841733D02*
Y842520D01*
G01Y838583D02*
Y839370D01*
G01X166666D02*
Y838583D01*
G01Y842520D02*
Y841733D01*
G01Y845670D02*
Y844882D01*
G01Y848819D02*
Y848032D01*
G01Y851969D02*
Y851181D01*
G01Y855118D02*
Y854331D01*
G01X166649D02*
Y855118D01*
G01Y851181D02*
Y851969D01*
G01Y844882D02*
Y845670D01*
G01Y848032D02*
Y848819D01*
G01Y841733D02*
Y842520D01*
G01Y838583D02*
Y839370D01*
G01X166401Y843951D02*
Y860040D01*
G01X166181Y853593D02*
Y853347D01*
G01Y855807D02*
Y855561D01*
G01Y854987D02*
Y854741D01*
G01X165678Y854577D02*
Y853757D01*
G01X165511Y854536D02*
Y853798D01*
G01X165190Y854331D02*
Y855118D01*
G01Y851181D02*
Y851969D01*
G01Y844882D02*
Y845670D01*
G01Y848032D02*
Y848819D01*
G01Y841733D02*
Y842520D01*
G01Y838583D02*
Y839370D01*
G01X164212Y855561D02*
Y855807D01*
G01Y854003D02*
Y854331D01*
G01X164156Y839370D02*
Y838583D01*
G01Y842520D02*
Y841733D01*
G01Y845670D02*
Y844882D01*
G01Y848819D02*
Y848032D01*
G01Y851969D02*
Y851181D01*
G01Y855118D02*
Y854331D01*
G01X163556Y839370D02*
Y838583D01*
G01Y842520D02*
Y841733D01*
G01Y845670D02*
Y844882D01*
G01Y848819D02*
Y848032D01*
G01Y851969D02*
Y851181D01*
G01Y855118D02*
Y854331D01*
G01X160590Y881792D02*
Y877422D01*
G01X148706Y862992D02*
Y857731D01*
G01X148528D02*
Y862992D01*
G01X174986Y856222D02*
X175028Y856346D01*
G01X174191D02*
X174149Y856222D01*
G01X173897Y856181D02*
X173940Y856387D01*
G01X174861Y856468D02*
X174903Y856550D01*
G01X173940Y856387D02*
X174065Y856550D01*
G01X175028Y856346D02*
X175112Y856427D01*
G01X174275D02*
X174191Y856346D01*
G01X167189Y844739D02*
X166401Y843951D01*
G01X174903Y856550D02*
X175070Y856674D01*
G01X174065Y856550D02*
X174232Y856674D01*
G01X175112Y856427D02*
X175238Y856468D01*
G01X175070Y856674D02*
X175196Y856715D01*
G01X174400Y856468D02*
X174275Y856427D01*
G01X174232Y856674D02*
X174358Y856715D01*
G01X166181Y854741D02*
X165678Y854577D01*
G01X164380Y854167D02*
X165511Y854536D01*
G01X164212Y854331D02*
X166181Y854987D01*
G01X759842Y915355D02*
X200787D01*
G01D02*
Y925197D01*
G01X280491Y-435251D02*
X282991D01*
G01X280991Y-436116D02*
X282491D01*
G01X280991D02*
X280491Y-435251D01*
G01X282491Y-436116D02*
X282991Y-435251D01*
G01Y-428912D02*
Y-435251D01*
G01X280491Y-428912D02*
Y-435251D01*
G01X283037Y-401239D02*
G03X280444I-1296J-181D01*
G01X391741Y-386112D02*
X261741D01*
G01Y-414112D02*
X391741D01*
G01X223066Y-418282D02*
X235270D01*
G01X229955Y-420742D02*
X230940D01*
G01X232515D02*
X233499D01*
G01X224837D02*
X225822D01*
G01X227396D02*
X228381D01*
G01X288241Y-421112D02*
X295241D01*
G01X278244D02*
X285241D01*
G01X229955Y-422219D02*
X230940D01*
G01X232515D02*
X233499D01*
G01X224837D02*
X225822D01*
G01X227396D02*
X228381D01*
G01X229955Y-422415D02*
X230940D01*
G01X232515D02*
X233499D01*
G01X224837D02*
X225822D01*
G01X227396D02*
X228381D01*
G01X283037Y-401239D02*
X284846Y-414112D01*
G01X278635D02*
X280444Y-401239D01*
G01X288241Y-421112D02*
Y-422612D01*
G01X285241Y-421112D02*
Y-422612D01*
G01X282991Y-421112D02*
Y-422612D01*
G01X280491Y-421112D02*
Y-422612D01*
G01X278244Y-414112D02*
Y-422612D01*
G01X267744Y-414112D02*
Y-422612D01*
G01X261741Y-386112D02*
Y-414112D01*
G01X235270Y-422612D02*
Y-418282D01*
G01X233499Y-420742D02*
Y-422415D01*
G01X232515Y-420742D02*
Y-422415D01*
G01X230940Y-420742D02*
Y-422415D01*
G01X229955Y-420742D02*
Y-422415D01*
G01X228381Y-420742D02*
Y-422415D01*
G01X227396Y-420742D02*
Y-422415D01*
G01X225822Y-420742D02*
Y-422415D01*
G01X224837Y-420742D02*
Y-422415D01*
G01X223066Y-422612D02*
Y-418282D01*
G01X267716Y-7874D02*
G03Y0I0J3937D01*
G01X298425D02*
X267716D01*
G01X221063Y192914D02*
G03I-591J0D01*
G01X234449Y183563D02*
Y210138D01*
G01X230512Y191142D02*
Y202559D01*
G01X228740Y191142D02*
Y187500D01*
G01Y206201D02*
Y202559D01*
G01X227756Y191142D02*
Y187500D01*
G01Y206201D02*
Y202559D01*
G01X226181Y191142D02*
Y187500D01*
G01Y206201D02*
Y202559D01*
G01X225197Y191142D02*
Y187500D01*
G01Y206201D02*
Y202559D01*
G01X223622Y191142D02*
Y187500D01*
G01Y206201D02*
Y202559D01*
G01X222638Y191142D02*
Y187500D01*
G01Y206201D02*
Y202559D01*
G01X221063Y191142D02*
Y187500D01*
G01Y206201D02*
Y202559D01*
G01X220275Y189863D02*
Y189813D01*
G01X220078Y191142D02*
Y187500D01*
G01Y206201D02*
Y202559D01*
G01X219882Y189813D02*
Y189863D01*
G01X219949Y189813D02*
X220008Y189764D01*
G01X219940D02*
X219882Y189813D01*
G01X227756Y204233D02*
X228740D01*
G01X225197D02*
X226181D01*
G01X222638D02*
X223622D01*
G01X220078D02*
X221063D01*
G01X227756Y202838D02*
X228740D01*
G01X225197D02*
X226181D01*
G01X222638D02*
X223622D01*
G01X220078D02*
X221063D01*
G01X227756Y202756D02*
X228740D01*
G01X225197D02*
X226181D01*
G01X222638D02*
X223622D01*
G01X220078D02*
X221063D01*
G01X227756Y190945D02*
X228740D01*
G01X225197D02*
X226181D01*
G01X222638D02*
X223622D01*
G01X220078D02*
X221063D01*
G01X227756Y190864D02*
X228740D01*
G01X225197D02*
X226181D01*
G01X222638D02*
X223622D01*
G01X220078D02*
X221063D01*
G01X219882Y189863D02*
X220275D01*
G01Y189813D02*
X219949D01*
G01X220008Y189764D02*
X219940D01*
G01X227756Y189469D02*
X228740D01*
G01X225197D02*
X226181D01*
G01X222638D02*
X223622D01*
G01X220078D02*
X221063D01*
G01X227756Y189387D02*
X228740D01*
G01X225197D02*
X226181D01*
G01X222638D02*
X223622D01*
G01X220078D02*
X221063D01*
G01X227756Y187500D02*
X228740D01*
G01X225197D02*
X226181D01*
G01X222638D02*
X223622D01*
G01X220078D02*
X221063D01*
G01X227756Y206201D02*
X228740D01*
G01X225197D02*
X226181D01*
G01X222638D02*
X223622D01*
G01X220078D02*
X221063D01*
G01X227756Y204314D02*
X228740D01*
G01X225197D02*
X226181D01*
G01X222638D02*
X223622D01*
G01X220078D02*
X221063D01*
G01Y759843D02*
G03I-591J0D01*
G01X219949Y756742D02*
X220008Y756693D01*
G01X219940D02*
X219882Y756742D01*
G01X227756Y757874D02*
X228740D01*
G01X225197D02*
X226181D01*
G01X222638D02*
X223622D01*
G01X220078D02*
X221063D01*
G01X227756Y757793D02*
X228740D01*
G01X225197D02*
X226181D01*
G01X222638D02*
X223622D01*
G01X220078D02*
X221063D01*
G01X219882Y756792D02*
X220275D01*
G01Y756742D02*
X219949D01*
G01X220008Y756693D02*
X219940D01*
G01X227756Y756398D02*
X228740D01*
G01X225197D02*
X226181D01*
G01X222638D02*
X223622D01*
G01X220078D02*
X221063D01*
G01X227756Y756316D02*
X228740D01*
G01X225197D02*
X226181D01*
G01X222638D02*
X223622D01*
G01X220078D02*
X221063D01*
G01X227756Y754429D02*
X228740D01*
G01X225197D02*
X226181D01*
G01X222638D02*
X223622D01*
G01X220078D02*
X221063D01*
G01X234449Y750492D02*
Y777067D01*
G01X230512Y758071D02*
Y769489D01*
G01X228740Y758071D02*
Y754429D01*
G01X227756Y758071D02*
Y754429D01*
G01X226181Y758071D02*
Y754429D01*
G01X225197Y758071D02*
Y754429D01*
G01X223622Y758071D02*
Y754429D01*
G01X222638Y758071D02*
Y754429D01*
G01X221063Y758071D02*
Y754429D01*
G01X220275Y756792D02*
Y756742D01*
G01X220078Y758071D02*
Y754429D01*
G01X219882Y756742D02*
Y756792D01*
G01X289226Y828335D02*
G03I-2244J0D01*
G01X279226D02*
G03I-2244J0D01*
G01X289226Y818335D02*
G03I-2244J0D01*
G01X279226D02*
G03I-2244J0D01*
G01X276902Y814659D02*
X277025Y814492D01*
G01X276779D02*
X276697Y814575D01*
G01X287732Y827585D02*
X288232Y827085D01*
G01X286232Y829085D02*
X285732Y829585D01*
G01X287732Y817585D02*
X288232Y817085D01*
G01X277732Y827585D02*
X278232Y827085D01*
G01X276232Y829085D02*
X275732Y829585D01*
G01X286232Y819085D02*
X285732Y819585D01*
G01X261194Y836623D02*
X261982Y835835D01*
G01X277732Y817585D02*
X278232Y817085D01*
G01X276232Y819085D02*
X275732Y819585D01*
G01X276738Y814785D02*
X276902Y814659D01*
G01X277025Y814492D02*
X277066Y814366D01*
G01X276820D02*
X276779Y814492D01*
G01X276697Y814575D02*
X276574Y814617D01*
G01X276533Y814827D02*
X276738Y814785D01*
G01X382769Y836623D02*
X261194D01*
G01X381982Y835835D02*
X261982D01*
G01X262986Y834835D02*
X380978D01*
G01X278232Y829585D02*
X275732D01*
G01X288232D02*
X285732D01*
G01X277732Y829085D02*
X276232D01*
G01X287732D02*
X286232D01*
G01Y827585D02*
X287732D01*
G01X276232D02*
X277732D01*
G01X285732Y827085D02*
X288232D01*
G01X275732D02*
X278232D01*
G01X370478Y824835D02*
X273486D01*
G01X370478Y821835D02*
X273486D01*
G01X278232Y819585D02*
X275732D01*
G01X288232D02*
X285732D01*
G01X277732Y819085D02*
X276232D01*
G01X287732D02*
X286232D01*
G01X288232Y827085D02*
Y829585D01*
G01Y817085D02*
Y819585D01*
G01X287732Y827585D02*
Y829085D01*
G01Y817585D02*
Y819085D01*
G01X286232D02*
Y817585D01*
G01Y829085D02*
Y827585D01*
G01X285732Y819585D02*
Y817085D01*
G01Y829585D02*
Y827085D01*
G01X283482Y834835D02*
Y811835D01*
G01X280482D02*
Y834835D01*
G01X278232Y827085D02*
Y829585D01*
G01Y817085D02*
Y819585D01*
G01X277886Y814827D02*
Y812858D01*
G01X277732Y827585D02*
Y829085D01*
G01Y817585D02*
Y819085D01*
G01X277640Y812858D02*
Y814492D01*
G01X277394Y814198D02*
Y814533D01*
G01X277066Y814366D02*
Y814198D01*
G01X276820Y814240D02*
Y814366D01*
G01X276232Y819085D02*
Y817585D01*
G01Y829085D02*
Y827585D01*
G01X275795Y814617D02*
Y813989D01*
G01Y813738D02*
Y812858D01*
G01X275732Y819585D02*
Y817085D01*
G01Y829585D02*
Y827085D01*
G01X275549Y812858D02*
Y814827D01*
G01X273486Y834835D02*
Y807835D01*
G01X268986Y834835D02*
Y811835D01*
G01X262986Y807835D02*
Y834835D01*
G01X261982Y835835D02*
Y810835D01*
G01X261194Y836623D02*
Y810048D01*
G01X256982Y840835D02*
Y805835D01*
G01X286232Y817585D02*
X287732D01*
G01X276232D02*
X277732D01*
G01X285732Y817085D02*
X288232D01*
G01X275732D02*
X278232D01*
G01X277640Y814827D02*
X277886D01*
G01X275549D02*
X276533D01*
G01X276574Y814617D02*
X275795D01*
G01Y813989D02*
X276574D01*
G01X276533Y813738D02*
X275795D01*
G01Y812858D02*
X275549D01*
G01X277886D02*
X277640D01*
G01X273486Y811835D02*
X370478D01*
G01X268986D02*
X262986D01*
G01X261982Y810835D02*
X381982D01*
G01X313882Y810048D02*
X261194D01*
G01X273486Y807835D02*
X262986D01*
G01X313882Y805835D02*
X256982D01*
G01X227756Y773130D02*
X228740D01*
G01X225197D02*
X226181D01*
G01X222638D02*
X223622D01*
G01X220078D02*
X221063D01*
G01X227756Y771243D02*
X228740D01*
G01X225197D02*
X226181D01*
G01X222638D02*
X223622D01*
G01X220078D02*
X221063D01*
G01X227756Y771162D02*
X228740D01*
G01X225197D02*
X226181D01*
G01X222638D02*
X223622D01*
G01X220078D02*
X221063D01*
G01X227756Y769767D02*
X228740D01*
G01X225197D02*
X226181D01*
G01X222638D02*
X223622D01*
G01X220078D02*
X221063D01*
G01X227756Y769685D02*
X228740D01*
G01X225197D02*
X226181D01*
G01X222638D02*
X223622D01*
G01X220078D02*
X221063D01*
G01X228740Y773130D02*
Y769489D01*
G01X227756Y773130D02*
Y769489D01*
G01X226181Y773130D02*
Y769489D01*
G01X225197Y773130D02*
Y769489D01*
G01X223622Y773130D02*
Y769489D01*
G01X222638Y773130D02*
Y769489D01*
G01X221063Y773130D02*
Y769489D01*
G01X220078Y773130D02*
Y769489D01*
G01X276738Y813779D02*
X276533Y813738D01*
G01X277066Y814198D02*
X277025Y814073D01*
G01X276779Y814115D02*
X276820Y814240D01*
G01X277025Y814073D02*
X276902Y813905D01*
G01X287732Y819085D02*
X288232Y819585D01*
G01X286232Y817585D02*
X285732Y817085D01*
G01X287732Y829085D02*
X288232Y829585D01*
G01X277732Y819085D02*
X278232Y819585D01*
G01X276232Y817585D02*
X275732Y817085D01*
G01X286232Y827585D02*
X285732Y827085D01*
G01X261194Y810048D02*
X261982Y810835D01*
G01X277732Y829085D02*
X278232Y829585D01*
G01X276232Y827585D02*
X275732Y827085D01*
G01X276697Y814031D02*
X276779Y814115D01*
G01X277640Y814492D02*
X277394Y814198D01*
G01Y814533D02*
X277640Y814827D01*
G01X276902Y813905D02*
X276738Y813779D01*
G01X276574Y813989D02*
X276697Y814031D01*
G01X386982Y840835D02*
X256982D01*
G01X350991Y-436116D02*
X350491Y-435251D01*
G01X352491Y-436116D02*
X352991Y-435251D01*
G01X342491Y-436116D02*
X342991Y-435251D01*
G01X332491Y-436116D02*
X332991Y-435251D01*
G01X322491Y-436116D02*
X322991Y-435251D01*
G01X352991Y-428912D02*
Y-435251D01*
G01X350491Y-428912D02*
Y-435251D01*
G01X342991Y-428912D02*
Y-435251D01*
G01X340491Y-428912D02*
Y-435251D01*
G01X340991Y-436116D02*
X340491Y-435251D01*
G01X330991Y-436116D02*
X330491Y-435251D01*
G01X320991Y-436116D02*
X320491Y-435251D01*
G01X350491D02*
X352991D01*
G01X340491D02*
X342991D01*
G01X330491D02*
X332991D01*
G01X320491D02*
X322991D01*
G01X310491D02*
X312991D01*
G01X300491D02*
X302991D01*
G01X290491D02*
X292991D01*
G01X350991Y-436116D02*
X352491D01*
G01X340991D02*
X342491D01*
G01X330991D02*
X332491D01*
G01X320991D02*
X322491D01*
G01X310991D02*
X312491D01*
G01X300991D02*
X302491D01*
G01X290991D02*
X292491D01*
G01X312491D02*
X312991Y-435251D01*
G01X302491Y-436116D02*
X302991Y-435251D01*
G01X292491Y-436116D02*
X292991Y-435251D01*
G01X332991Y-428912D02*
Y-435251D01*
G01X330491Y-428912D02*
Y-435251D01*
G01X322991Y-428912D02*
Y-435251D01*
G01X320491Y-428912D02*
Y-435251D01*
G01X312991Y-428912D02*
Y-435251D01*
G01X310491Y-428912D02*
Y-435251D01*
G01X310991Y-436116D02*
X310491Y-435251D01*
G01X300991Y-436116D02*
X300491Y-435251D01*
G01X290991Y-436116D02*
X290491Y-435251D01*
G01X302991Y-428912D02*
Y-435251D01*
G01X300491Y-428912D02*
Y-435251D01*
G01X292991Y-428912D02*
Y-435251D01*
G01X290491Y-428912D02*
Y-435251D01*
G01X332491Y-387097D02*
X332991Y-387963D01*
G01X322491Y-387097D02*
X322991Y-387963D01*
G01X334841Y-386900D02*
X318641D01*
G01X330991Y-387097D02*
X332491D01*
G01X320991D02*
X322491D01*
G01X330491Y-387963D02*
X332991D01*
G01X320491D02*
X322991D01*
G01X358241Y-421112D02*
Y-422612D01*
G01X355241Y-421112D02*
Y-422612D01*
G01X352991Y-421112D02*
Y-422612D01*
G01X350491Y-421112D02*
Y-422612D01*
G01X348241Y-421112D02*
Y-422612D01*
G01X345241Y-421112D02*
Y-422612D01*
G01X342991Y-421112D02*
Y-422612D01*
G01X340491Y-421112D02*
Y-422612D01*
G01X338241Y-421112D02*
Y-422612D01*
G01X335241Y-421112D02*
Y-422612D01*
G01X334841Y-414112D02*
Y-386112D01*
G01X318641Y-411112D02*
X334841D01*
G01X358241Y-421112D02*
X365241D01*
G01X348241D02*
X355241D01*
G01X338241D02*
X345241D01*
G01X328241D02*
X335241D01*
G01X318241D02*
X325241D01*
G01X308241D02*
X315241D01*
G01X298241D02*
X305241D01*
G01X330991Y-387097D02*
X330491Y-387963D01*
G01X320991Y-387097D02*
X320491Y-387963D01*
G01X332991Y-421112D02*
Y-422612D01*
G01Y-387963D02*
Y-411112D01*
G01X330491Y-421112D02*
Y-422612D01*
G01Y-387963D02*
Y-411112D01*
G01X328241Y-421112D02*
Y-422612D01*
G01X325241Y-421112D02*
Y-422612D01*
G01X322991Y-421112D02*
Y-422612D01*
G01Y-387963D02*
Y-411112D01*
G01X320491Y-421112D02*
Y-422612D01*
G01Y-387963D02*
Y-411112D01*
G01X318641Y-414112D02*
Y-386112D01*
G01X318241Y-421112D02*
Y-422612D01*
G01X315241Y-421112D02*
Y-422612D01*
G01X312991Y-421112D02*
Y-422612D01*
G01X310491Y-421112D02*
Y-422612D01*
G01X308241Y-421112D02*
Y-422612D01*
G01X305241Y-421112D02*
Y-422612D01*
G01X302991Y-421112D02*
Y-422612D01*
G01X300491Y-421112D02*
Y-422612D01*
G01X298241Y-421112D02*
Y-422612D01*
G01X295241Y-421112D02*
Y-422612D01*
G01X292991Y-421112D02*
Y-422612D01*
G01X290491Y-421112D02*
Y-422612D01*
G01X298425Y0D02*
G03Y-7874I0J-3937D01*
G01X483071D02*
X298425D01*
G01X358878Y5387D02*
Y3544D01*
G01Y7481D02*
Y5889D01*
G01X358386Y3544D02*
Y7481D01*
G01D02*
X358878D01*
G01Y5889D02*
X361175D01*
G01Y5387D02*
X358878D01*
G01Y3544D02*
X358386D01*
G01X355053Y396733D02*
Y357363D01*
G01X350131Y380817D02*
Y396733D01*
G01Y357363D02*
Y375791D01*
G01X327165D02*
Y357363D01*
G01Y396733D02*
Y380817D01*
G01X322244Y357363D02*
Y396733D01*
G01X350131D02*
X355053D01*
G01X322244D02*
X327165D01*
G01Y380817D02*
X350131D01*
G01Y375791D02*
X327165D01*
G01Y357363D02*
X322244D01*
G01X355053D02*
X350131D01*
G01X359226Y818335D02*
G03I-2244J0D01*
G01Y828335D02*
G03I-2244J0D01*
G01X349226D02*
G03I-2244J0D01*
G01X339226D02*
G03I-2244J0D01*
G01X329226D02*
G03I-2244J0D01*
G01X319226D02*
G03I-2244J0D01*
G01X309226D02*
G03I-2244J0D01*
G01X299226D02*
G03I-2244J0D01*
G01X349226Y818335D02*
G03I-2244J0D01*
G01X339226D02*
G03I-2244J0D01*
G01X329226D02*
G03I-2244J0D01*
G01X319226D02*
G03I-2244J0D01*
G01X309226D02*
G03I-2244J0D01*
G01X299226D02*
G03I-2244J0D01*
G01X357732Y827585D02*
X358232Y827085D01*
G01X356232Y829085D02*
X355732Y829585D01*
G01X357732Y817585D02*
X358232Y817085D01*
G01X347732Y827585D02*
X348232Y827085D01*
G01X346232Y829085D02*
X345732Y829585D01*
G01X356232Y819085D02*
X355732Y819585D01*
G01X347732Y817585D02*
X348232Y817085D01*
G01X337732Y827585D02*
X338232Y827085D01*
G01X336232Y829085D02*
X335732Y829585D01*
G01X346232Y819085D02*
X345732Y819585D01*
G01X337732Y817585D02*
X338232Y817085D01*
G01X327732Y827585D02*
X328232Y827085D01*
G01X326232Y829085D02*
X325732Y829585D01*
G01X336232Y819085D02*
X335732Y819585D01*
G01X327732Y817585D02*
X328232Y817085D01*
G01X317732Y827585D02*
X318232Y827085D01*
G01X316232Y829085D02*
X315732Y829585D01*
G01X326232Y819085D02*
X325732Y819585D01*
G01X317732Y817585D02*
X318232Y817085D01*
G01X307732Y827585D02*
X308232Y827085D01*
G01X306232Y829085D02*
X305732Y829585D01*
G01X316232Y819085D02*
X315732Y819585D01*
G01X307732Y817585D02*
X308232Y817085D01*
G01X297732Y827585D02*
X298232Y827085D01*
G01X296232Y829085D02*
X295732Y829585D01*
G01X306232Y819085D02*
X305732Y819585D01*
G01X297732Y817585D02*
X298232Y817085D01*
G01X296232Y819085D02*
X295732Y819585D01*
G01X358232Y827085D02*
Y829585D01*
G01Y817085D02*
Y819585D01*
G01X357732Y827585D02*
Y829085D01*
G01Y817585D02*
Y819085D01*
G01X356232D02*
Y817585D01*
G01Y829085D02*
Y827585D01*
G01X355732Y819585D02*
Y817085D01*
G01Y829585D02*
Y827085D01*
G01X353482Y834835D02*
Y811835D01*
G01X350482D02*
Y834835D01*
G01X348232Y827085D02*
Y829585D01*
G01Y817085D02*
Y819585D01*
G01X347732Y827585D02*
Y829085D01*
G01Y817585D02*
Y819085D01*
G01X346232D02*
Y817585D01*
G01Y829085D02*
Y827585D01*
G01X345732Y819585D02*
Y817085D01*
G01Y829585D02*
Y827085D01*
G01X343482Y834835D02*
Y811835D01*
G01X340482D02*
Y834835D01*
G01X338232Y827085D02*
Y829585D01*
G01Y817085D02*
Y819585D01*
G01X337732Y827585D02*
Y829085D01*
G01Y817585D02*
Y819085D01*
G01X336232D02*
Y817585D01*
G01Y829085D02*
Y827585D01*
G01X335732Y819585D02*
Y817085D01*
G01Y829585D02*
Y827085D01*
G01X333482Y834835D02*
Y811835D01*
G01X330482D02*
Y834835D01*
G01X330082Y805835D02*
Y810835D01*
G01X328232Y827085D02*
Y829585D01*
G01Y817085D02*
Y819585D01*
G01X327732Y827585D02*
Y829085D01*
G01Y817585D02*
Y819085D01*
G01X326232D02*
Y817585D01*
G01Y829085D02*
Y827585D01*
G01X325732Y819585D02*
Y817085D01*
G01Y829585D02*
Y827085D01*
G01X323482Y834835D02*
Y811835D01*
G01X320482D02*
Y834835D01*
G01X318232Y827085D02*
Y829585D01*
G01Y817085D02*
Y819585D01*
G01X317732Y827585D02*
Y829085D01*
G01Y817585D02*
Y819085D01*
G01X316232D02*
Y817585D01*
G01Y829085D02*
Y827585D01*
G01X315732Y819585D02*
Y817085D01*
G01Y829585D02*
Y827085D01*
G01X313882Y805835D02*
Y810835D01*
G01X313482Y834835D02*
Y811835D01*
G01X310482D02*
Y834835D01*
G01X308232Y827085D02*
Y829585D01*
G01Y817085D02*
Y819585D01*
G01X307732Y827585D02*
Y829085D01*
G01Y817585D02*
Y819085D01*
G01X298232Y829585D02*
X295732D01*
G01X308232D02*
X305732D01*
G01X318232D02*
X315732D01*
G01X328232D02*
X325732D01*
G01X338232D02*
X335732D01*
G01X348232D02*
X345732D01*
G01X358232D02*
X355732D01*
G01X297732Y829085D02*
X296232D01*
G01X307732D02*
X306232D01*
G01X317732D02*
X316232D01*
G01X327732D02*
X326232D01*
G01X337732D02*
X336232D01*
G01X347732D02*
X346232D01*
G01X357732D02*
X356232D01*
G01Y827585D02*
X357732D01*
G01X346232D02*
X347732D01*
G01X336232D02*
X337732D01*
G01X326232D02*
X327732D01*
G01X316232D02*
X317732D01*
G01X306232D02*
X307732D01*
G01X296232D02*
X297732D01*
G01X355732Y827085D02*
X358232D01*
G01X335732D02*
X338232D01*
G01X325732D02*
X328232D01*
G01X315732D02*
X318232D01*
G01X305732D02*
X308232D01*
G01X295732D02*
X298232D01*
G01X348232D02*
X345732D01*
G01X298232Y819585D02*
X295732D01*
G01X308232D02*
X305732D01*
G01X318232D02*
X315732D01*
G01X328232D02*
X325732D01*
G01X338232D02*
X335732D01*
G01X348232D02*
X345732D01*
G01X358232D02*
X355732D01*
G01X297732Y819085D02*
X296232D01*
G01X307732D02*
X306232D01*
G01X317732D02*
X316232D01*
G01X327732D02*
X326232D01*
G01X337732D02*
X336232D01*
G01X347732D02*
X346232D01*
G01X357732D02*
X356232D01*
G01X306232D02*
Y817585D01*
G01Y829085D02*
Y827585D01*
G01X305732Y819585D02*
Y817085D01*
G01Y829585D02*
Y827085D01*
G01X303482Y834835D02*
Y811835D01*
G01X300482D02*
Y834835D01*
G01X298232Y827085D02*
Y829585D01*
G01Y817085D02*
Y819585D01*
G01X297732Y827585D02*
Y829085D01*
G01Y817585D02*
Y819085D01*
G01X296232D02*
Y817585D01*
G01Y829085D02*
Y827585D01*
G01X295732Y819585D02*
Y817085D01*
G01Y829585D02*
Y827085D01*
G01X293482Y834835D02*
Y811835D01*
G01X290482D02*
Y834835D01*
G01X356232Y817585D02*
X357732D01*
G01X346232D02*
X347732D01*
G01X336232D02*
X337732D01*
G01X326232D02*
X327732D01*
G01X316232D02*
X317732D01*
G01X306232D02*
X307732D01*
G01X296232D02*
X297732D01*
G01X355732Y817085D02*
X358232D01*
G01X335732D02*
X338232D01*
G01X325732D02*
X328232D01*
G01X315732D02*
X318232D01*
G01X305732D02*
X308232D01*
G01X295732D02*
X298232D01*
G01X348232D02*
X345732D01*
G01X382769Y810048D02*
X330082D01*
G01X386982Y805835D02*
X330082D01*
G01X357732Y819085D02*
X358232Y819585D01*
G01X356232Y817585D02*
X355732Y817085D01*
G01X357732Y829085D02*
X358232Y829585D01*
G01X347732Y819085D02*
X348232Y819585D01*
G01X346232Y817585D02*
X345732Y817085D01*
G01X356232Y827585D02*
X355732Y827085D01*
G01X347732Y829085D02*
X348232Y829585D01*
G01X337732Y819085D02*
X338232Y819585D01*
G01X336232Y817585D02*
X335732Y817085D01*
G01X346232Y827585D02*
X345732Y827085D01*
G01X337732Y829085D02*
X338232Y829585D01*
G01X327732Y819085D02*
X328232Y819585D01*
G01X326232Y817585D02*
X325732Y817085D01*
G01X336232Y827585D02*
X335732Y827085D01*
G01X327732Y829085D02*
X328232Y829585D01*
G01X317732Y819085D02*
X318232Y819585D01*
G01X316232Y817585D02*
X315732Y817085D01*
G01X326232Y827585D02*
X325732Y827085D01*
G01X317732Y829085D02*
X318232Y829585D01*
G01X307732Y819085D02*
X308232Y819585D01*
G01X306232Y817585D02*
X305732Y817085D01*
G01X316232Y827585D02*
X315732Y827085D01*
G01X307732Y829085D02*
X308232Y829585D01*
G01X297732Y819085D02*
X298232Y819585D01*
G01X296232Y817585D02*
X295732Y817085D01*
G01X306232Y827585D02*
X305732Y827085D01*
G01X297732Y829085D02*
X298232Y829585D01*
G01X296232Y827585D02*
X295732Y827085D01*
G01X335827Y933071D02*
G03Y925197I0J-3937D01*
G01X305118D02*
G03Y933071I0J3937D01*
G01X335827D02*
X522441D01*
G01X335827Y925197D02*
X305118D01*
G01X357953Y921300D02*
X358445D01*
G01Y919708D02*
X360741D01*
G01Y919205D02*
X358445D01*
G01Y917363D02*
X357953D01*
G01X358445Y919205D02*
Y917363D01*
G01Y921300D02*
Y919708D01*
G01X357953Y917363D02*
Y921300D01*
G01X372491Y-436116D02*
X372991Y-435251D01*
G01X362491Y-436116D02*
X362991Y-435251D01*
G01X372991Y-428912D02*
Y-435251D01*
G01X370491Y-428912D02*
Y-435251D01*
G01X370991Y-436116D02*
X370491Y-435251D01*
G01X360991Y-436116D02*
X360491Y-435251D01*
G01X362991Y-428912D02*
Y-435251D01*
G01X360491Y-428912D02*
Y-435251D01*
G01X370491D02*
X372991D01*
G01X360491D02*
X362991D01*
G01X370991Y-436116D02*
X372491D01*
G01X360991D02*
X362491D01*
G01X391741Y-414112D02*
Y-386112D01*
G01X385737Y-414112D02*
Y-422612D01*
G01X375237Y-414112D02*
Y-422612D01*
G01X372991Y-421112D02*
Y-422612D01*
G01X370491Y-421112D02*
Y-422612D01*
G01X368241Y-421112D02*
Y-422612D01*
G01X365241Y-421112D02*
Y-422612D01*
G01X362991Y-421112D02*
Y-422612D01*
G01X360491Y-421112D02*
Y-422612D01*
G01X368241Y-421112D02*
X375237D01*
G01X368310Y3627D02*
X368720Y3879D01*
G01X367326Y7397D02*
X366916Y7146D01*
G01X368228Y4046D02*
X368474Y4214D01*
G01X367408Y6978D02*
X367162Y6811D01*
G01X375528Y5805D02*
X375446Y5722D01*
G01X375282Y5889D02*
X375528Y6140D01*
G01X374216Y5805D02*
X374052Y5638D01*
G01Y5973D02*
X374216Y6140D01*
G01X371837Y5805D02*
X371755Y5722D01*
G01X371591Y5889D02*
X371837Y6140D01*
G01X368720Y3879D02*
X368966Y4130D01*
G01X370525Y5805D02*
X370361Y5638D01*
G01Y5973D02*
X370525Y6140D01*
G01X366916Y7146D02*
X366670Y6894D01*
G01X365193Y6811D02*
X364701Y6224D01*
G01Y6894D02*
X365193Y7481D01*
G01X368474Y4214D02*
X368803Y4716D01*
G01X367162Y6811D02*
X366834Y6308D01*
G01X364045Y4968D02*
X363881Y4716D01*
G01X375446Y5722D02*
X375364Y5554D01*
G01X371755Y5722D02*
X371673Y5554D01*
G01X368966Y4130D02*
X369130Y4465D01*
G01X366670Y6894D02*
X366506Y6559D01*
G01X375528Y6140D02*
X375774Y6224D01*
G01X374462Y5889D02*
X374216Y5805D01*
G01Y6140D02*
X374462Y6224D01*
G01X371837Y6140D02*
X372083Y6224D01*
G01X370771Y5889D02*
X370525Y5805D01*
G01Y6140D02*
X370771Y6224D01*
G01X375692Y5889D02*
X375528Y5805D01*
G01X372001Y5889D02*
X371837Y5805D01*
G01X364045Y6140D02*
X362897Y5554D01*
G01X362323D02*
X363881Y6392D01*
G01X369130Y4465D02*
X369212Y4716D01*
G01X366506Y6559D02*
X366424Y6308D01*
G01X369212Y4716D02*
X369295Y5135D01*
G01X366424Y6308D02*
X366342Y5889D01*
G01X368803Y4716D02*
X368884Y5219D01*
G01X366834Y6308D02*
X366752Y5805D01*
G01X376677Y5554D02*
Y3544D01*
G01X376266D02*
Y5554D01*
G01X375364D02*
Y3544D01*
G01X374954D02*
Y5554D01*
G01X374052Y6224D02*
Y5973D01*
G01Y5638D02*
Y3544D01*
G01X373641D02*
Y6224D01*
G01X372986Y5554D02*
Y3544D01*
G01X372575D02*
Y5554D01*
G01X371673D02*
Y3544D01*
G01X371263D02*
Y5554D01*
G01X370361Y6224D02*
Y5973D01*
G01Y5638D02*
Y3544D01*
G01X369951D02*
Y6224D01*
G01X369295Y5135D02*
Y5889D01*
G01X368884Y5219D02*
Y5805D01*
G01X366752D02*
Y5219D01*
G01X366342Y5889D02*
Y5135D01*
G01X365686Y7481D02*
Y3544D01*
G01X365193D02*
Y6811D01*
G01X364701Y6224D02*
Y6894D01*
G01X361667Y7481D02*
Y3544D01*
G01X361175Y5889D02*
Y7481D01*
G01Y3544D02*
Y5387D01*
G01X368884Y5805D02*
X368803Y6308D01*
G01X366752Y5219D02*
X366834Y4716D01*
G01X369295Y5889D02*
X369212Y6308D01*
G01X366342Y5135D02*
X366424Y4716D01*
G01X369212Y6308D02*
X369130Y6559D01*
G01X366424Y4716D02*
X366506Y4465D01*
G01X376512Y5973D02*
X376677Y5554D01*
G01X372821Y5973D02*
X372986Y5554D01*
G01X376266D02*
X376184Y5722D01*
G01X374954Y5554D02*
X374872Y5722D01*
G01X372575Y5554D02*
X372493Y5722D01*
G01X371263Y5554D02*
X371181Y5722D01*
G01X369130Y6559D02*
X368966Y6894D01*
G01X366506Y4465D02*
X366670Y4130D01*
G01X368803Y6308D02*
X368474Y6811D01*
G01X366834Y4716D02*
X367162Y4214D01*
G01X363881Y6392D02*
X364045Y6140D01*
G01X376348D02*
X376512Y5973D01*
G01X376184Y5722D02*
X376102Y5805D01*
G01X375036Y6140D02*
X375282Y5889D01*
G01X374872Y5722D02*
X374790Y5805D01*
G01X372657Y6140D02*
X372821Y5973D01*
G01X372493Y5722D02*
X372411Y5805D01*
G01X371345Y6140D02*
X371591Y5889D01*
G01X371181Y5722D02*
X371099Y5805D01*
G01X368966Y6894D02*
X368720Y7146D01*
G01X366670Y4130D02*
X366916Y3879D01*
G01X368474Y6811D02*
X368228Y6978D01*
G01X367162Y4214D02*
X367408Y4046D01*
G01X368720Y7146D02*
X368310Y7397D01*
G01X366916Y3879D02*
X367326Y3627D01*
G01X363881Y4716D02*
X362323Y5554D01*
G01X376102Y5805D02*
X375938Y5889D01*
G01X374790Y5805D02*
X374626Y5889D01*
G01X372411Y5805D02*
X372247Y5889D01*
G01X371099Y5805D02*
X370935Y5889D01*
G01X362897Y5554D02*
X364045Y4968D01*
G01X376102Y6224D02*
X376348Y6140D01*
G01X374790Y6224D02*
X375036Y6140D01*
G01X372411Y6224D02*
X372657Y6140D01*
G01X371099Y6224D02*
X371345Y6140D01*
G01X368228Y6978D02*
X367818Y7062D01*
G01X367408Y4046D02*
X367818Y3963D01*
G01X368310Y7397D02*
X367818Y7481D01*
G01X367326Y3627D02*
X367818Y3544D01*
G01X365193Y7481D02*
X365686D01*
G01X361175D02*
X361667D01*
G01X373641Y6224D02*
X374052D01*
G01X374462D02*
X374790D01*
G01X375774D02*
X376102D01*
G01X372083D02*
X372411D01*
G01X369951D02*
X370361D01*
G01X370771D02*
X371099D01*
G01X370935Y5889D02*
X370771D01*
G01X375938D02*
X375692D01*
G01X374626D02*
X374462D01*
G01X372247D02*
X372001D01*
G01X361667Y3544D02*
X361175D01*
G01X365686D02*
X365193D01*
G01X370361D02*
X369951D01*
G01X374052D02*
X373641D01*
G01X375364D02*
X374954D01*
G01X372986D02*
X372575D01*
G01X371673D02*
X371263D01*
G01X376677D02*
X376266D01*
G01X367818Y7481D02*
X367326Y7397D01*
G01X367818Y3544D02*
X368310Y3627D01*
G01X367818Y7062D02*
X367408Y6978D01*
G01X367818Y3963D02*
X368228Y4046D01*
G01X414108Y390869D02*
X414928Y387518D01*
G01X408366Y382492D02*
X410006Y385843D01*
G01X414928D02*
X414108Y382492D01*
G01X386220Y387518D02*
X387041Y390869D01*
G01X425590Y378304D02*
Y357363D01*
G01Y384168D02*
Y381655D01*
G01X421490Y357363D02*
Y384168D01*
G01X414928Y361551D02*
Y357363D01*
G01Y387518D02*
Y385843D01*
G01X410006D02*
Y387518D01*
G01X385400Y357363D02*
Y361551D01*
G01X427231Y379979D02*
X425590Y378304D01*
G01Y381655D02*
X427231Y383330D01*
G01X414108Y382492D02*
X412467Y379979D01*
G01X391962Y390031D02*
X390321Y387518D01*
G01X378838Y371603D02*
X377198Y369090D01*
G01X410006Y387518D02*
X408366Y390031D01*
G01X377198Y385843D02*
X378838Y383330D01*
G01X412467Y379979D02*
X391962Y361551D01*
G01X385400D02*
X408366Y382492D01*
G01X387041Y390869D02*
X390321Y394220D01*
G01X410827D02*
X414108Y390869D01*
G01X378838Y383330D02*
X367356Y377466D01*
G01X390321Y394220D02*
X393602Y395895D01*
G01X361614Y377466D02*
X377198Y385843D01*
G01X394423Y391707D02*
X391962Y390031D01*
G01X408366D02*
X405905Y391707D01*
G01X429691Y380817D02*
X427231Y379979D01*
G01Y383330D02*
X429691Y384168D01*
G01X377198Y369090D02*
X361614Y377466D01*
G01X407546Y395895D02*
X410827Y394220D01*
G01X367356Y377466D02*
X378838Y371603D01*
G01X405905Y391707D02*
X401804Y392544D01*
G01X402625Y396733D02*
X407546Y395895D01*
G01X399344Y396733D02*
X402625D01*
G01X401804Y392544D02*
X398523D01*
G01X390321Y387518D02*
X386220D01*
G01X429691Y384168D02*
X432972D01*
G01X421490D02*
X425590D01*
G01X431332Y380817D02*
X429691D01*
G01X391962Y361551D02*
X414928D01*
G01Y357363D02*
X385400D01*
G01X425590D02*
X421490D01*
G01X393602Y395895D02*
X399344Y396733D01*
G01X398523Y392544D02*
X394423Y391707D01*
G01X369226Y818335D02*
G03I-2244J0D01*
G01Y828335D02*
G03I-2244J0D01*
G01X367732Y827585D02*
X368232Y827085D01*
G01X366232Y829085D02*
X365732Y829585D01*
G01X382769Y810048D02*
X381982Y810835D01*
G01X367732Y817585D02*
X368232Y817085D01*
G01X366232Y819085D02*
X365732Y819585D01*
G01X386982Y840835D02*
Y805835D01*
G01X382769Y810048D02*
Y836623D01*
G01X381982Y810835D02*
Y835835D01*
G01X380978Y834835D02*
Y807835D01*
G01X374978Y834835D02*
Y811835D01*
G01X370478Y807835D02*
Y834835D01*
G01X368232Y827085D02*
Y829585D01*
G01Y817085D02*
Y819585D01*
G01X367732Y827585D02*
Y829085D01*
G01Y817585D02*
Y819085D01*
G01X366232D02*
Y817585D01*
G01Y829085D02*
Y827585D01*
G01X365732Y819585D02*
Y817085D01*
G01Y829585D02*
Y827085D01*
G01X363482Y834835D02*
Y811835D01*
G01X360482D02*
Y834835D01*
G01X368232Y829585D02*
X365732D01*
G01X367732Y829085D02*
X366232D01*
G01Y827585D02*
X367732D01*
G01X365732Y827085D02*
X368232D01*
G01Y819585D02*
X365732D01*
G01X367732Y819085D02*
X366232D01*
G01Y817585D02*
X367732D01*
G01X365732Y817085D02*
X368232D01*
G01X380978Y811835D02*
X374978D01*
G01X380978Y807835D02*
X370478D01*
G01X367732Y819085D02*
X368232Y819585D01*
G01X366232Y817585D02*
X365732Y817085D01*
G01X382769Y836623D02*
X381982Y835835D01*
G01X367732Y829085D02*
X368232Y829585D01*
G01X366232Y827585D02*
X365732Y827085D01*
G01X375833Y919373D02*
X375751Y919540D01*
G01X374521Y919373D02*
X374439Y919540D01*
G01X372142Y919373D02*
X372060Y919540D01*
G01X370830Y919373D02*
X370748Y919540D01*
G01X368697Y920378D02*
X368533Y920713D01*
G01X366073Y918284D02*
X366237Y917949D01*
G01X368369Y920127D02*
X368041Y920629D01*
G01X366401Y918535D02*
X366729Y918033D01*
G01X363448Y920211D02*
X363612Y919959D01*
G01X375915D02*
X376079Y919792D01*
G01X375751Y919540D02*
X375669Y919624D01*
G01X374603Y919959D02*
X374849Y919708D01*
G01X374439Y919540D02*
X374357Y919624D01*
G01X372224Y919959D02*
X372388Y919792D01*
G01X372060Y919540D02*
X371978Y919624D01*
G01X370912Y919959D02*
X371158Y919708D01*
G01X370748Y919540D02*
X370666Y919624D01*
G01X368533Y920713D02*
X368287Y920965D01*
G01X366237Y917949D02*
X366483Y917698D01*
G01X368041Y920629D02*
X367795Y920797D01*
G01X366729Y918033D02*
X366975Y917865D01*
G01X368287Y920965D02*
X367877Y921216D01*
G01X366483Y917698D02*
X366893Y917446D01*
G01X368862Y919708D02*
X368779Y920127D01*
G01D02*
X368697Y920378D01*
G01X365991Y918535D02*
X366073Y918284D01*
G01X376079Y919792D02*
X376243Y919373D01*
G01X372388Y919792D02*
X372553Y919373D01*
G01X363448Y918535D02*
X361890Y919373D01*
G01X375669Y919624D02*
X375505Y919708D01*
G01X374357Y919624D02*
X374193Y919708D01*
G01X371978Y919624D02*
X371814Y919708D01*
G01X370666Y919624D02*
X370502Y919708D01*
G01X362464Y919373D02*
X363612Y918787D01*
G01X375669Y920043D02*
X375915Y919959D01*
G01X374357Y920043D02*
X374603Y919959D01*
G01X371978Y920043D02*
X372224Y919959D01*
G01X370666Y920043D02*
X370912Y919959D01*
G01X368451Y919624D02*
X368369Y920127D01*
G01X366319Y919038D02*
X366401Y918535D01*
G01X365909Y918954D02*
X365991Y918535D01*
G01X367795Y920797D02*
X367385Y920881D01*
G01X366975Y917865D02*
X367385Y917781D01*
G01X367877Y921216D02*
X367385Y921300D01*
G01X366893Y917446D02*
X367385Y917363D01*
G01X364760Y921300D02*
X365253D01*
G01X360741D02*
X361234D01*
G01X373208Y920043D02*
X373619D01*
G01X374029D02*
X374357D01*
G01X375341D02*
X375669D01*
G01X371650D02*
X371978D01*
G01X369517D02*
X369928D01*
G01X370338D02*
X370666D01*
G01X370502Y919708D02*
X370338D01*
G01X375505D02*
X375259D01*
G01X374193D02*
X374029D01*
G01X371814D02*
X371568D01*
G01X361234Y917363D02*
X360741D01*
G01X365253D02*
X364760D01*
G01X369928D02*
X369517D01*
G01X371240D02*
X370830D01*
G01X373619D02*
X373208D01*
G01X376243D02*
X375833D01*
G01X374931D02*
X374521D01*
G01X372553D02*
X372142D01*
G01X376243Y919373D02*
Y917363D01*
G01X375833D02*
Y919373D01*
G01X374931D02*
Y917363D01*
G01X374521D02*
Y919373D01*
G01X373619Y920043D02*
Y919792D01*
G01Y919457D02*
Y917363D01*
G01X373208D02*
Y920043D01*
G01X372553Y919373D02*
Y917363D01*
G01X372142D02*
Y919373D01*
G01X371240D02*
Y917363D01*
G01X370830D02*
Y919373D01*
G01X369928Y920043D02*
Y919792D01*
G01Y919457D02*
Y917363D01*
G01X369517D02*
Y920043D01*
G01X368862Y918954D02*
Y919708D01*
G01X368451Y919038D02*
Y919624D01*
G01X366319D02*
Y919038D01*
G01X365909Y919708D02*
Y918954D01*
G01X365253Y921300D02*
Y917363D01*
G01X364760D02*
Y920629D01*
G01X364268Y920043D02*
Y920713D01*
G01X361234Y921300D02*
Y917363D01*
G01X360741Y919708D02*
Y921300D01*
G01Y917363D02*
Y919205D01*
G01X367385Y921300D02*
X366893Y921216D01*
G01X367385Y917363D02*
X367877Y917446D01*
G01X368779Y918535D02*
X368862Y918954D01*
G01X365991Y920127D02*
X365909Y919708D01*
G01X368369Y918535D02*
X368451Y919038D01*
G01X366401Y920127D02*
X366319Y919624D01*
G01X367385Y920881D02*
X366975Y920797D01*
G01X367385Y917781D02*
X367795Y917865D01*
G01X368697Y918284D02*
X368779Y918535D01*
G01X366073Y920378D02*
X365991Y920127D01*
G01X375013Y919540D02*
X374931Y919373D01*
G01X371322Y919540D02*
X371240Y919373D01*
G01X368533Y917949D02*
X368697Y918284D01*
G01X366237Y920713D02*
X366073Y920378D01*
G01X368041Y918033D02*
X368369Y918535D01*
G01X366729Y920629D02*
X366401Y920127D01*
G01X363612Y918787D02*
X363448Y918535D01*
G01X375095Y919624D02*
X375013Y919540D01*
G01X374849Y919708D02*
X375095Y919959D01*
G01X373783Y919624D02*
X373619Y919457D01*
G01Y919792D02*
X373783Y919959D01*
G01X371404Y919624D02*
X371322Y919540D01*
G01X371158Y919708D02*
X371404Y919959D01*
G01X368287Y917698D02*
X368533Y917949D01*
G01X370092Y919624D02*
X369928Y919457D01*
G01Y919792D02*
X370092Y919959D01*
G01X366483Y920965D02*
X366237Y920713D01*
G01X364760Y920629D02*
X364268Y920043D01*
G01Y920713D02*
X364760Y921300D01*
G01X367795Y917865D02*
X368041Y918033D01*
G01X366975Y920797D02*
X366729Y920629D01*
G01X375259Y919708D02*
X375095Y919624D01*
G01X371568Y919708D02*
X371404Y919624D01*
G01X363612Y919959D02*
X362464Y919373D01*
G01X361890D02*
X363448Y920211D01*
G01X367877Y917446D02*
X368287Y917698D01*
G01X366893Y921216D02*
X366483Y920965D01*
G01X375095Y919959D02*
X375341Y920043D01*
G01X374029Y919708D02*
X373783Y919624D01*
G01Y919959D02*
X374029Y920043D01*
G01X371404Y919959D02*
X371650Y920043D01*
G01X370338Y919708D02*
X370092Y919624D01*
G01Y919959D02*
X370338Y920043D01*
G01X483071Y-7874D02*
G03Y0I0J3937D01*
G01X513779D02*
X483071D01*
G01X476443Y379142D02*
X475623Y377466D01*
G01X488747D02*
Y357363D01*
G01X484645D02*
Y377466D01*
G01X475623D02*
Y357363D01*
G01X471522D02*
Y377466D01*
G01X462500Y378304D02*
Y357363D01*
G01Y384168D02*
Y381655D01*
G01X458399Y357363D02*
Y384168D01*
G01X451837Y377466D02*
Y357363D01*
G01X447736D02*
Y377466D01*
G01X487106Y381655D02*
X488747Y377466D01*
G01X450197Y381655D02*
X451837Y377466D01*
G01X484645D02*
X483825Y379142D01*
G01X439534D02*
X438714Y377466D01*
G01D02*
Y357363D01*
G01X434613D02*
Y377466D01*
G01X471522D02*
X470702Y379142D01*
G01X447736Y377466D02*
X446916Y379142D01*
G01X434613Y377466D02*
X433793Y379142D01*
G01X477264Y379979D02*
X476443Y379142D01*
G01X474803Y380817D02*
X477264Y383330D01*
G01X464140Y379979D02*
X462500Y378304D01*
G01Y381655D02*
X464140Y383330D01*
G01X440354Y379979D02*
X439534Y379142D01*
G01X437893Y380817D02*
X440354Y383330D01*
G01X485466D02*
X487106Y381655D01*
G01X483825Y379142D02*
X483005Y379979D01*
G01X472342Y383330D02*
X474803Y380817D01*
G01X470702Y379142D02*
X469882Y379979D01*
G01X448556Y383330D02*
X450197Y381655D01*
G01X446916Y379142D02*
X446096Y379979D01*
G01X435433Y383330D02*
X437893Y380817D01*
G01X433793Y379142D02*
X432972Y379979D01*
G01X478904Y380817D02*
X477264Y379979D01*
G01X441995Y380817D02*
X440354Y379979D01*
G01X477264Y383330D02*
X479724Y384168D01*
G01X466601Y380817D02*
X464140Y379979D01*
G01Y383330D02*
X466601Y384168D01*
G01X440354Y383330D02*
X442815Y384168D01*
G01X483005Y379979D02*
X481365Y380817D01*
G01X469882Y379979D02*
X468241Y380817D01*
G01X446096Y379979D02*
X444455Y380817D01*
G01X432972Y379979D02*
X431332Y380817D01*
G01X483005Y384168D02*
X485466Y383330D01*
G01X469882Y384168D02*
X472342Y383330D01*
G01X446096Y384168D02*
X448556Y383330D01*
G01X432972Y384168D02*
X435433Y383330D01*
G01X479724Y384168D02*
X483005D01*
G01X466601D02*
X469882D01*
G01X458399D02*
X462500D01*
G01X442815D02*
X446096D01*
G01X444455Y380817D02*
X441995D01*
G01X468241D02*
X466601D01*
G01X481365D02*
X478904D01*
G01X438714Y357363D02*
X434613D01*
G01X451837D02*
X447736D01*
G01X462500D02*
X458399D01*
G01X475623D02*
X471522D01*
G01X488747D02*
X484645D01*
G01X513779Y0D02*
G03Y-7874I0J-3937D01*
G01X719291D02*
X513779D01*
G01X553149Y933071D02*
G03Y925197I0J-3937D01*
G01X522441D02*
G03Y933071I0J3937D01*
G01X553149D02*
X719291D01*
G01X553149Y925197D02*
X522441D01*
G01X711161Y-14685D02*
Y-19685D01*
G01X708661Y-14685D02*
Y-17185D01*
G01X706161Y-19685D02*
Y-14685D01*
G01X700537Y-25185D02*
Y-9185D01*
G01D02*
X716785D01*
G01X706161Y-14685D02*
X711161D01*
G01X708661Y-17185D02*
X711161D01*
G01Y-19685D02*
X706161D01*
G01X716785Y-25185D02*
X700537D01*
G01X726378Y39370D02*
G03I-9843J0D01*
G01X756406Y-442785D02*
G03X805515Y-467956I38116J13873D01*
G01X790823Y-430258D02*
X752707Y-444131D01*
G01X774837Y-399239D02*
X797278D01*
G01X794522D02*
X774837D01*
G01X758644Y-409990D02*
G03X753960Y-428912I35878J-18922D01*
G01X764601D02*
X750023D01*
G01X768538D02*
Y-422612D01*
G01X764601Y-428912D02*
Y-422612D01*
G01X760664Y-428912D02*
Y-422612D01*
G01X773425Y-211849D02*
X763189D01*
X765236Y-213384D01*
G01X773425D02*
Y-210313D01*
G01X772231Y-203788D02*
X773084Y-202892D01*
X773425Y-201868D01*
X773084Y-200845D01*
X772060Y-199949D01*
X770525Y-199309D01*
X768989Y-199053D01*
X767113D01*
X765578Y-199309D01*
X764213Y-199949D01*
X763530Y-200717D01*
X763189Y-201613D01*
X763530Y-202636D01*
X764213Y-203404D01*
X765236Y-203916D01*
X766601Y-204172D01*
X767795Y-203916D01*
X768989Y-203276D01*
X769672Y-202508D01*
X769843Y-201613D01*
X769501Y-200589D01*
X768648Y-199821D01*
X767113Y-199053D01*
G01X773425Y-191632D02*
X771207Y-191377D01*
X769331Y-190993D01*
X767625Y-190481D01*
X765748Y-189841D01*
X763189Y-188817D01*
Y-193936D01*
G01X773766Y-181141D02*
X773596Y-181396D01*
X773254D01*
X773084Y-181141D01*
X773254Y-180885D01*
X773596D01*
X773766Y-181141D01*
G01X763189Y-170905D02*
X763530Y-171928D01*
X764383Y-172696D01*
X765407Y-173208D01*
X766772Y-173591D01*
X768307Y-173719D01*
X769843Y-173591D01*
X771207Y-173208D01*
X772231Y-172696D01*
X773084Y-171928D01*
X773425Y-170905D01*
X773084Y-169881D01*
X772231Y-169113D01*
X771207Y-168601D01*
X769843Y-168218D01*
X768307Y-168090D01*
X766772Y-168218D01*
X765407Y-168601D01*
X764383Y-169113D01*
X763530Y-169881D01*
X763189Y-170905D01*
G01Y-160669D02*
X763530Y-161692D01*
X764383Y-162460D01*
X765407Y-162972D01*
X766772Y-163355D01*
X768307Y-163483D01*
X769843Y-163355D01*
X771207Y-162972D01*
X772231Y-162460D01*
X773084Y-161692D01*
X773425Y-160669D01*
X773084Y-159645D01*
X772231Y-158877D01*
X771207Y-158365D01*
X769843Y-157982D01*
X768307Y-157854D01*
X766772Y-157982D01*
X765407Y-158365D01*
X764383Y-158877D01*
X763530Y-159645D01*
X763189Y-160669D01*
G01X757677Y-211849D02*
X747441D01*
X749488Y-213384D01*
G01X757677D02*
Y-210313D01*
G01X756483Y-203788D02*
X757336Y-202892D01*
X757677Y-201868D01*
X757336Y-200845D01*
X756312Y-199949D01*
X754777Y-199309D01*
X753241Y-199053D01*
X751365D01*
X749830Y-199309D01*
X748465Y-199949D01*
X747782Y-200717D01*
X747441Y-201613D01*
X747782Y-202636D01*
X748465Y-203404D01*
X749488Y-203916D01*
X750853Y-204172D01*
X752047Y-203916D01*
X753241Y-203276D01*
X753924Y-202508D01*
X754095Y-201613D01*
X753753Y-200589D01*
X752900Y-199821D01*
X751365Y-199053D01*
G01X755630Y-194191D02*
X756824Y-193424D01*
X757506Y-192400D01*
X757677Y-191248D01*
X757506Y-190225D01*
X756654Y-189201D01*
X755630Y-188562D01*
X754606Y-188434D01*
X753412Y-188690D01*
X752559Y-189585D01*
X752218Y-190481D01*
Y-191632D01*
G01Y-190481D02*
X751706Y-189713D01*
X750853Y-189073D01*
X749830Y-188817D01*
X748806Y-189073D01*
X747953Y-189713D01*
X747441Y-190865D01*
X747612Y-192016D01*
X748294Y-193168D01*
G01X758018Y-181141D02*
X757848Y-181396D01*
X757506D01*
X757336Y-181141D01*
X757506Y-180885D01*
X757848D01*
X758018Y-181141D01*
G01X747441Y-170905D02*
X747782Y-171928D01*
X748635Y-172696D01*
X749659Y-173208D01*
X751024Y-173591D01*
X752559Y-173719D01*
X754095Y-173591D01*
X755459Y-173208D01*
X756483Y-172696D01*
X757336Y-171928D01*
X757677Y-170905D01*
X757336Y-169881D01*
X756483Y-169113D01*
X755459Y-168601D01*
X754095Y-168218D01*
X752559Y-168090D01*
X751024Y-168218D01*
X749659Y-168601D01*
X748635Y-169113D01*
X747782Y-169881D01*
X747441Y-170905D01*
G01Y-160669D02*
X747782Y-161692D01*
X748635Y-162460D01*
X749659Y-162972D01*
X751024Y-163355D01*
X752559Y-163483D01*
X754095Y-163355D01*
X755459Y-162972D01*
X756483Y-162460D01*
X757336Y-161692D01*
X757677Y-160669D01*
X757336Y-159645D01*
X756483Y-158877D01*
X755459Y-158365D01*
X754095Y-157982D01*
X752559Y-157854D01*
X751024Y-157982D01*
X749659Y-158365D01*
X748635Y-158877D01*
X747782Y-159645D01*
X747441Y-160669D01*
G01X775590Y-19685D02*
Y-152499D01*
G01X759842Y0D02*
Y-152499D01*
G01X779527Y-15748D02*
X838479D01*
G01X763779Y-7874D02*
G03X767716Y-3937I0J3937D01*
G01X719291Y-7874D02*
G03Y0I0J3937D01*
G01X750000D02*
G03Y-7874I0J-3937D01*
G01X782578Y-15748D02*
G03I-6988J0D01*
G01X716785Y-9185D02*
Y-25185D01*
G01X763779Y-7874D02*
X750000D01*
G01X755905Y0D02*
G03X759842Y3937I0J3937D01*
G01X755905Y0D02*
G03X759842Y3937I0J3937D01*
G01X767716Y185827D02*
Y-3937D01*
G01X759842Y3937D02*
Y921260D01*
G01Y3937D02*
Y324213D01*
G01X750000Y0D02*
X719291D01*
G01X767716Y185827D02*
G03X759842I-3937J0D01*
G01Y216536D02*
Y185827D01*
G01Y216536D02*
G03X767716I3937J0D01*
G01Y316339D02*
Y216536D01*
G01X771653Y320276D02*
G03X767716Y316339I0J-3937D01*
G01X763779Y328150D02*
G03X759842Y324213I0J-3937D01*
G01X773228Y341142D02*
Y343898D01*
G01Y337205D02*
Y339961D01*
G01Y333268D02*
Y336024D01*
G01Y329331D02*
Y332087D01*
G01Y343898D02*
X789764D01*
G01Y341142D02*
X773228D01*
G01Y339961D02*
X789764D01*
G01Y337205D02*
X773228D01*
G01Y336024D02*
X789764D01*
G01Y333268D02*
X773228D01*
G01Y332087D02*
X789764D01*
G01Y329331D02*
X773228D01*
G01X793307Y328150D02*
X763779D01*
G01X791338Y320276D02*
X771653D01*
G01X765945Y379725D02*
G03Y372244I0J-3741D01*
G01X773228Y412008D02*
Y414764D01*
G01Y408071D02*
Y410827D01*
G01Y404134D02*
Y406890D01*
G01Y400197D02*
Y402953D01*
G01Y396260D02*
Y399016D01*
G01Y392323D02*
Y395079D01*
G01Y388386D02*
Y391142D01*
G01Y384449D02*
Y387205D01*
G01Y380512D02*
Y383268D01*
G01Y368701D02*
Y371457D01*
G01Y364764D02*
Y367520D01*
G01Y360827D02*
Y363583D01*
G01Y356890D02*
Y359646D01*
G01Y352953D02*
Y355709D01*
G01Y349016D02*
Y351772D01*
G01Y345079D02*
Y347835D01*
G01Y414764D02*
X789764D01*
G01Y412008D02*
X773228D01*
G01Y410827D02*
X789764D01*
G01Y408071D02*
X773228D01*
G01Y406890D02*
X789764D01*
G01Y404134D02*
X773228D01*
G01Y402953D02*
X789764D01*
G01Y400197D02*
X773228D01*
G01Y399016D02*
X789764D01*
G01Y396260D02*
X773228D01*
G01Y395079D02*
X789764D01*
G01Y392323D02*
X773228D01*
G01Y391142D02*
X789764D01*
G01Y388386D02*
X773228D01*
G01Y387205D02*
X789764D01*
G01Y384449D02*
X773228D01*
G01Y383268D02*
X789764D01*
G01Y380512D02*
X773228D01*
G01X793307Y379725D02*
X765945D01*
G01X793307Y372244D02*
X765945D01*
G01X773228Y371457D02*
X789764D01*
G01Y368701D02*
X773228D01*
G01Y367520D02*
X789764D01*
G01Y364764D02*
X773228D01*
G01Y363583D02*
X789764D01*
G01Y360827D02*
X773228D01*
G01Y359646D02*
X789764D01*
G01Y356890D02*
X773228D01*
G01Y355709D02*
X789764D01*
G01Y352953D02*
X773228D01*
G01Y351772D02*
X789764D01*
G01Y349016D02*
X773228D01*
G01Y347835D02*
X789764D01*
G01Y345079D02*
X773228D01*
G01Y482874D02*
Y485630D01*
G01Y478937D02*
Y481693D01*
G01Y475000D02*
Y477756D01*
G01Y471063D02*
Y473819D01*
G01Y467126D02*
Y469882D01*
G01Y463189D02*
Y465945D01*
G01Y459252D02*
Y462008D01*
G01Y455315D02*
Y458071D01*
G01Y451378D02*
Y454134D01*
G01Y447441D02*
Y450197D01*
G01Y443504D02*
Y446260D01*
G01Y439567D02*
Y442323D01*
G01Y435630D02*
Y438386D01*
G01Y431693D02*
Y434449D01*
G01Y427756D02*
Y430512D01*
G01Y423819D02*
Y426575D01*
G01Y419882D02*
Y422638D01*
G01Y415945D02*
Y418701D01*
G01Y485630D02*
X789764D01*
G01Y482874D02*
X773228D01*
G01Y481693D02*
X789764D01*
G01Y478937D02*
X773228D01*
G01Y477756D02*
X789764D01*
G01Y475000D02*
X773228D01*
G01Y473819D02*
X789764D01*
G01Y471063D02*
X773228D01*
G01Y469882D02*
X789764D01*
G01Y467126D02*
X773228D01*
G01Y465945D02*
X789764D01*
G01Y463189D02*
X773228D01*
G01Y462008D02*
X789764D01*
G01Y459252D02*
X773228D01*
G01Y458071D02*
X789764D01*
G01Y455315D02*
X773228D01*
G01Y454134D02*
X789764D01*
G01Y451378D02*
X773228D01*
G01Y450197D02*
X789764D01*
G01Y447441D02*
X773228D01*
G01Y446260D02*
X789764D01*
G01Y443504D02*
X773228D01*
G01Y442323D02*
X789764D01*
G01Y439567D02*
X773228D01*
G01Y438386D02*
X789764D01*
G01Y435630D02*
X773228D01*
G01Y434449D02*
X789764D01*
G01Y431693D02*
X773228D01*
G01Y430512D02*
X789764D01*
G01Y427756D02*
X773228D01*
G01Y426575D02*
X789764D01*
G01Y423819D02*
X773228D01*
G01Y422638D02*
X789764D01*
G01Y419882D02*
X773228D01*
G01Y418701D02*
X789764D01*
G01Y415945D02*
X773228D01*
G01Y553740D02*
Y556496D01*
G01Y549803D02*
Y552559D01*
G01Y545866D02*
Y548622D01*
G01Y541929D02*
Y544685D01*
G01Y537992D02*
Y540748D01*
G01Y534055D02*
Y536811D01*
G01Y530118D02*
Y532874D01*
G01Y526181D02*
Y528937D01*
G01Y522244D02*
Y525000D01*
G01Y518307D02*
Y521063D01*
G01Y514370D02*
Y517126D01*
G01Y510433D02*
Y513189D01*
G01Y506496D02*
Y509252D01*
G01Y502559D02*
Y505315D01*
G01Y498622D02*
Y501378D01*
G01Y494685D02*
Y497441D01*
G01Y490748D02*
Y493504D01*
G01Y486811D02*
Y489567D01*
G01X789764Y553740D02*
X773228D01*
G01Y552559D02*
X789764D01*
G01Y549803D02*
X773228D01*
G01Y548622D02*
X789764D01*
G01Y545866D02*
X773228D01*
G01Y544685D02*
X789764D01*
G01Y541929D02*
X773228D01*
G01Y540748D02*
X789764D01*
G01Y537992D02*
X773228D01*
G01Y536811D02*
X789764D01*
G01Y534055D02*
X773228D01*
G01Y532874D02*
X789764D01*
G01Y530118D02*
X773228D01*
G01Y528937D02*
X789764D01*
G01Y526181D02*
X773228D01*
G01Y525000D02*
X789764D01*
G01Y522244D02*
X773228D01*
G01Y521063D02*
X789764D01*
G01Y518307D02*
X773228D01*
G01Y517126D02*
X789764D01*
G01Y514370D02*
X773228D01*
G01Y513189D02*
X789764D01*
G01Y510433D02*
X773228D01*
G01Y509252D02*
X789764D01*
G01Y506496D02*
X773228D01*
G01Y505315D02*
X789764D01*
G01Y502559D02*
X773228D01*
G01Y501378D02*
X789764D01*
G01Y498622D02*
X773228D01*
G01Y497441D02*
X789764D01*
G01Y494685D02*
X773228D01*
G01Y493504D02*
X789764D01*
G01Y490748D02*
X773228D01*
G01Y489567D02*
X789764D01*
G01Y486811D02*
X773228D01*
G01Y624607D02*
Y627363D01*
G01Y620670D02*
Y623426D01*
G01Y616733D02*
Y619489D01*
G01Y612796D02*
Y615552D01*
G01Y608859D02*
Y611615D01*
G01Y604922D02*
Y607677D01*
G01Y600985D02*
Y603740D01*
G01Y597048D02*
Y599803D01*
G01Y593111D02*
Y595866D01*
G01Y589174D02*
Y591929D01*
G01Y585237D02*
Y587992D01*
G01Y581300D02*
Y584055D01*
G01Y577363D02*
Y580118D01*
G01Y573426D02*
Y576181D01*
G01Y569489D02*
Y572244D01*
G01Y565552D02*
Y568307D01*
G01Y561615D02*
Y564370D01*
G01Y557677D02*
Y560433D01*
G01X789764Y624607D02*
X773228D01*
G01Y623426D02*
X789764D01*
G01Y620670D02*
X773228D01*
G01Y619489D02*
X789764D01*
G01Y616733D02*
X773228D01*
G01Y615552D02*
X789764D01*
G01Y612796D02*
X773228D01*
G01Y611615D02*
X789764D01*
G01Y608859D02*
X773228D01*
G01Y607677D02*
X789764D01*
G01Y604922D02*
X773228D01*
G01Y603740D02*
X789764D01*
G01Y600985D02*
X773228D01*
G01Y599803D02*
X789764D01*
G01Y597048D02*
X773228D01*
G01Y595866D02*
X789764D01*
G01Y593111D02*
X773228D01*
G01Y591929D02*
X789764D01*
G01Y589174D02*
X773228D01*
G01Y587992D02*
X789764D01*
G01Y585237D02*
X773228D01*
G01Y584055D02*
X789764D01*
G01Y581300D02*
X773228D01*
G01Y580118D02*
X789764D01*
G01Y577363D02*
X773228D01*
G01Y576181D02*
X789764D01*
G01Y573426D02*
X773228D01*
G01Y572244D02*
X789764D01*
G01Y569489D02*
X773228D01*
G01Y568307D02*
X789764D01*
G01Y565552D02*
X773228D01*
G01Y564370D02*
X789764D01*
G01Y561615D02*
X773228D01*
G01Y560433D02*
X789764D01*
G01Y557677D02*
X773228D01*
G01Y556496D02*
X789764D01*
G01X759842Y663977D02*
G03X763779Y660040I3937J0D01*
G01X773228Y656103D02*
Y658859D01*
G01Y652166D02*
Y654922D01*
G01Y648229D02*
Y650985D01*
G01Y644292D02*
Y647048D01*
G01Y640355D02*
Y643111D01*
G01Y636418D02*
Y639174D01*
G01Y632481D02*
Y635237D01*
G01Y628544D02*
Y631300D01*
G01X759842Y663977D02*
Y733662D01*
G01X793307Y660040D02*
X763779D01*
G01X773228Y658859D02*
X789764D01*
G01Y656103D02*
X773228D01*
G01Y654922D02*
X785827D01*
G01Y652166D02*
X773228D01*
G01Y650985D02*
X789764D01*
G01Y648229D02*
X773228D01*
G01Y647048D02*
X789764D01*
G01Y644292D02*
X773228D01*
G01Y643111D02*
X789764D01*
G01Y640355D02*
X773228D01*
G01Y639174D02*
X789764D01*
G01Y636418D02*
X773228D01*
G01Y635237D02*
X789764D01*
G01Y632481D02*
X773228D01*
G01Y631300D02*
X789764D01*
G01Y628544D02*
X773228D01*
G01Y627363D02*
X789764D01*
G01X763779Y737599D02*
G03X759842Y733662I0J-3937D01*
G01X773228Y766339D02*
Y769095D01*
G01Y762402D02*
Y765158D01*
G01Y758465D02*
Y761221D01*
G01Y754528D02*
Y757284D01*
G01Y750591D02*
Y753347D01*
G01Y746654D02*
Y749410D01*
G01Y742717D02*
Y745473D01*
G01Y738780D02*
Y741536D01*
G01X789764Y766339D02*
X773228D01*
G01Y765158D02*
X789764D01*
G01Y762402D02*
X773228D01*
G01Y761221D02*
X789764D01*
G01Y758465D02*
X773228D01*
G01Y757284D02*
X789764D01*
G01Y754528D02*
X773228D01*
G01Y753347D02*
X789764D01*
G01Y750591D02*
X773228D01*
G01Y749410D02*
X789764D01*
G01Y746654D02*
X773228D01*
G01Y745473D02*
X789764D01*
G01Y742717D02*
X773228D01*
G01Y741536D02*
X789764D01*
G01Y738780D02*
X773228D01*
G01X793307Y737599D02*
X763779D01*
G01X765945Y789174D02*
G03Y781693I0J-3740D01*
G01X767716Y829331D02*
G03X771653Y825394I3937J0D01*
G01X759842Y821457D02*
G03X763779Y817520I3937J0D01*
G01X773228Y809646D02*
Y812402D01*
G01Y813583D02*
Y816339D01*
G01Y805709D02*
Y808465D01*
G01Y801772D02*
Y804528D01*
G01Y797835D02*
Y800591D01*
G01Y793898D02*
Y796654D01*
G01Y789961D02*
Y792717D01*
G01Y778150D02*
Y780906D01*
G01Y774213D02*
Y776969D01*
G01Y770276D02*
Y773032D01*
G01X767716Y855118D02*
Y829331D01*
G01X759842Y921260D02*
Y821457D01*
G01X771653Y825394D02*
X791338D01*
G01X793307Y817520D02*
X763779D01*
G01X773228Y816339D02*
X789764D01*
G01Y813583D02*
X773228D01*
G01Y812402D02*
X785827D01*
G01Y809646D02*
X773228D01*
G01Y808465D02*
X789764D01*
G01Y805709D02*
X773228D01*
G01Y804528D02*
X789764D01*
G01Y801772D02*
X773228D01*
G01Y800591D02*
X789764D01*
G01Y797835D02*
X773228D01*
G01Y796654D02*
X789764D01*
G01Y793898D02*
X773228D01*
G01Y792717D02*
X789764D01*
G01Y789961D02*
X773228D01*
G01X793307Y789174D02*
X765945D01*
G01X793307Y781693D02*
X765945D01*
G01X773228Y780906D02*
X789764D01*
G01Y778150D02*
X773228D01*
G01Y776969D02*
X789764D01*
G01Y774213D02*
X773228D01*
G01Y773032D02*
X789764D01*
G01Y770276D02*
X773228D01*
G01Y769095D02*
X789764D01*
G01X767716Y855118D02*
G03X759842I-3937J0D01*
G01Y885827D02*
G03X767716I3937J0D01*
G01Y929134D02*
Y885827D01*
G01X759842D02*
Y855118D01*
G01X775590Y944882D02*
Y1015079D01*
G01X779527Y940945D02*
X838479D01*
G01X759842Y921260D02*
G03X755905Y925197I-3937J0D01*
G01X767716Y929134D02*
G03X763779Y933071I-3937J0D01*
G01X750000D02*
G03Y925197I0J-3937D01*
G01X719291D02*
G03Y933071I0J3937D01*
G01X759842Y921260D02*
G03X755905Y925197I-3937J0D01*
G01X782578Y940945D02*
G03I-6988J0D01*
G01X750000Y933071D02*
X763779D01*
G01X750000Y925197D02*
X719291D01*
G01X773425Y1023248D02*
X763189D01*
X765236Y1021713D01*
G01X773425D02*
Y1024784D01*
G01X772231Y1031309D02*
X773084Y1032205D01*
X773425Y1033229D01*
X773084Y1034252D01*
X772060Y1035148D01*
X770525Y1035788D01*
X768989Y1036044D01*
X767113D01*
X765578Y1035788D01*
X764213Y1035148D01*
X763530Y1034380D01*
X763189Y1033484D01*
X763530Y1032461D01*
X764213Y1031693D01*
X765236Y1031181D01*
X766601Y1030925D01*
X767795Y1031181D01*
X768989Y1031821D01*
X769672Y1032589D01*
X769843Y1033484D01*
X769501Y1034508D01*
X768648Y1035276D01*
X767113Y1036044D01*
G01X773425Y1043465D02*
X771207Y1043720D01*
X769331Y1044104D01*
X767625Y1044616D01*
X765748Y1045256D01*
X763189Y1046280D01*
Y1041161D01*
G01X773766Y1053956D02*
X773596Y1053701D01*
X773254D01*
X773084Y1053956D01*
X773254Y1054212D01*
X773596D01*
X773766Y1053956D01*
G01X763189Y1064192D02*
X763530Y1063169D01*
X764383Y1062401D01*
X765407Y1061889D01*
X766772Y1061506D01*
X768307Y1061378D01*
X769843Y1061506D01*
X771207Y1061889D01*
X772231Y1062401D01*
X773084Y1063169D01*
X773425Y1064192D01*
X773084Y1065216D01*
X772231Y1065984D01*
X771207Y1066496D01*
X769843Y1066879D01*
X768307Y1067007D01*
X766772Y1066879D01*
X765407Y1066496D01*
X764383Y1065984D01*
X763530Y1065216D01*
X763189Y1064192D01*
G01Y1074428D02*
X763530Y1073405D01*
X764383Y1072637D01*
X765407Y1072125D01*
X766772Y1071742D01*
X768307Y1071614D01*
X769843Y1071742D01*
X771207Y1072125D01*
X772231Y1072637D01*
X773084Y1073405D01*
X773425Y1074428D01*
X773084Y1075452D01*
X772231Y1076220D01*
X771207Y1076732D01*
X769843Y1077115D01*
X768307Y1077243D01*
X766772Y1077115D01*
X765407Y1076732D01*
X764383Y1076220D01*
X763530Y1075452D01*
X763189Y1074428D01*
G01X848171Y-468875D02*
X849450Y-465463D01*
X850730D01*
X853289Y-472287D01*
X854569D01*
X855848Y-468875D01*
G01X818397Y-463757D02*
X819165Y-462734D01*
X820061Y-462222D01*
X821084Y-462051D01*
X822364Y-462392D01*
X823260Y-463245D01*
X823515Y-464269D01*
X823388Y-465293D01*
X822876Y-466145D01*
X820317Y-467851D01*
X819165Y-469046D01*
X818397Y-470752D01*
X818142Y-472287D01*
X823515D01*
G01X831064Y-462051D02*
X830041Y-462392D01*
X829273Y-463245D01*
X828761Y-464269D01*
X828378Y-465634D01*
X828250Y-467169D01*
X828378Y-468705D01*
X828761Y-470069D01*
X829273Y-471093D01*
X830041Y-471946D01*
X831064Y-472287D01*
X832088Y-471946D01*
X832856Y-471093D01*
X833368Y-470069D01*
X833751Y-468705D01*
X833879Y-467169D01*
X833751Y-465634D01*
X833368Y-464269D01*
X832856Y-463245D01*
X832088Y-462392D01*
X831064Y-462051D01*
G01X841300Y-472628D02*
X841045Y-472458D01*
Y-472116D01*
X841300Y-471946D01*
X841556Y-472116D01*
Y-472458D01*
X841300Y-472628D01*
G01X851536Y-462051D02*
X850513Y-462392D01*
X849745Y-463245D01*
X849233Y-464269D01*
X848850Y-465634D01*
X848722Y-467169D01*
X848850Y-468705D01*
X849233Y-470069D01*
X849745Y-471093D01*
X850513Y-471946D01*
X851536Y-472287D01*
X852560Y-471946D01*
X853328Y-471093D01*
X853840Y-470069D01*
X854223Y-468705D01*
X854351Y-467169D01*
X854223Y-465634D01*
X853840Y-464269D01*
X853328Y-463245D01*
X852560Y-462392D01*
X851536Y-462051D01*
G01X805515Y-467956D02*
X808329D01*
G01X821786Y-397074D02*
Y-386838D01*
X820251Y-388885D01*
G01Y-397074D02*
X823322D01*
G01X832022Y-397415D02*
X831767Y-397245D01*
Y-396903D01*
X832022Y-396733D01*
X832278Y-396903D01*
Y-397245D01*
X832022Y-397415D01*
G01X843794Y-397074D02*
Y-386838D01*
X839060Y-394174D01*
X845457D01*
G01X852494Y-386838D02*
X851471Y-387179D01*
X850703Y-388032D01*
X850191Y-389056D01*
X849808Y-390421D01*
X849680Y-391956D01*
X849808Y-393492D01*
X850191Y-394856D01*
X850703Y-395880D01*
X851471Y-396733D01*
X852494Y-397074D01*
X853518Y-396733D01*
X854286Y-395880D01*
X854798Y-394856D01*
X855181Y-393492D01*
X855309Y-391956D01*
X855181Y-390421D01*
X854798Y-389056D01*
X854286Y-388032D01*
X853518Y-387179D01*
X852494Y-386838D01*
G01X849129Y-399239D02*
X797278D01*
G01X800034D02*
X849129D01*
G01X794522Y-418675D02*
Y-395302D01*
G01X800034Y-420682D02*
Y-395302D01*
G01Y-424619D02*
Y-426906D01*
G01X798066Y-423902D02*
Y-427622D01*
G01X800034Y-426906D02*
X794522Y-428912D01*
G01Y-422612D02*
X800034Y-424619D01*
G01X784580Y-214280D02*
X783557Y-213512D01*
X783045Y-212616D01*
X782874Y-211593D01*
X783215Y-210313D01*
X784068Y-209417D01*
X785092Y-209162D01*
X786116Y-209289D01*
X786968Y-209801D01*
X788674Y-212360D01*
X789869Y-213512D01*
X791575Y-214280D01*
X793110Y-214535D01*
Y-209162D01*
G01X782874Y-201613D02*
X783215Y-202636D01*
X784068Y-203404D01*
X785092Y-203916D01*
X786457Y-204299D01*
X787992Y-204427D01*
X789528Y-204299D01*
X790892Y-203916D01*
X791916Y-203404D01*
X792769Y-202636D01*
X793110Y-201613D01*
X792769Y-200589D01*
X791916Y-199821D01*
X790892Y-199309D01*
X789528Y-198926D01*
X787992Y-198798D01*
X786457Y-198926D01*
X785092Y-199309D01*
X784068Y-199821D01*
X783215Y-200589D01*
X782874Y-201613D01*
G01X784580Y-193808D02*
X783557Y-193040D01*
X783045Y-192144D01*
X782874Y-191121D01*
X783215Y-189841D01*
X784068Y-188945D01*
X785092Y-188690D01*
X786116Y-188817D01*
X786968Y-189329D01*
X788674Y-191888D01*
X789869Y-193040D01*
X791575Y-193808D01*
X793110Y-194063D01*
Y-188690D01*
G01X793451Y-181141D02*
X793281Y-181396D01*
X792939D01*
X792769Y-181141D01*
X792939Y-180885D01*
X793281D01*
X793451Y-181141D01*
G01X782874Y-170905D02*
X783215Y-171928D01*
X784068Y-172696D01*
X785092Y-173208D01*
X786457Y-173591D01*
X787992Y-173719D01*
X789528Y-173591D01*
X790892Y-173208D01*
X791916Y-172696D01*
X792769Y-171928D01*
X793110Y-170905D01*
X792769Y-169881D01*
X791916Y-169113D01*
X790892Y-168601D01*
X789528Y-168218D01*
X787992Y-168090D01*
X786457Y-168218D01*
X785092Y-168601D01*
X784068Y-169113D01*
X783215Y-169881D01*
X782874Y-170905D01*
G01Y-160669D02*
X783215Y-161692D01*
X784068Y-162460D01*
X785092Y-162972D01*
X786457Y-163355D01*
X787992Y-163483D01*
X789528Y-163355D01*
X790892Y-162972D01*
X791916Y-162460D01*
X792769Y-161692D01*
X793110Y-160669D01*
X792769Y-159645D01*
X791916Y-158877D01*
X790892Y-158365D01*
X789528Y-157982D01*
X787992Y-157854D01*
X786457Y-157982D01*
X785092Y-158365D01*
X784068Y-158877D01*
X783215Y-159645D01*
X782874Y-160669D01*
G01X795275Y-35433D02*
Y-152499D01*
G01X848184Y-13582D02*
Y-3346D01*
X843450Y-10682D01*
X849847D01*
G01X856884Y-13923D02*
X856629Y-13753D01*
Y-13411D01*
X856884Y-13241D01*
X857140Y-13411D01*
Y-13753D01*
X856884Y-13923D01*
G01X867120Y-3346D02*
X866097Y-3687D01*
X865329Y-4540D01*
X864817Y-5564D01*
X864434Y-6929D01*
X864306Y-8464D01*
X864434Y-10000D01*
X864817Y-11364D01*
X865329Y-12388D01*
X866097Y-13241D01*
X867120Y-13582D01*
X868144Y-13241D01*
X868912Y-12388D01*
X869424Y-11364D01*
X869807Y-10000D01*
X869935Y-8464D01*
X869807Y-6929D01*
X869424Y-5564D01*
X868912Y-4540D01*
X868144Y-3687D01*
X867120Y-3346D01*
G01X877356D02*
X876333Y-3687D01*
X875565Y-4540D01*
X875053Y-5564D01*
X874670Y-6929D01*
X874542Y-8464D01*
X874670Y-10000D01*
X875053Y-11364D01*
X875565Y-12388D01*
X876333Y-13241D01*
X877356Y-13582D01*
X878380Y-13241D01*
X879148Y-12388D01*
X879660Y-11364D01*
X880043Y-10000D01*
X880171Y-8464D01*
X880043Y-6929D01*
X879660Y-5564D01*
X879148Y-4540D01*
X878380Y-3687D01*
X877356Y-3346D01*
G01X791338Y-35433D02*
G03X795275Y-31496I0J3937D01*
G01D02*
Y316339D01*
G01D02*
G03X791338Y320276I-3937J0D01*
G01X795275Y370276D02*
Y330118D01*
G01X789764Y332087D02*
Y329331D01*
G01Y336024D02*
Y333268D01*
G01Y339961D02*
Y337205D01*
G01Y343898D02*
Y341142D01*
G01Y372244D02*
Y328150D01*
G01X795275Y330118D02*
X793307Y328150D01*
G01X795275Y658071D02*
Y381693D01*
G01X789764Y347835D02*
Y345079D01*
G01Y351772D02*
Y349016D01*
G01Y355709D02*
Y352953D01*
G01Y359646D02*
Y356890D01*
G01Y363583D02*
Y360827D01*
G01Y371457D02*
Y368701D01*
G01Y367520D02*
Y364764D01*
G01Y383268D02*
Y380512D01*
G01Y387205D02*
Y384449D01*
G01Y395079D02*
Y392323D01*
G01Y391142D02*
Y388386D01*
G01Y399016D02*
Y396260D01*
G01Y402953D02*
Y400197D01*
G01Y406890D02*
Y404134D01*
G01Y410827D02*
Y408071D01*
G01Y414764D02*
Y412008D01*
G01Y660040D02*
Y379725D01*
G01X795275Y381693D02*
X793307Y379725D01*
G01X795275Y370276D02*
X793307Y372244D01*
G01X789764Y422638D02*
Y419882D01*
G01Y418701D02*
Y415945D01*
G01Y426575D02*
Y423819D01*
G01Y430512D02*
Y427756D01*
G01Y434449D02*
Y431693D01*
G01Y438386D02*
Y435630D01*
G01Y446260D02*
Y443504D01*
G01Y442323D02*
Y439567D01*
G01Y450197D02*
Y447441D01*
G01Y454134D02*
Y451378D01*
G01Y458071D02*
Y455315D01*
G01Y462008D02*
Y459252D01*
G01Y469882D02*
Y467126D01*
G01Y465945D02*
Y463189D01*
G01Y473819D02*
Y471063D01*
G01Y477756D02*
Y475000D01*
G01Y481693D02*
Y478937D01*
G01Y485630D02*
Y482874D01*
G01Y489567D02*
Y486811D01*
G01Y497441D02*
Y494685D01*
G01Y493504D02*
Y490748D01*
G01Y501378D02*
Y498622D01*
G01Y505315D02*
Y502559D01*
G01Y509252D02*
Y506496D01*
G01Y513189D02*
Y510433D01*
G01Y521063D02*
Y518307D01*
G01Y517126D02*
Y514370D01*
G01Y525000D02*
Y522244D01*
G01Y528937D02*
Y526181D01*
G01Y532874D02*
Y530118D01*
G01Y536811D02*
Y534055D01*
G01Y544685D02*
Y541929D01*
G01Y540748D02*
Y537992D01*
G01Y548622D02*
Y545866D01*
G01Y552559D02*
Y549803D01*
G01Y556496D02*
Y553740D01*
G01Y560433D02*
Y557677D01*
G01Y568307D02*
Y565552D01*
G01Y564370D02*
Y561615D01*
G01Y572244D02*
Y569489D01*
G01Y576181D02*
Y573426D01*
G01Y580118D02*
Y577363D01*
G01Y584055D02*
Y581300D01*
G01Y587992D02*
Y585237D01*
G01Y595866D02*
Y593111D01*
G01Y591929D02*
Y589174D01*
G01Y599803D02*
Y597048D01*
G01Y603740D02*
Y600985D01*
G01Y607677D02*
Y604922D01*
G01Y611615D02*
Y608859D01*
G01Y619489D02*
Y616733D01*
G01Y615552D02*
Y612796D01*
G01Y623426D02*
Y620670D01*
G01Y627363D02*
Y624607D01*
G01Y631300D02*
Y628544D01*
G01Y635237D02*
Y632481D01*
G01Y643111D02*
Y640355D01*
G01Y639174D02*
Y636418D01*
G01Y647048D02*
Y644292D01*
G01Y650985D02*
Y648229D01*
G01Y658859D02*
Y656103D01*
G01X785827Y654922D02*
Y652166D01*
G01X795275Y658071D02*
X793307Y660040D01*
G01X795275Y779725D02*
Y739567D01*
G01X789764Y741536D02*
Y738780D01*
G01Y745473D02*
Y742717D01*
G01Y749410D02*
Y746654D01*
G01Y753347D02*
Y750591D01*
G01Y757284D02*
Y754528D01*
G01Y761221D02*
Y758465D01*
G01Y769095D02*
Y766339D01*
G01Y765158D02*
Y762402D01*
G01Y781693D02*
Y737599D01*
G01X795275Y739567D02*
X793307Y737599D01*
G01X791338Y825394D02*
G03X795275Y829331I0J3937D01*
G01D02*
Y956693D01*
G01Y815552D02*
Y791142D01*
G01Y815552D02*
X793307Y817520D01*
G01X795275Y779725D02*
X793307Y781693D01*
G01X789764Y773032D02*
Y770276D01*
G01Y776969D02*
Y774213D01*
G01Y780906D02*
Y778150D01*
G01Y792717D02*
Y789961D01*
G01Y796654D02*
Y793898D01*
G01Y800591D02*
Y797835D01*
G01Y804528D02*
Y801772D01*
G01Y808465D02*
Y805709D01*
G01Y816339D02*
Y813583D01*
G01Y817520D02*
Y789174D01*
G01X785827Y812402D02*
Y809646D01*
G01X795275Y791142D02*
X793307Y789174D01*
G01X814206Y979071D02*
X807558Y986854D01*
X809991Y988932D01*
X811101Y989207D01*
X812031Y989104D01*
X813112Y988232D01*
X813804Y987028D01*
X813774Y985881D01*
X813425Y984910D01*
X810993Y982833D01*
G01X813425Y984910D02*
X818098Y982395D01*
G01X844217Y951641D02*
X844985Y952664D01*
X845881Y953176D01*
X846904Y953347D01*
X848184Y953006D01*
X849080Y952153D01*
X849335Y951129D01*
X849208Y950105D01*
X848696Y949253D01*
X846137Y947547D01*
X844985Y946352D01*
X844217Y944646D01*
X843962Y943111D01*
X849335D01*
G01X854070Y945158D02*
X854837Y943964D01*
X855861Y943282D01*
X857013Y943111D01*
X858036Y943282D01*
X859060Y944134D01*
X859699Y945158D01*
X859827Y946182D01*
X859571Y947376D01*
X858676Y948229D01*
X857780Y948570D01*
X856629D01*
G01X857780D02*
X858548Y949082D01*
X859188Y949935D01*
X859444Y950958D01*
X859188Y951982D01*
X858548Y952835D01*
X857396Y953347D01*
X856245Y953176D01*
X855093Y952494D01*
G01X864945Y944305D02*
X865841Y943452D01*
X866865Y943111D01*
X867888Y943452D01*
X868784Y944476D01*
X869424Y946011D01*
X869680Y947547D01*
Y949423D01*
X869424Y950958D01*
X868784Y952323D01*
X868016Y953006D01*
X867120Y953347D01*
X866097Y953006D01*
X865329Y952323D01*
X864817Y951300D01*
X864561Y949935D01*
X864817Y948741D01*
X865457Y947547D01*
X866225Y946864D01*
X867120Y946693D01*
X868144Y947035D01*
X868912Y947888D01*
X869680Y949423D01*
G01X877356Y942770D02*
X877101Y942940D01*
Y943282D01*
X877356Y943452D01*
X877612Y943282D01*
Y942940D01*
X877356Y942770D01*
G01X887592Y953347D02*
X886569Y953006D01*
X885801Y952153D01*
X885289Y951129D01*
X884906Y949764D01*
X884778Y948229D01*
X884906Y946693D01*
X885289Y945329D01*
X885801Y944305D01*
X886569Y943452D01*
X887592Y943111D01*
X888616Y943452D01*
X889384Y944305D01*
X889896Y945329D01*
X890279Y946693D01*
X890407Y948229D01*
X890279Y949764D01*
X889896Y951129D01*
X889384Y952153D01*
X888616Y953006D01*
X887592Y953347D01*
G01X897828D02*
X896805Y953006D01*
X896037Y952153D01*
X895525Y951129D01*
X895142Y949764D01*
X895014Y948229D01*
X895142Y946693D01*
X895525Y945329D01*
X896037Y944305D01*
X896805Y943452D01*
X897828Y943111D01*
X898852Y943452D01*
X899620Y944305D01*
X900132Y945329D01*
X900515Y946693D01*
X900643Y948229D01*
X900515Y949764D01*
X900132Y951129D01*
X899620Y952153D01*
X898852Y953006D01*
X897828Y953347D01*
G01X794332Y959250D02*
X844277Y1001907D01*
G01X795275Y956693D02*
G03X791338Y960630I-3937J0D01*
G01X822079Y985796D02*
X815431Y993579D01*
X815593Y991026D01*
G01X820911Y984799D02*
X823246Y986793D01*
G01X830084Y992184D02*
X829779Y992148D01*
X829557Y992407D01*
X829641Y992703D01*
X829947Y992740D01*
X830168Y992480D01*
X830084Y992184D01*
G01X830999Y1006875D02*
X830442Y1005951D01*
X830413Y1004804D01*
X830688Y1003693D01*
X831283Y1002406D01*
X832183Y1001155D01*
X833277Y1000071D01*
X834455Y999282D01*
X835509Y998836D01*
X836647Y998686D01*
X837647Y999092D01*
X838204Y1000016D01*
X838234Y1001163D01*
X837958Y1002274D01*
X837363Y1003561D01*
X836463Y1004812D01*
X835369Y1005896D01*
X834191Y1006685D01*
X833137Y1007131D01*
X831999Y1007281D01*
X830999Y1006875D01*
G01X838783Y1013523D02*
X838226Y1012599D01*
X838197Y1011452D01*
X838472Y1010341D01*
X839067Y1009054D01*
X839967Y1007803D01*
X841061Y1006719D01*
X842239Y1005930D01*
X843293Y1005484D01*
X844431Y1005334D01*
X845431Y1005740D01*
X845988Y1006664D01*
X846018Y1007811D01*
X845742Y1008922D01*
X845147Y1010209D01*
X844247Y1011460D01*
X843153Y1012544D01*
X841975Y1013333D01*
X840921Y1013779D01*
X839783Y1013929D01*
X838783Y1013523D01*
G01X887436Y-468875D02*
X888715Y-465463D01*
X889995D01*
X892554Y-472287D01*
X893834D01*
X895113Y-468875D01*
G01X865457Y-463757D02*
X866225Y-462734D01*
X867121Y-462222D01*
X868144Y-462051D01*
X869424Y-462392D01*
X870320Y-463245D01*
X870575Y-464269D01*
X870448Y-465293D01*
X869936Y-466145D01*
X867377Y-467851D01*
X866225Y-469046D01*
X865457Y-470752D01*
X865202Y-472287D01*
X870575D01*
G01X878124Y-472628D02*
X877869Y-472458D01*
Y-472116D01*
X878124Y-471946D01*
X878380Y-472116D01*
Y-472458D01*
X878124Y-472628D01*
G01X888360Y-462051D02*
X887337Y-462392D01*
X886569Y-463245D01*
X886057Y-464269D01*
X885674Y-465634D01*
X885546Y-467169D01*
X885674Y-468705D01*
X886057Y-470069D01*
X886569Y-471093D01*
X887337Y-471946D01*
X888360Y-472287D01*
X889384Y-471946D01*
X890152Y-471093D01*
X890664Y-470069D01*
X891047Y-468705D01*
X891175Y-467169D01*
X891047Y-465634D01*
X890664Y-464269D01*
X890152Y-463245D01*
X889384Y-462392D01*
X888360Y-462051D01*
G01X857784Y-465463D02*
X856504Y-463331D01*
Y-462051D01*
X857464D01*
Y-463331D01*
X856504D01*
M02*
